G04 ================== begin FILE IDENTIFICATION RECORD ==================*
G04 Layout Name:  15126-1b.brd*
G04 Film Name:    L12*
G04 File Format:  Gerber RS274X*
G04 File Origin:  Cadence Allegro 16.6-2015-S079*
G04 Origin Date:  Fri Feb 10 17:23:11 2017*
G04 *
G04 Layer:  VIA CLASS/L12*
G04 Layer:  PIN/L12*
G04 Layer:  ETCH/L12*
G04 Layer:  DRAWING FORMAT/LAYER_PCB_STORY*
G04 Layer:  DRAWING FORMAT/LAYER_L12*
G04 *
G04 Offset:    (0.00 0.00)*
G04 Mirror:    No*
G04 Mode:      Positive*
G04 Rotation:  0*
G04 FullContactRelief:  No*
G04 UndefLineWidth:     6.00*
G04 ================== end FILE IDENTIFICATION RECORD ====================*
%FSLAX35Y35*MOIN*%
%IR0*IPPOS*OFA0.00000B0.00000*MIA0B0*SFA1.00000B1.00000*%
%ADD12C,.02*%
%ADD10C,.022*%
%ADD11C,.032*%
%ADD17C,.06*%
%ADD14C,.034*%
%ADD16C,.044*%
%ADD24C,.045*%
%ADD21C,.018*%
%ADD23C,.064*%
%ADD22C,.019*%
%ADD20C,.028*%
%ADD13C,.046*%
%ADD19C,.039*%
%ADD18C,.057*%
%ADD15C,.14*%
%ADD25C,.01*%
%ADD26C,.04*%
%ADD27C,.015*%
%ADD28C,.016*%
%ADD29C,.004*%
%ADD30C,.006*%
%ADD31C,.005*%
%ADD32C,.00402*%
%ADD33C,.0061*%
%ADD34C,.0035*%
%ADD35C,.00351*%
%ADD36C,.0045*%
%ADD37C,.00352*%
%ADD38C,.0056*%
%ADD39C,.00399*%
%ADD51C,.03004*%
%ADD46C,.04004*%
%ADD44C,.03204*%
%ADD47C,.06004*%
%ADD50C,.06204*%
%ADD43C,.02804*%
%ADD45C,.03804*%
%ADD41C,.05604*%
%ADD49C,.12104*%
%ADD42C,.11204*%
%ADD40C,.11404*%
%ADD48C,.17804*%
G75*
%LPD*%
G75*
G36*
G01X1973300Y-60000D02*
X-19810D01*
Y-34500D01*
X1973300D01*
Y-60000D01*
G37*
G36*
G01X42194Y169700D02*
X41015Y170878D01*
X21681D01*
G02X21506Y171638I0J400D01*
G03X14950I-3278J6748D01*
G02X14775Y170878I-175J-360D01*
G01X1484D01*
G02X1309Y171638I0J400D01*
G03X-5247I-3278J6748D01*
G02X-5422Y170878I-175J-360D01*
G01X-10590D01*
X-17000Y177289D01*
Y246417D01*
G03Y248383I-1000J983D01*
G01Y261717D01*
G03Y263683I-1000J983D01*
G01Y334481D01*
X-8781Y342700D01*
X6000D01*
X8800Y339900D01*
Y271113D01*
X2000Y264313D01*
Y234800D01*
X7000Y229800D01*
Y195800D01*
X11100Y191700D01*
X47200D01*
X49600Y189300D01*
Y184578D01*
G02X48952Y184265I-400J0D01*
G03X47512Y171611I-4661J-5879D01*
G02X47967Y170967I172J-361D01*
G01X46700Y169700D01*
X42194D01*
G37*
G36*
G01X-16133Y503697D02*
G03I-565J0D01*
G37*
G36*
G01X-20621Y661811D02*
G02X-19685Y662747I936J0D01*
G01X1972600D01*
Y637600D01*
X-20412D01*
G02X-20621Y638189I726J589D01*
G01Y661811D01*
G37*
G36*
G01X-9400Y22300D02*
X-12450Y25350D01*
Y61962D01*
X-15651Y65163D01*
Y71149D01*
X-13534Y73266D01*
X-7234D01*
X1500Y82000D01*
X14800D01*
X19800Y77000D01*
Y60100D01*
X21200Y58700D01*
Y57475D01*
G03Y55325I900J-1075D01*
G01Y48500D01*
X19900Y47200D01*
Y29688D01*
X18636Y28424D01*
X11433D01*
G03X5887I-2773J-1150D01*
G01X5542D01*
X5483Y28518D01*
G03X3538Y29874I-2550J-1584D01*
G03X-650Y27774I-2936J628D01*
G02X-535Y27127I-167J-363D01*
G01X-5362Y22300D01*
X-9400D01*
G37*
G36*
G01X12100Y198300D02*
Y232900D01*
X9100Y235900D01*
Y264300D01*
X13900Y269100D01*
Y336999D01*
X16178Y339278D01*
X38762D01*
X39735Y338305D01*
Y287600D01*
X29800Y277665D01*
Y262600D01*
X39735Y252665D01*
Y199523D01*
X37212Y197000D01*
X13400D01*
X12100Y198300D01*
G37*
G36*
G01X32520Y493700D02*
X25974Y500246D01*
X25982Y500338D01*
G03X22211Y504109I-3491J280D01*
G01X22119Y504101D01*
X16632Y509588D01*
Y523718D01*
X5173Y535177D01*
X-644D01*
X-3067Y537600D01*
X-3200D01*
X-4000Y538400D01*
Y545500D01*
X-6173Y547673D01*
Y560383D01*
X-4357Y562198D01*
X3839D01*
X5506Y563866D01*
X5608Y563848D01*
G03X4900Y570552I592J3452D01*
G03X4546Y570672I-1300J-3252D01*
G01X4400Y570713D01*
Y578313D01*
X3500Y579213D01*
X3493Y579285D01*
G03X1685Y581093I-1993J-185D01*
G01X1613Y581100D01*
X1535Y581178D01*
X-3105D01*
X-6782Y584855D01*
Y594181D01*
X-5932Y595031D01*
X-5469D01*
X-5453Y595047D01*
X316D01*
X2533Y592830D01*
X17888D01*
X18369Y593310D01*
X20332D01*
X21503Y594482D01*
X23397D01*
X23962Y595047D01*
X41305D01*
X41332Y594879D01*
G03X44573Y593854I1878J301D01*
G02X45145Y593855I286J-279D01*
G03X48377Y594880I1355J1335D01*
G01X48404Y595047D01*
X60127D01*
X60172Y594909D01*
G03X63949Y592527I3328J1091D01*
G02X64400Y592130I51J-397D01*
G01Y565370D01*
G02X63949Y564973I-400J0D01*
G03X60625Y559500I-449J-3473D01*
G03X60336Y556000I2875J-1999D01*
G03X63949Y551027I3164J-1500D01*
G02X64400Y550630I51J-397D01*
G01Y538825D01*
G03X64000Y538664I1105J-3323D01*
G03Y532336I-1500J-3164D01*
G03X64400Y532175I1505J3162D01*
G01Y528204D01*
G03X62610Y527137I-20J-2002D01*
G02X61881Y527187I-353J187D01*
G03X61770Y525565I-1881J-686D01*
G02X62499Y525515I353J-187D01*
G03X62856Y524904I1880J689D01*
G03X62395Y523868I1524J-1299D01*
G02X61782Y523584I-397J52D01*
G03X62031Y520404I-1082J-1684D01*
G02X62664Y520263I266J-299D01*
G03X63064Y519662I1839J791D01*
G02X63073Y519394I-144J-139D01*
G03X63036Y516850I1527J-1294D01*
G03X63315Y514065I1564J-1250D01*
G01Y497478D01*
X63207Y497370D01*
X56498D01*
X55365Y496237D01*
Y494089D01*
X54976Y493700D01*
X50051D01*
G03X45549I-2251J-6100D01*
G01X32520D01*
G37*
G36*
G01X53000Y223300D02*
X51800Y224500D01*
Y258900D01*
X59984Y267084D01*
X72912D01*
X74529Y265467D01*
Y265408D01*
X74988Y264949D01*
Y224634D01*
X73654Y223300D01*
X53000D01*
G37*
G36*
G01X122168Y201920D02*
X109023Y215065D01*
X109640Y215682D01*
Y279124D01*
G02X110071Y279522I400J0D01*
G03Y282318I109J1398D01*
G02X109640Y282716I-31J398D01*
G01Y286968D01*
X104082Y292525D01*
Y293044D01*
X104160Y293104D01*
G03X104082Y297910I-1838J2374D01*
G01Y300691D01*
X106557Y303166D01*
Y309716D01*
X104661Y311612D01*
X100643D01*
X99391Y312864D01*
Y322810D01*
X103837Y327256D01*
X103892Y327269D01*
G03X105236Y332396I-692J2921D01*
G02Y332984I271J294D01*
G03X104200Y338021I-2036J2206D01*
G01Y344395D01*
G03X104645Y347468I-2320J1905D01*
G03X104706Y350341I-2605J1492D01*
G03X104702Y353184I-2646J1418D01*
G03X104200Y356982I-2542J1596D01*
G01Y358385D01*
G03X104352Y361618I-2450J1735D01*
G03X104200Y364913I-2582J1532D01*
G01Y366292D01*
G03X104548Y369826I-2235J2004D01*
G03X104200Y372936I-2720J1270D01*
G01Y384446D01*
X97438Y391208D01*
Y397791D01*
G02X97900Y398186I400J0D01*
G03Y401352I249J1583D01*
G02X97438Y401747I-62J395D01*
G01Y416138D01*
X98320Y417020D01*
X110366D01*
X112506Y414880D01*
Y411527D01*
G02X111789Y411284I-400J1D01*
G03X111122Y411791I-1269J-978D01*
G02X111058Y412500I150J371D01*
G03X109596Y412368I-859J1352D01*
G02X109660Y411659I-150J-371D01*
G03X109679Y408943I859J-1352D01*
G02X109687Y408267I-210J-341D01*
G03X109182Y407686I765J-1175D01*
G02X108570Y407543I-362J170D01*
G03X109073Y405734I-999J-1252D01*
G02X109671Y405928I375J-138D01*
G03X111265Y408234I781J1164D01*
G02X111302Y408909I232J326D01*
G03X111789Y409330I-783J1398D01*
G02X112506Y409087I317J-244D01*
G01Y404687D01*
X118175Y399018D01*
X126982D01*
X133570Y392430D01*
Y205990D01*
X129500Y201920D01*
X122168D01*
G37*
G36*
G01X136150Y353450D02*
Y365248D01*
X137100Y366198D01*
X169400D01*
X170100Y365498D01*
Y210458D01*
X166342Y206700D01*
X163342D01*
X162121Y205479D01*
X156079D01*
X153821Y203221D01*
X138486D01*
X136200Y205507D01*
Y353400D01*
X136150Y353450D01*
G37*
G36*
G01X136948Y368202D02*
X136150Y369000D01*
Y392650D01*
X131300Y397500D01*
Y403500D01*
X131800Y404000D01*
X144044D01*
X144116Y403928D01*
Y400220D01*
X170100Y374236D01*
Y369100D01*
X169202Y368202D01*
X136948D01*
G37*
G36*
G01X172958Y206542D02*
X171892Y207608D01*
Y362892D01*
X172900Y363900D01*
X190450D01*
X192094Y362256D01*
G02X191831Y361573I-282J-283D01*
G03X192922Y359213I69J-1400D01*
G02X193499Y359219I291J-274D01*
G03X195580Y359306I1001J981D01*
G02X196165Y359339I308J-255D01*
G03X198516Y360603I972J1011D01*
G02X198909Y361076I393J73D01*
G01X206940D01*
X240493Y327522D01*
X253054D01*
X264138Y316438D01*
G03X264172Y316406I755J768D01*
G01X265754Y314824D01*
X268746D01*
X270687Y316764D01*
X270942D01*
X271294Y316739D01*
G02X271525Y316502I-356J-578D01*
G03X273281Y314985I3094J1807D01*
G03X273683Y314908I400J999D01*
G01X274652D01*
G02X275052Y314659I-33J-499D01*
G03X277875Y312959I2948J1701D01*
G03X277914Y312958I47J1076D01*
G01X278024D01*
G02X278431Y312709I-25J-498D01*
G03X281277Y311008I2947J1700D01*
G01X281412D01*
G02X281812Y310759I-33J-499D01*
G03X283362Y309357I2947J1701D01*
G02X283464Y309098I-83J-182D01*
G03X285873Y307709I1295J-538D01*
G02X286149Y307749I159J-122D01*
G03X288037Y307108I1990J2760D01*
G01X288172D01*
G02X288572Y306859I-33J-499D01*
G03X291395Y305159I2948J1701D01*
G03X291434Y305158I47J1076D01*
G01X291604D01*
G03X291643Y305159I-8J1077D01*
G03X294466Y306859I-125J3401D01*
G02X294866Y307108I433J-250D01*
G01X294932D01*
G02X295332Y306859I-33J-499D01*
G03X298155Y305159I2948J1701D01*
G03X298194Y305158I47J1076D01*
G01X298364D01*
G03X298403Y305159I-8J1077D01*
G03X301226Y306859I-125J3401D01*
G02X301626Y307108I433J-250D01*
G01X301729D01*
X301761D01*
G03X303649Y307749I-102J3401D01*
G02X303925Y307709I117J-162D01*
G03X306334Y309098I1114J851D01*
G02X306436Y309357I185J77D01*
G03X307989Y310762I-1396J3104D01*
G01X307995Y310774D01*
G02X308418Y311008I423J-265D01*
G01X308488D01*
X308520D01*
G03X311366Y312709I-101J3401D01*
G02X311773Y312958I432J-249D01*
G01X311883D01*
G03X311922Y312959I-8J1077D01*
G03X313610Y313480I-125J3401D01*
G01X313673Y313519D01*
X314156Y313447D01*
X314202Y313402D01*
G03X315819Y313162I976J1007D01*
G01X315877Y313192D01*
X316090Y313160D01*
X349600Y332500D01*
X361252Y339300D01*
X373197Y345973D01*
X374215D01*
G02X374615Y345581I0J-400D01*
G03X377419I1402J28D01*
G02X377819Y345973I400J-8D01*
G01X378237D01*
X388560Y335650D01*
X423060D01*
X423082Y335672D01*
X430768D01*
X432283Y337187D01*
Y340991D01*
X433252Y341960D01*
X444540D01*
X445960Y340540D01*
Y340040D01*
X448016Y337984D01*
G02X447748Y337301I-282J-283D01*
G03X448830Y334949I52J-1401D01*
G02X449473Y334871I293J-272D01*
G03X451558Y334442I1226J679D01*
G01X457690Y328310D01*
Y282587D01*
X456160Y281058D01*
Y277681D01*
X457050Y276792D01*
X457028Y276686D01*
G03X457690Y275191I1372J-286D01*
G01Y270174D01*
G03X457391Y269777I953J-1029D01*
G01X457377Y269749D01*
X456463Y268835D01*
X456700Y268598D01*
Y265900D01*
X436717Y254000D01*
X434200D01*
X433100Y255100D01*
Y255884D01*
X435102Y257885D01*
Y258202D01*
X435200Y258300D01*
Y267200D01*
X433800Y268600D01*
X427500D01*
X426560Y267660D01*
X389480D01*
X374771Y252951D01*
X372446D01*
X354780Y262700D01*
X347100Y267100D01*
X347000Y267200D01*
X344020D01*
G02X343620Y267602I0J400D01*
G03X340816I-1402J7D01*
G02X340416Y267200I-400J-2D01*
G01X337260D01*
G02X336860Y267602I0J400D01*
G03X334056I-1402J7D01*
G02X333656Y267200I-400J-2D01*
G01X330500D01*
G02X330100Y267602I0J400D01*
G03X327296I-1402J7D01*
G02X326896Y267200I-400J-2D01*
G01X323740D01*
G02X323340Y267602I0J400D01*
G03X320536I-1402J7D01*
G02X320136Y267200I-400J-2D01*
G01X316980D01*
G02X316580Y267602I0J400D01*
G03X313776I-1402J7D01*
G02X313376Y267200I-400J-2D01*
G01X310220D01*
G02X309820Y267602I0J400D01*
G03X307524Y268689I-1402J7D01*
G02X306986Y268714I-255J308D01*
G01X306417Y269283D01*
X306429Y269381D01*
G03X304860Y270950I-1390J179D01*
G01X304762Y270938D01*
X302100Y273600D01*
X299683D01*
X299649Y273758D01*
G03X296909I-1370J-298D01*
G01X296875Y273600D01*
X292923D01*
X292889Y273758D01*
G03X290149I-1370J-298D01*
G01X290115Y273600D01*
X286600D01*
X286351Y273351D01*
X286160Y273543D01*
X286153Y273613D01*
G03X284313Y272131I-1394J-153D01*
G02X284469Y271469I-127J-379D01*
G01X281912Y268912D01*
X281796Y268948D01*
G03X280336Y268546I-417J-1339D01*
G01X279693D01*
G02X279317Y269082I0J400D01*
G03X276681I-1318J478D01*
G02X276305Y268546I-376J-136D01*
G01X275662D01*
G03X273576I-1043J-937D01*
G01X272933D01*
G02X272557Y269082I0J400D01*
G03X269921I-1318J478D01*
G02X269545Y268546I-376J-136D01*
G01X256053D01*
X255999Y268600D01*
X236500D01*
Y268442D01*
X174600Y206542D01*
X172958D01*
G37*
G36*
G01X267650Y214931D02*
X267360Y215715D01*
X267997Y216352D01*
X268781Y216062D01*
X268905Y215938D01*
X267774Y214807D01*
X267650Y214931D01*
G37*
G36*
G01X270450Y217731D02*
X270160Y218515D01*
X270797Y219152D01*
X271581Y218862D01*
X271705Y218738D01*
X270574Y217607D01*
X270450Y217731D01*
G37*
G36*
G01X264850Y212131D02*
X264560Y212915D01*
X265197Y213552D01*
X265981Y213262D01*
X266105Y213138D01*
X264974Y212007D01*
X264850Y212131D01*
G37*
G36*
G01X272358Y218085D02*
X272648Y217301D01*
X272011Y216664D01*
X271227Y216954D01*
X271103Y217078D01*
X272234Y218209D01*
X272358Y218085D01*
G37*
G36*
G01X269558Y215285D02*
X269848Y214501D01*
X269211Y213864D01*
X268427Y214154D01*
X268303Y214278D01*
X269434Y215409D01*
X269558Y215285D01*
G37*
G36*
G01X266800Y212528D02*
X267090Y211743D01*
X266454Y211106D01*
X265669Y211396D01*
X265545Y211520D01*
X266676Y212651D01*
X266800Y212528D01*
G37*
G36*
G01X265349Y216901D02*
X265059Y217685D01*
X265696Y218322D01*
X266480Y218032D01*
X266604Y217908D01*
X265473Y216777D01*
X265349Y216901D01*
G37*
G36*
G01X267258Y217254D02*
X267548Y216469D01*
X266912Y215833D01*
X266127Y216123D01*
X266003Y216246D01*
X267135Y217378D01*
X267258Y217254D01*
G37*
G36*
G01X279412Y214761D02*
X279380Y215516D01*
X280133Y215951D01*
X280771Y215546D01*
X280859Y215395D01*
X279499Y214609D01*
X279412Y214761D01*
G37*
G36*
G01X282798Y216715D02*
X282766Y217470D01*
X283519Y217905D01*
X284157Y217500D01*
X284245Y217348D01*
X282885Y216563D01*
X282798Y216715D01*
G37*
G36*
G01X275498Y210233D02*
X274828Y210582D01*
Y211452D01*
X275498Y211802D01*
X275673Y211803D01*
Y210232D01*
X275498Y210233D01*
G37*
G36*
G01X272652Y206962D02*
X272620Y207717D01*
X273373Y208152D01*
X274011Y207747D01*
X274099Y207596D01*
X272739Y206810D01*
X272652Y206962D01*
G37*
G36*
G01X276032Y212812D02*
X276000Y213567D01*
X276753Y214002D01*
X277391Y213597D01*
X277479Y213446D01*
X276119Y212660D01*
X276032Y212812D01*
G37*
G36*
G01X272118Y204383D02*
X271448Y204732D01*
Y205602D01*
X272118Y205952D01*
X272293Y205953D01*
Y204382D01*
X272118Y204383D01*
G37*
G36*
G01X286726Y217108D02*
X286758Y216353D01*
X286005Y215918D01*
X285367Y216323D01*
X285279Y216474D01*
X286639Y217260D01*
X286726Y217108D01*
G37*
G36*
G01X277120Y209936D02*
X277790Y209587D01*
Y208717D01*
X277120Y208367D01*
X276945Y208366D01*
Y209937D01*
X277120Y209936D01*
G37*
G36*
G01X279966Y213208D02*
X279998Y212453D01*
X279245Y212018D01*
X278607Y212423D01*
X278519Y212574D01*
X279879Y213360D01*
X279966Y213208D01*
G37*
G36*
G01X283340Y215154D02*
X283372Y214399D01*
X282619Y213964D01*
X281981Y214369D01*
X281893Y214520D01*
X283253Y215306D01*
X283340Y215154D01*
G37*
G36*
G01X276586Y207357D02*
X276618Y206602D01*
X275865Y206167D01*
X275227Y206572D01*
X275139Y206723D01*
X276499Y207509D01*
X276586Y207357D01*
G37*
G36*
G01X273741Y204045D02*
X274411Y203695D01*
Y202825D01*
X273741Y202475D01*
X273566D01*
Y204045D01*
X273741D01*
G37*
G36*
G01X289558Y205015D02*
X289526Y205770D01*
X290279Y206205D01*
X290917Y205800D01*
X291005Y205648D01*
X289645Y204863D01*
X289558Y205015D01*
G37*
G36*
G01X290400Y194479D02*
X289640Y194829D01*
Y195729D01*
X290400Y196079D01*
X290575D01*
Y194479D01*
X290400D01*
G37*
G36*
G01X289018Y202442D02*
X288348Y202793D01*
X288349Y203663D01*
X289019Y204012D01*
X289195D01*
X289193Y202441D01*
X289018Y202442D01*
G37*
G36*
G01Y198542D02*
X288348Y198893D01*
X288349Y199763D01*
X289019Y200112D01*
X289195D01*
X289193Y198541D01*
X289018Y198542D01*
G37*
G36*
G01X291500Y196079D02*
X292260Y195729D01*
Y194829D01*
X291500Y194479D01*
X291325D01*
Y196079D01*
X291500D01*
G37*
G36*
G01X290641Y202119D02*
X291311Y201769D01*
Y200899D01*
X290641Y200549D01*
X290466D01*
Y202119D01*
X290641D01*
G37*
G36*
G01X293486Y205408D02*
X293518Y204653D01*
X292765Y204218D01*
X292127Y204623D01*
X292039Y204774D01*
X293399Y205559D01*
X293486Y205408D01*
G37*
G36*
G01X276038Y216715D02*
X276006Y217470D01*
X276759Y217905D01*
X277397Y217500D01*
X277485Y217348D01*
X276125Y216563D01*
X276038Y216715D01*
G37*
G36*
G01X272039Y213543D02*
X271634Y214181D01*
X272069Y214934D01*
X272824Y214902D01*
X272975Y214815D01*
X272190Y213455D01*
X272039Y213543D01*
G37*
G36*
G01X269272Y208911D02*
X269240Y209666D01*
X269993Y210101D01*
X270631Y209696D01*
X270719Y209545D01*
X269359Y208759D01*
X269272Y208911D01*
G37*
G36*
G01X279966Y217108D02*
X279998Y216353D01*
X279245Y215918D01*
X278607Y216323D01*
X278519Y216474D01*
X279879Y217260D01*
X279966Y217108D01*
G37*
G36*
G01X276580Y215154D02*
X276612Y214399D01*
X275859Y213964D01*
X275221Y214369D01*
X275133Y214520D01*
X276493Y215306D01*
X276580Y215154D01*
G37*
G36*
G01X273200Y209305D02*
X273232Y208550D01*
X272479Y208115D01*
X271841Y208520D01*
X271753Y208671D01*
X273113Y209457D01*
X273200Y209305D01*
G37*
G36*
G01X273739Y211881D02*
X274409Y211531D01*
Y210661D01*
X273740Y210311D01*
X273565D01*
X273564Y211881D01*
X273739D01*
G37*
G36*
G01X286187Y206971D02*
X286155Y207726D01*
X286908Y208161D01*
X287546Y207756D01*
X287634Y207605D01*
X286274Y206819D01*
X286187Y206971D01*
G37*
G36*
G01X289567Y208920D02*
X289535Y209675D01*
X290288Y210110D01*
X290926Y209705D01*
X291014Y209554D01*
X289654Y208768D01*
X289567Y208920D01*
G37*
G36*
G01X285639Y204396D02*
X284969Y204745D01*
X284967Y205614D01*
X285636Y205965D01*
X285811Y205966D01*
X285814Y204396D01*
X285639D01*
G37*
G36*
G01X286161Y195444D02*
X285401Y195794D01*
Y196694D01*
X286161Y197044D01*
X286336D01*
Y195444D01*
X286161D01*
G37*
G36*
G01X285637Y200549D02*
X284967Y200899D01*
Y201769D01*
X285637Y202119D01*
X285812D01*
Y200549D01*
X285637D01*
G37*
G36*
G01X290106Y207357D02*
X290138Y206602D01*
X289385Y206167D01*
X288747Y206572D01*
X288659Y206723D01*
X290019Y207508D01*
X290106Y207357D01*
G37*
G36*
G01X293471Y209299D02*
X293503Y208544D01*
X292750Y208109D01*
X292112Y208514D01*
X292024Y208665D01*
X293384Y209450D01*
X293471Y209299D01*
G37*
G36*
G01X287260Y197044D02*
X288020Y196694D01*
Y195794D01*
X287260Y195444D01*
X287085D01*
Y197044D01*
X287260D01*
G37*
G36*
G01X287261Y204045D02*
X287931Y203695D01*
Y202825D01*
X287261Y202475D01*
X287086D01*
Y204045D01*
X287261D01*
G37*
G36*
G01X283340Y211254D02*
X283372Y210499D01*
X282619Y210064D01*
X281981Y210469D01*
X281893Y210620D01*
X283253Y211406D01*
X283340Y211254D01*
G37*
G36*
G01X280499Y207980D02*
X281169Y207630D01*
Y206760D01*
X280500Y206410D01*
X280325D01*
X280324Y207980D01*
X280499D01*
G37*
G36*
G01X290100Y215154D02*
X290132Y214399D01*
X289379Y213964D01*
X288741Y214369D01*
X288653Y214520D01*
X290013Y215306D01*
X290100Y215154D01*
G37*
G36*
G01X286726Y213208D02*
X286758Y212453D01*
X286005Y212018D01*
X285367Y212423D01*
X285279Y212574D01*
X286639Y213360D01*
X286726Y213208D01*
G37*
G36*
G01X293486Y217108D02*
X293518Y216353D01*
X292765Y215918D01*
X292127Y216323D01*
X292039Y216474D01*
X293399Y217260D01*
X293486Y217108D01*
G37*
G36*
G01X277120Y202120D02*
X277790Y201770D01*
Y200900D01*
X277120Y200550D01*
X276945D01*
Y202120D01*
X277120D01*
G37*
G36*
G01X279960Y205404D02*
X279992Y204649D01*
X279239Y204214D01*
X278601Y204619D01*
X278513Y204770D01*
X279873Y205556D01*
X279960Y205404D01*
G37*
G36*
G01X290100Y211254D02*
X290132Y210499D01*
X289379Y210064D01*
X288741Y210469D01*
X288653Y210620D01*
X290013Y211406D01*
X290100Y211254D01*
G37*
G36*
G01X286720Y209305D02*
X286752Y208550D01*
X285999Y208115D01*
X285361Y208520D01*
X285273Y208671D01*
X286633Y209457D01*
X286720Y209305D01*
G37*
G36*
G01X283881Y205970D02*
X284551Y205620D01*
Y204750D01*
X283881Y204400D01*
X283706D01*
Y205970D01*
X283881D01*
G37*
G36*
G01X293486Y213208D02*
X293518Y212453D01*
X292765Y212018D01*
X292127Y212423D01*
X292039Y212574D01*
X293399Y213360D01*
X293486Y213208D01*
G37*
G36*
G01X283881Y202119D02*
X284551Y201769D01*
Y200899D01*
X283881Y200549D01*
X283706D01*
Y202119D01*
X283881D01*
G37*
G36*
G01X286178Y214764D02*
X286146Y215519D01*
X286899Y215954D01*
X287537Y215549D01*
X287625Y215398D01*
X286265Y214612D01*
X286178Y214764D01*
G37*
G36*
G01X278879Y208296D02*
X278209Y208646D01*
Y209516D01*
X278878Y209866D01*
X279054D01*
Y208296D01*
X278879D01*
G37*
G36*
G01X279425Y210868D02*
X279393Y211623D01*
X280146Y212058D01*
X280784Y211653D01*
X280872Y211501D01*
X279512Y210716D01*
X279425Y210868D01*
G37*
G36*
G01X282805Y212819D02*
X282773Y213574D01*
X283526Y214009D01*
X284164Y213604D01*
X284252Y213452D01*
X282892Y212667D01*
X282805Y212819D01*
G37*
G36*
G01X289565Y216719D02*
X289533Y217474D01*
X290286Y217909D01*
X290924Y217504D01*
X291012Y217352D01*
X289652Y216567D01*
X289565Y216719D01*
G37*
G36*
G01X276045Y205019D02*
X276013Y205774D01*
X276766Y206209D01*
X277404Y205804D01*
X277492Y205652D01*
X276132Y204867D01*
X276045Y205019D01*
G37*
G36*
G01X274553Y198357D02*
X274148Y198995D01*
X274583Y199749D01*
X275337Y199717D01*
X275490Y199629D01*
X274704Y198270D01*
X274553Y198357D01*
G37*
G36*
G01X275499Y202447D02*
X274829Y202797D01*
Y203667D01*
X275498Y204017D01*
X275674D01*
Y202447D01*
X275499D01*
G37*
G36*
G01X282257Y206374D02*
X281588Y206724D01*
Y207594D01*
X282258Y207943D01*
X282432Y207944D01*
X282433Y206374D01*
X282257D01*
G37*
G36*
G01X282855Y208962D02*
X282834Y209716D01*
X283594Y210140D01*
X284225Y209725D01*
X284311Y209574D01*
X282940Y208808D01*
X282855Y208962D01*
G37*
G36*
G01X286172Y210861D02*
X286140Y211616D01*
X286893Y212051D01*
X287531Y211646D01*
X287619Y211495D01*
X286259Y210709D01*
X286172Y210861D01*
G37*
G36*
G01X289558Y212815D02*
X289526Y213570D01*
X290279Y214005D01*
X290917Y213600D01*
X291005Y213448D01*
X289645Y212663D01*
X289558Y212815D01*
G37*
G36*
G01X282257Y202475D02*
X281587Y202825D01*
Y203695D01*
X282257Y204045D01*
X282432D01*
Y202475D01*
X282257D01*
G37*
G36*
G01X286172Y265461D02*
X286140Y266216D01*
X286893Y266651D01*
X287531Y266246D01*
X287619Y266094D01*
X286259Y265310D01*
X286172Y265461D01*
G37*
G36*
G01X289558Y267415D02*
X289526Y268170D01*
X290279Y268605D01*
X290917Y268200D01*
X291005Y268048D01*
X289645Y267264D01*
X289558Y267415D01*
G37*
G36*
G01X292121Y268200D02*
X292759Y268605D01*
X293512Y268170D01*
X293480Y267415D01*
X293393Y267264D01*
X292033Y268048D01*
X292121Y268200D01*
G37*
G36*
G01X279412Y261561D02*
X279380Y262316D01*
X280133Y262751D01*
X280771Y262346D01*
X280859Y262194D01*
X279499Y261409D01*
X279412Y261561D01*
G37*
G36*
G01X282798Y263515D02*
X282766Y264270D01*
X283519Y264705D01*
X284157Y264300D01*
X284245Y264148D01*
X282885Y263364D01*
X282798Y263515D01*
G37*
G36*
G01X265081Y260400D02*
X265719Y260805D01*
X266472Y260370D01*
X266440Y259615D01*
X266353Y259463D01*
X264993Y260248D01*
X265081Y260400D01*
G37*
G36*
G01X269278Y259615D02*
X269246Y260370D01*
X269999Y260805D01*
X270637Y260400D01*
X270725Y260248D01*
X269365Y259463D01*
X269278Y259615D01*
G37*
G36*
G01X271841Y260400D02*
X272479Y260805D01*
X273232Y260370D01*
X273200Y259615D01*
X273113Y259463D01*
X271753Y260248D01*
X271841Y260400D01*
G37*
G36*
G01X276038Y259615D02*
X276006Y260370D01*
X276759Y260805D01*
X277397Y260400D01*
X277485Y260248D01*
X276125Y259463D01*
X276038Y259615D01*
G37*
G36*
G01X282798Y224515D02*
X282766Y225270D01*
X283519Y225705D01*
X284157Y225300D01*
X284245Y225148D01*
X282885Y224363D01*
X282798Y224515D01*
G37*
G36*
G01X286187Y226470D02*
X286155Y227225D01*
X286908Y227660D01*
X287546Y227255D01*
X287634Y227104D01*
X286274Y226318D01*
X286187Y226470D01*
G37*
G36*
G01X289552Y228412D02*
X289520Y229167D01*
X290273Y229602D01*
X290911Y229197D01*
X290999Y229046D01*
X289639Y228260D01*
X289552Y228412D01*
G37*
G36*
G01X279412Y222561D02*
X279380Y223316D01*
X280133Y223751D01*
X280771Y223346D01*
X280859Y223195D01*
X279499Y222409D01*
X279412Y222561D01*
G37*
G36*
G01X276038Y220615D02*
X276006Y221370D01*
X276759Y221805D01*
X277397Y221400D01*
X277485Y221248D01*
X276125Y220463D01*
X276038Y220615D01*
G37*
G36*
G01X290091Y226849D02*
X290123Y226094D01*
X289370Y225659D01*
X288732Y226064D01*
X288644Y226215D01*
X290004Y227000D01*
X290091Y226849D01*
G37*
G36*
G01X279966Y221008D02*
X279998Y220253D01*
X279245Y219818D01*
X278607Y220223D01*
X278519Y220374D01*
X279879Y221160D01*
X279966Y221008D01*
G37*
G36*
G01X276580Y219054D02*
X276612Y218299D01*
X275859Y217864D01*
X275221Y218269D01*
X275133Y218420D01*
X276493Y219206D01*
X276580Y219054D01*
G37*
G36*
G01X286726Y224908D02*
X286758Y224153D01*
X286005Y223718D01*
X285367Y224123D01*
X285279Y224274D01*
X286639Y225060D01*
X286726Y224908D01*
G37*
G36*
G01X283346Y222957D02*
X283378Y222202D01*
X282625Y221767D01*
X281987Y222172D01*
X281899Y222323D01*
X283259Y223109D01*
X283346Y222957D01*
G37*
G36*
G01X293480Y228804D02*
X293512Y228049D01*
X292759Y227614D01*
X292121Y228019D01*
X292033Y228170D01*
X293393Y228956D01*
X293480Y228804D01*
G37*
G36*
G01X279412Y242061D02*
X279380Y242816D01*
X280133Y243251D01*
X280771Y242846D01*
X280859Y242695D01*
X279499Y241909D01*
X279412Y242061D01*
G37*
G36*
G01X276038Y240115D02*
X276006Y240870D01*
X276759Y241305D01*
X277397Y240900D01*
X277485Y240748D01*
X276125Y239963D01*
X276038Y240115D01*
G37*
G36*
G01X271841Y240900D02*
X272479Y241305D01*
X273232Y240870D01*
X273200Y240115D01*
X273113Y239963D01*
X271753Y240748D01*
X271841Y240900D01*
G37*
G36*
G01X269278Y240115D02*
X269246Y240870D01*
X269999Y241305D01*
X270637Y240900D01*
X270725Y240748D01*
X269365Y239963D01*
X269278Y240115D01*
G37*
G36*
G01X286172Y245961D02*
X286140Y246716D01*
X286893Y247151D01*
X287531Y246746D01*
X287619Y246595D01*
X286259Y245809D01*
X286172Y245961D01*
G37*
G36*
G01X282798Y244015D02*
X282766Y244770D01*
X283519Y245205D01*
X284157Y244800D01*
X284245Y244648D01*
X282885Y243863D01*
X282798Y244015D01*
G37*
G36*
G01X289558Y247915D02*
X289526Y248670D01*
X290279Y249105D01*
X290917Y248700D01*
X291005Y248548D01*
X289645Y247763D01*
X289558Y247915D01*
G37*
G36*
G01X261590Y236264D02*
X261940Y237024D01*
X262840D01*
X263190Y236264D01*
Y236089D01*
X261590D01*
Y236264D01*
G37*
G36*
G01X279966Y240508D02*
X279998Y239753D01*
X279245Y239318D01*
X278607Y239723D01*
X278519Y239874D01*
X279879Y240660D01*
X279966Y240508D01*
G37*
G36*
G01X286726Y244408D02*
X286758Y243653D01*
X286005Y243218D01*
X285367Y243623D01*
X285279Y243774D01*
X286639Y244560D01*
X286726Y244408D01*
G37*
G36*
G01X283340Y242454D02*
X283372Y241699D01*
X282619Y241264D01*
X281981Y241669D01*
X281893Y241820D01*
X283253Y242606D01*
X283340Y242454D01*
G37*
G36*
G01X290100Y246354D02*
X290132Y245599D01*
X289379Y245164D01*
X288741Y245569D01*
X288653Y245720D01*
X290013Y246506D01*
X290100Y246354D01*
G37*
G36*
G01X263190Y235166D02*
X262840Y234406D01*
X261940D01*
X261590Y235166D01*
Y235341D01*
X263190D01*
Y235166D01*
G37*
G36*
G01X276580Y238554D02*
X276612Y237799D01*
X275859Y237364D01*
X275221Y237769D01*
X275133Y237920D01*
X276493Y238706D01*
X276580Y238554D01*
G37*
G36*
G01X274017Y237769D02*
X273379Y237364D01*
X272626Y237799D01*
X272658Y238554D01*
X272745Y238706D01*
X274105Y237920D01*
X274017Y237769D01*
G37*
G36*
G01X279427Y226470D02*
X279395Y227225D01*
X280148Y227660D01*
X280786Y227255D01*
X280874Y227104D01*
X279514Y226318D01*
X279427Y226470D01*
G37*
G36*
G01X276038Y224515D02*
X276006Y225270D01*
X276759Y225705D01*
X277397Y225300D01*
X277485Y225148D01*
X276125Y224363D01*
X276038Y224515D01*
G37*
G36*
G01X282792Y228412D02*
X282760Y229167D01*
X283513Y229602D01*
X284151Y229197D01*
X284239Y229046D01*
X282879Y228260D01*
X282792Y228412D01*
G37*
G36*
G01X286172Y230362D02*
X286140Y231117D01*
X286893Y231552D01*
X287531Y231147D01*
X287619Y230996D01*
X286259Y230210D01*
X286172Y230362D01*
G37*
G36*
G01X289567Y232320D02*
X289535Y233075D01*
X290288Y233510D01*
X290926Y233105D01*
X291014Y232954D01*
X289654Y232168D01*
X289567Y232320D01*
G37*
G36*
G01X268149Y219701D02*
X267859Y220485D01*
X268496Y221122D01*
X269280Y220832D01*
X269404Y220708D01*
X268273Y219577D01*
X268149Y219701D01*
G37*
G36*
G01X272109Y223326D02*
X272459Y224085D01*
X273359D01*
X273709Y223326D01*
Y223150D01*
X272109D01*
Y223326D01*
G37*
G36*
G01X283331Y226849D02*
X283363Y226094D01*
X282610Y225659D01*
X281972Y226064D01*
X281884Y226215D01*
X283244Y227000D01*
X283331Y226849D01*
G37*
G36*
G01X286720Y228804D02*
X286752Y228049D01*
X285999Y227614D01*
X285361Y228019D01*
X285273Y228170D01*
X286633Y228956D01*
X286720Y228804D01*
G37*
G36*
G01X290106Y230757D02*
X290138Y230002D01*
X289385Y229567D01*
X288747Y229972D01*
X288659Y230123D01*
X290019Y230908D01*
X290106Y230757D01*
G37*
G36*
G01X270058Y220054D02*
X270348Y219269D01*
X269712Y218633D01*
X268927Y218923D01*
X268803Y219046D01*
X269935Y220178D01*
X270058Y220054D01*
G37*
G36*
G01X276580Y222954D02*
X276612Y222199D01*
X275859Y221764D01*
X275221Y222169D01*
X275133Y222320D01*
X276493Y223106D01*
X276580Y222954D01*
G37*
G36*
G01X279966Y224908D02*
X279998Y224153D01*
X279245Y223718D01*
X278607Y224123D01*
X278519Y224274D01*
X279879Y225060D01*
X279966Y224908D01*
G37*
G36*
G01X293471Y232699D02*
X293503Y231944D01*
X292750Y231509D01*
X292112Y231914D01*
X292024Y232065D01*
X293384Y232850D01*
X293471Y232699D01*
G37*
G36*
G01X273709Y222225D02*
X273359Y221465D01*
X272459D01*
X272109Y222225D01*
Y222400D01*
X273709D01*
Y222225D01*
G37*
G36*
G01X286172Y218661D02*
X286140Y219416D01*
X286893Y219851D01*
X287531Y219446D01*
X287619Y219295D01*
X286259Y218509D01*
X286172Y218661D01*
G37*
G36*
G01X289558Y220615D02*
X289526Y221370D01*
X290279Y221805D01*
X290917Y221400D01*
X291005Y221248D01*
X289645Y220463D01*
X289558Y220615D01*
G37*
G36*
G01X290100Y219054D02*
X290132Y218299D01*
X289379Y217864D01*
X288741Y218269D01*
X288653Y218420D01*
X290013Y219206D01*
X290100Y219054D01*
G37*
G36*
G01X293486Y221008D02*
X293518Y220253D01*
X292765Y219818D01*
X292127Y220223D01*
X292039Y220374D01*
X293399Y221160D01*
X293486Y221008D01*
G37*
G36*
G01X286726Y263908D02*
X286758Y263153D01*
X286005Y262718D01*
X285367Y263123D01*
X285279Y263274D01*
X286639Y264060D01*
X286726Y263908D01*
G37*
G36*
G01X290100Y265854D02*
X290132Y265099D01*
X289379Y264664D01*
X288741Y265069D01*
X288653Y265220D01*
X290013Y266006D01*
X290100Y265854D01*
G37*
G36*
G01X283340Y261954D02*
X283372Y261199D01*
X282619Y260764D01*
X281981Y261169D01*
X281893Y261320D01*
X283253Y262106D01*
X283340Y261954D01*
G37*
G36*
G01X267257Y257269D02*
X266619Y256864D01*
X265866Y257299D01*
X265898Y258054D01*
X265985Y258206D01*
X267345Y257420D01*
X267257Y257269D01*
G37*
G36*
G01X269820Y258054D02*
X269852Y257299D01*
X269099Y256864D01*
X268461Y257269D01*
X268373Y257420D01*
X269733Y258206D01*
X269820Y258054D01*
G37*
G36*
G01X274017Y257269D02*
X273379Y256864D01*
X272626Y257299D01*
X272658Y258054D01*
X272745Y258206D01*
X274105Y257420D01*
X274017Y257269D01*
G37*
G36*
G01X276580Y258054D02*
X276612Y257299D01*
X275859Y256864D01*
X275221Y257269D01*
X275133Y257420D01*
X276493Y258206D01*
X276580Y258054D01*
G37*
G36*
G01X279966Y260008D02*
X279998Y259253D01*
X279245Y258818D01*
X278607Y259223D01*
X278519Y259374D01*
X279879Y260160D01*
X279966Y260008D01*
G37*
G36*
G01X279412Y218661D02*
X279380Y219416D01*
X280133Y219851D01*
X280771Y219446D01*
X280859Y219295D01*
X279499Y218509D01*
X279412Y218661D01*
G37*
G36*
G01X282798Y220615D02*
X282766Y221370D01*
X283519Y221805D01*
X284157Y221400D01*
X284245Y221248D01*
X282885Y220463D01*
X282798Y220615D01*
G37*
G36*
G01X286172Y222561D02*
X286140Y223316D01*
X286893Y223751D01*
X287531Y223346D01*
X287619Y223195D01*
X286259Y222409D01*
X286172Y222561D01*
G37*
G36*
G01X289558Y224515D02*
X289526Y225270D01*
X290279Y225705D01*
X290917Y225300D01*
X291005Y225148D01*
X289645Y224363D01*
X289558Y224515D01*
G37*
G36*
G01X283340Y219054D02*
X283372Y218299D01*
X282619Y217864D01*
X281981Y218269D01*
X281893Y218420D01*
X283253Y219206D01*
X283340Y219054D01*
G37*
G36*
G01X286726Y221008D02*
X286758Y220253D01*
X286005Y219818D01*
X285367Y220223D01*
X285279Y220374D01*
X286639Y221160D01*
X286726Y221008D01*
G37*
G36*
G01X290106Y222957D02*
X290138Y222202D01*
X289385Y221767D01*
X288747Y222172D01*
X288659Y222323D01*
X290019Y223109D01*
X290106Y222957D01*
G37*
G36*
G01X293486Y224908D02*
X293518Y224153D01*
X292765Y223718D01*
X292127Y224123D01*
X292039Y224274D01*
X293399Y225060D01*
X293486Y224908D01*
G37*
G36*
G01X279412Y245961D02*
X279380Y246716D01*
X280133Y247151D01*
X280771Y246746D01*
X280859Y246595D01*
X279499Y245809D01*
X279412Y245961D01*
G37*
G36*
G01X276038Y244015D02*
X276006Y244770D01*
X276759Y245205D01*
X277397Y244800D01*
X277485Y244648D01*
X276125Y243863D01*
X276038Y244015D01*
G37*
G36*
G01X271841Y244800D02*
X272479Y245205D01*
X273232Y244770D01*
X273200Y244015D01*
X273113Y243863D01*
X271753Y244648D01*
X271841Y244800D01*
G37*
G36*
G01X269278Y244015D02*
X269246Y244770D01*
X269999Y245205D01*
X270637Y244800D01*
X270725Y244648D01*
X269365Y243863D01*
X269278Y244015D01*
G37*
G36*
G01X264997Y244832D02*
X265642Y245225D01*
X266387Y244777D01*
X266343Y244022D01*
X266252Y243872D01*
X264907Y244682D01*
X264997Y244832D01*
G37*
G36*
G01X286172Y249861D02*
X286140Y250616D01*
X286893Y251051D01*
X287531Y250646D01*
X287619Y250495D01*
X286259Y249709D01*
X286172Y249861D01*
G37*
G36*
G01X282798Y247915D02*
X282766Y248670D01*
X283519Y249105D01*
X284157Y248700D01*
X284245Y248548D01*
X282885Y247763D01*
X282798Y247915D01*
G37*
G36*
G01X289558Y251815D02*
X289526Y252570D01*
X290279Y253005D01*
X290917Y252600D01*
X291005Y252448D01*
X289645Y251663D01*
X289558Y251815D01*
G37*
G36*
G01X279966Y244408D02*
X279998Y243653D01*
X279245Y243218D01*
X278607Y243623D01*
X278519Y243774D01*
X279879Y244560D01*
X279966Y244408D01*
G37*
G36*
G01X276580Y242454D02*
X276612Y241699D01*
X275859Y241264D01*
X275221Y241669D01*
X275133Y241820D01*
X276493Y242606D01*
X276580Y242454D01*
G37*
G36*
G01X274017Y241669D02*
X273379Y241264D01*
X272626Y241699D01*
X272658Y242454D01*
X272745Y242606D01*
X274105Y241820D01*
X274017Y241669D01*
G37*
G36*
G01X266851Y241601D02*
X266152Y241313D01*
X265486Y241872D01*
X265648Y242611D01*
X265761Y242745D01*
X266963Y241735D01*
X266851Y241601D01*
G37*
G36*
G01X269820Y242454D02*
X269852Y241699D01*
X269099Y241264D01*
X268461Y241669D01*
X268373Y241820D01*
X269733Y242606D01*
X269820Y242454D01*
G37*
G36*
G01X286726Y248308D02*
X286758Y247553D01*
X286005Y247118D01*
X285367Y247523D01*
X285279Y247674D01*
X286639Y248460D01*
X286726Y248308D01*
G37*
G36*
G01X283340Y246354D02*
X283372Y245599D01*
X282619Y245164D01*
X281981Y245569D01*
X281893Y245720D01*
X283253Y246506D01*
X283340Y246354D01*
G37*
G36*
G01X290100Y250254D02*
X290132Y249499D01*
X289379Y249064D01*
X288741Y249469D01*
X288653Y249620D01*
X290013Y250406D01*
X290100Y250254D01*
G37*
G36*
G01X286172Y269361D02*
X286140Y270116D01*
X286893Y270551D01*
X287531Y270146D01*
X287619Y269994D01*
X286259Y269210D01*
X286172Y269361D01*
G37*
G36*
G01X279412Y265461D02*
X279380Y266216D01*
X280133Y266651D01*
X280771Y266246D01*
X280859Y266094D01*
X279499Y265310D01*
X279412Y265461D01*
G37*
G36*
G01X282798Y267415D02*
X282766Y268170D01*
X283519Y268605D01*
X284157Y268200D01*
X284245Y268048D01*
X282885Y267264D01*
X282798Y267415D01*
G37*
G36*
G01X265081Y264300D02*
X265719Y264705D01*
X266472Y264270D01*
X266440Y263515D01*
X266353Y263364D01*
X264993Y264148D01*
X265081Y264300D01*
G37*
G36*
G01X269278Y263515D02*
X269246Y264270D01*
X269999Y264705D01*
X270637Y264300D01*
X270725Y264148D01*
X269365Y263364D01*
X269278Y263515D01*
G37*
G36*
G01X271841Y264300D02*
X272479Y264705D01*
X273232Y264270D01*
X273200Y263515D01*
X273113Y263364D01*
X271753Y264148D01*
X271841Y264300D01*
G37*
G36*
G01X276038Y263515D02*
X276006Y264270D01*
X276759Y264705D01*
X277397Y264300D01*
X277485Y264148D01*
X276125Y263364D01*
X276038Y263515D01*
G37*
G36*
G01X290100Y269754D02*
X290132Y268999D01*
X289379Y268564D01*
X288741Y268969D01*
X288653Y269120D01*
X290013Y269906D01*
X290100Y269754D01*
G37*
G36*
G01X286726Y267808D02*
X286758Y267053D01*
X286005Y266618D01*
X285367Y267023D01*
X285279Y267174D01*
X286639Y267960D01*
X286726Y267808D01*
G37*
G36*
G01X279966Y263908D02*
X279998Y263153D01*
X279245Y262718D01*
X278607Y263123D01*
X278519Y263274D01*
X279879Y264060D01*
X279966Y263908D01*
G37*
G36*
G01X283340Y265854D02*
X283372Y265099D01*
X282619Y264664D01*
X281981Y265069D01*
X281893Y265220D01*
X283253Y266006D01*
X283340Y265854D01*
G37*
G36*
G01X267257Y261169D02*
X266619Y260764D01*
X265866Y261199D01*
X265898Y261954D01*
X265985Y262106D01*
X267345Y261320D01*
X267257Y261169D01*
G37*
G36*
G01X269820Y261954D02*
X269852Y261199D01*
X269099Y260764D01*
X268461Y261169D01*
X268373Y261320D01*
X269733Y262106D01*
X269820Y261954D01*
G37*
G36*
G01X274017Y261169D02*
X273379Y260764D01*
X272626Y261199D01*
X272658Y261954D01*
X272745Y262106D01*
X274105Y261320D01*
X274017Y261169D01*
G37*
G36*
G01X276580Y261954D02*
X276612Y261199D01*
X275859Y260764D01*
X275221Y261169D01*
X275133Y261320D01*
X276493Y262106D01*
X276580Y261954D01*
G37*
G36*
G01X269278Y247915D02*
X269246Y248670D01*
X269999Y249105D01*
X270637Y248700D01*
X270725Y248548D01*
X269365Y247763D01*
X269278Y247915D01*
G37*
G36*
G01X265081Y248700D02*
X265719Y249105D01*
X266472Y248670D01*
X266440Y247915D01*
X266353Y247763D01*
X264993Y248548D01*
X265081Y248700D01*
G37*
G36*
G01X279412Y249861D02*
X279380Y250616D01*
X280133Y251051D01*
X280771Y250646D01*
X280859Y250495D01*
X279499Y249709D01*
X279412Y249861D01*
G37*
G36*
G01X276038Y247915D02*
X276006Y248670D01*
X276759Y249105D01*
X277397Y248700D01*
X277485Y248548D01*
X276125Y247763D01*
X276038Y247915D01*
G37*
G36*
G01X271841Y248700D02*
X272479Y249105D01*
X273232Y248670D01*
X273200Y247915D01*
X273113Y247763D01*
X271753Y248548D01*
X271841Y248700D01*
G37*
G36*
G01X286172Y253761D02*
X286140Y254516D01*
X286893Y254951D01*
X287531Y254546D01*
X287619Y254395D01*
X286259Y253609D01*
X286172Y253761D01*
G37*
G36*
G01X282798Y251815D02*
X282766Y252570D01*
X283519Y253005D01*
X284157Y252600D01*
X284245Y252448D01*
X282885Y251663D01*
X282798Y251815D01*
G37*
G36*
G01X289558Y255715D02*
X289526Y256470D01*
X290279Y256905D01*
X290917Y256500D01*
X291005Y256348D01*
X289645Y255563D01*
X289558Y255715D01*
G37*
G36*
G01X267257Y245569D02*
X266619Y245164D01*
X265866Y245599D01*
X265898Y246354D01*
X265985Y246506D01*
X267345Y245720D01*
X267257Y245569D01*
G37*
G36*
G01X269820Y246354D02*
X269852Y245599D01*
X269099Y245164D01*
X268461Y245569D01*
X268373Y245720D01*
X269733Y246506D01*
X269820Y246354D01*
G37*
G36*
G01X274017Y245569D02*
X273379Y245164D01*
X272626Y245599D01*
X272658Y246354D01*
X272745Y246506D01*
X274105Y245720D01*
X274017Y245569D01*
G37*
G36*
G01X276580Y246354D02*
X276612Y245599D01*
X275859Y245164D01*
X275221Y245569D01*
X275133Y245720D01*
X276493Y246506D01*
X276580Y246354D01*
G37*
G36*
G01X279966Y248308D02*
X279998Y247553D01*
X279245Y247118D01*
X278607Y247523D01*
X278519Y247674D01*
X279879Y248460D01*
X279966Y248308D01*
G37*
G36*
G01X283340Y250254D02*
X283372Y249499D01*
X282619Y249064D01*
X281981Y249469D01*
X281893Y249620D01*
X283253Y250406D01*
X283340Y250254D01*
G37*
G36*
G01X286726Y252208D02*
X286758Y251453D01*
X286005Y251018D01*
X285367Y251423D01*
X285279Y251574D01*
X286639Y252360D01*
X286726Y252208D01*
G37*
G36*
G01X290100Y254154D02*
X290132Y253399D01*
X289379Y252964D01*
X288741Y253369D01*
X288653Y253520D01*
X290013Y254306D01*
X290100Y254154D01*
G37*
G36*
G01X282798Y240115D02*
X282766Y240870D01*
X283519Y241305D01*
X284157Y240900D01*
X284245Y240748D01*
X282885Y239963D01*
X282798Y240115D01*
G37*
G36*
G01X286172Y242061D02*
X286140Y242816D01*
X286893Y243251D01*
X287531Y242846D01*
X287619Y242695D01*
X286259Y241909D01*
X286172Y242061D01*
G37*
G36*
G01X279412Y238161D02*
X279380Y238916D01*
X280133Y239351D01*
X280771Y238946D01*
X280859Y238795D01*
X279499Y238009D01*
X279412Y238161D01*
G37*
G36*
G01X289558Y244015D02*
X289526Y244770D01*
X290279Y245205D01*
X290917Y244800D01*
X291005Y244648D01*
X289645Y243863D01*
X289558Y244015D01*
G37*
G36*
G01X258376Y230896D02*
X258725Y231656D01*
X259626D01*
X259975Y230896D01*
Y230721D01*
X258376D01*
Y230896D01*
G37*
G36*
G01X271743Y235009D02*
X272093Y235769D01*
X272993D01*
X273343Y235009D01*
Y234834D01*
X271743D01*
Y235009D01*
G37*
G36*
G01X262276Y230896D02*
X262625Y231656D01*
X263526D01*
X263875Y230896D01*
Y230721D01*
X262276D01*
Y230896D01*
G37*
G36*
G01X267677Y232336D02*
X267386Y233120D01*
X268023Y233757D01*
X268807Y233467D01*
X268931Y233343D01*
X267800Y232212D01*
X267677Y232336D01*
G37*
G36*
G01X276032Y236212D02*
X276000Y236967D01*
X276753Y237402D01*
X277391Y236997D01*
X277479Y236846D01*
X276119Y236060D01*
X276032Y236212D01*
G37*
G36*
G01X286726Y240508D02*
X286758Y239753D01*
X286005Y239318D01*
X285367Y239723D01*
X285279Y239874D01*
X286639Y240660D01*
X286726Y240508D01*
G37*
G36*
G01X290100Y242454D02*
X290132Y241699D01*
X289379Y241264D01*
X288741Y241669D01*
X288653Y241820D01*
X290013Y242606D01*
X290100Y242454D01*
G37*
G36*
G01X259961Y229796D02*
X259611Y229036D01*
X258711D01*
X258361Y229796D01*
Y229971D01*
X259961D01*
Y229796D01*
G37*
G36*
G01X263861D02*
X263511Y229036D01*
X262611D01*
X262261Y229796D01*
Y229971D01*
X263861D01*
Y229796D01*
G37*
G36*
G01X276580Y234654D02*
X276612Y233899D01*
X275859Y233464D01*
X275221Y233869D01*
X275133Y234020D01*
X276493Y234806D01*
X276580Y234654D01*
G37*
G36*
G01X273343Y233909D02*
X272993Y233149D01*
X272093D01*
X271743Y233909D01*
Y234084D01*
X273343D01*
Y233909D01*
G37*
G36*
G01X269367Y232470D02*
X269657Y231685D01*
X269021Y231049D01*
X268236Y231339D01*
X268112Y231462D01*
X269244Y232594D01*
X269367Y232470D01*
G37*
G36*
G01X279966Y236608D02*
X279998Y235853D01*
X279245Y235418D01*
X278607Y235823D01*
X278519Y235974D01*
X279879Y236760D01*
X279966Y236608D01*
G37*
G36*
G01X283340Y238554D02*
X283372Y237799D01*
X282619Y237364D01*
X281981Y237769D01*
X281893Y237920D01*
X283253Y238706D01*
X283340Y238554D01*
G37*
G36*
G01X267286Y249452D02*
X266648Y249047D01*
X265895Y249482D01*
X265927Y250237D01*
X266014Y250389D01*
X267374Y249604D01*
X267286Y249452D01*
G37*
G36*
G01X269791Y250237D02*
X269823Y249482D01*
X269070Y249047D01*
X268432Y249452D01*
X268344Y249604D01*
X269704Y250389D01*
X269791Y250237D01*
G37*
G36*
G01X274047Y249452D02*
X273409Y249047D01*
X272656Y249482D01*
X272688Y250237D01*
X272775Y250389D01*
X274135Y249604D01*
X274047Y249452D01*
G37*
G36*
G01X276551Y250237D02*
X276583Y249482D01*
X275830Y249047D01*
X275192Y249452D01*
X275104Y249604D01*
X276464Y250389D01*
X276551Y250237D01*
G37*
G36*
G01X279966Y252208D02*
X279998Y251453D01*
X279245Y251018D01*
X278607Y251423D01*
X278519Y251574D01*
X279879Y252360D01*
X279966Y252208D01*
G37*
G36*
G01X283340Y254154D02*
X283372Y253399D01*
X282619Y252964D01*
X281981Y253369D01*
X281893Y253520D01*
X283253Y254306D01*
X283340Y254154D01*
G37*
G36*
G01X286726Y256108D02*
X286758Y255353D01*
X286005Y254918D01*
X285367Y255323D01*
X285279Y255474D01*
X286639Y256260D01*
X286726Y256108D01*
G37*
G36*
G01X290106Y258057D02*
X290138Y257302D01*
X289385Y256867D01*
X288747Y257272D01*
X288659Y257423D01*
X290019Y258209D01*
X290106Y258057D01*
G37*
G36*
G01X273550Y230009D02*
X273200Y229249D01*
X272301D01*
X271951Y230009D01*
X271950Y230184D01*
X273551D01*
X273550Y230009D01*
G37*
G36*
G01X270760Y229301D02*
X271050Y228516D01*
X270414Y227880D01*
X269629Y228170D01*
X269505Y228293D01*
X270637Y229425D01*
X270760Y229301D01*
G37*
G36*
G01X267960Y226501D02*
X268250Y225716D01*
X267614Y225080D01*
X266829Y225370D01*
X266705Y225493D01*
X267837Y226625D01*
X267960Y226501D01*
G37*
G36*
G01X279951Y232699D02*
X279983Y231944D01*
X279230Y231509D01*
X278592Y231914D01*
X278504Y232065D01*
X279864Y232850D01*
X279951Y232699D01*
G37*
G36*
G01X276586Y230757D02*
X276618Y230002D01*
X275865Y229567D01*
X275227Y229972D01*
X275139Y230123D01*
X276499Y230908D01*
X276586Y230757D01*
G37*
G36*
G01X283340Y234654D02*
X283372Y233899D01*
X282619Y233464D01*
X281981Y233869D01*
X281893Y234020D01*
X283253Y234806D01*
X283340Y234654D01*
G37*
G36*
G01X262441Y224160D02*
X262091Y223400D01*
X261191D01*
X260841Y224160D01*
Y224335D01*
X262441D01*
Y224160D01*
G37*
G36*
G01X286726Y236608D02*
X286758Y235853D01*
X286005Y235418D01*
X285367Y235823D01*
X285279Y235974D01*
X286639Y236760D01*
X286726Y236608D01*
G37*
G36*
G01X290100Y238554D02*
X290132Y237799D01*
X289379Y237364D01*
X288741Y237769D01*
X288653Y237920D01*
X290013Y238706D01*
X290100Y238554D01*
G37*
G36*
G01X276586Y226858D02*
X276618Y226103D01*
X275865Y225668D01*
X275227Y226073D01*
X275139Y226224D01*
X276499Y227009D01*
X276586Y226858D01*
G37*
G36*
G01X279966Y228807D02*
X279998Y228052D01*
X279245Y227617D01*
X278607Y228022D01*
X278519Y228173D01*
X279879Y228958D01*
X279966Y228807D01*
G37*
G36*
G01X283346Y230757D02*
X283378Y230002D01*
X282625Y229567D01*
X281987Y229972D01*
X281899Y230123D01*
X283259Y230908D01*
X283346Y230757D01*
G37*
G36*
G01X286711Y232699D02*
X286743Y231944D01*
X285990Y231509D01*
X285352Y231914D01*
X285264Y232065D01*
X286624Y232850D01*
X286711Y232699D01*
G37*
G36*
G01X290100Y234654D02*
X290132Y233899D01*
X289379Y233464D01*
X288741Y233869D01*
X288653Y234020D01*
X290013Y234806D01*
X290100Y234654D01*
G37*
G36*
G01X269925Y224194D02*
X270215Y223409D01*
X269579Y222773D01*
X268794Y223063D01*
X268670Y223186D01*
X269802Y224318D01*
X269925Y224194D01*
G37*
G36*
G01X262480Y220166D02*
X262130Y219406D01*
X261230D01*
X260880Y220166D01*
Y220341D01*
X262480D01*
Y220166D01*
G37*
G36*
G01X293486Y236608D02*
X293518Y235853D01*
X292765Y235418D01*
X292127Y235823D01*
X292039Y235974D01*
X293399Y236760D01*
X293486Y236608D01*
G37*
G36*
G01X290100Y261954D02*
X290132Y261199D01*
X289379Y260764D01*
X288741Y261169D01*
X288653Y261320D01*
X290013Y262105D01*
X290100Y261954D01*
G37*
G36*
G01X267287Y253352D02*
X266649Y252947D01*
X265896Y253382D01*
X265928Y254137D01*
X266015Y254289D01*
X267375Y253504D01*
X267287Y253352D01*
G37*
G36*
G01X269791Y254137D02*
X269823Y253382D01*
X269070Y252947D01*
X268432Y253352D01*
X268344Y253504D01*
X269704Y254289D01*
X269791Y254137D01*
G37*
G36*
G01X274047Y253352D02*
X273409Y252947D01*
X272656Y253382D01*
X272688Y254137D01*
X272775Y254289D01*
X274135Y253504D01*
X274047Y253352D01*
G37*
G36*
G01X276551Y254137D02*
X276583Y253382D01*
X275830Y252947D01*
X275192Y253352D01*
X275104Y253504D01*
X276464Y254289D01*
X276551Y254137D01*
G37*
G36*
G01X279960Y256105D02*
X279992Y255350D01*
X279239Y254915D01*
X278601Y255320D01*
X278513Y255471D01*
X279873Y256256D01*
X279960Y256105D01*
G37*
G36*
G01X263040Y255360D02*
X262690Y254600D01*
X261790D01*
X261440Y255360D01*
Y255535D01*
X263040D01*
Y255360D01*
G37*
G36*
G01X286720Y260005D02*
X286752Y259250D01*
X285999Y258815D01*
X285361Y259220D01*
X285273Y259371D01*
X286633Y260156D01*
X286720Y260005D01*
G37*
G36*
G01X283340Y258054D02*
X283372Y257299D01*
X282619Y256864D01*
X281981Y257269D01*
X281893Y257420D01*
X283253Y258205D01*
X283340Y258054D01*
G37*
G36*
G01X265074Y252604D02*
X265712Y253009D01*
X266465Y252574D01*
X266433Y251819D01*
X266346Y251667D01*
X264986Y252452D01*
X265074Y252604D01*
G37*
G36*
G01X269307Y251832D02*
X269275Y252587D01*
X270028Y253022D01*
X270666Y252617D01*
X270754Y252466D01*
X269394Y251680D01*
X269307Y251832D01*
G37*
G36*
G01X271812Y252617D02*
X272450Y253022D01*
X273203Y252587D01*
X273171Y251832D01*
X273084Y251680D01*
X271724Y252466D01*
X271812Y252617D01*
G37*
G36*
G01X279412Y253761D02*
X279380Y254516D01*
X280133Y254951D01*
X280771Y254546D01*
X280859Y254395D01*
X279499Y253609D01*
X279412Y253761D01*
G37*
G36*
G01X282798Y255715D02*
X282766Y256470D01*
X283519Y256905D01*
X284157Y256500D01*
X284245Y256348D01*
X282885Y255563D01*
X282798Y255715D01*
G37*
G36*
G01X286172Y257661D02*
X286140Y258416D01*
X286893Y258851D01*
X287531Y258446D01*
X287619Y258295D01*
X286259Y257509D01*
X286172Y257661D01*
G37*
G36*
G01X289588Y259632D02*
X289556Y260387D01*
X290309Y260822D01*
X290947Y260417D01*
X291035Y260266D01*
X289675Y259480D01*
X289588Y259632D01*
G37*
G36*
G01X292091Y260417D02*
X292729Y260822D01*
X293482Y260387D01*
X293450Y259632D01*
X293363Y259480D01*
X292003Y260266D01*
X292091Y260417D01*
G37*
G36*
G01X286172Y238161D02*
X286140Y238916D01*
X286893Y239351D01*
X287531Y238946D01*
X287619Y238795D01*
X286259Y238009D01*
X286172Y238161D01*
G37*
G36*
G01X289558Y240115D02*
X289526Y240870D01*
X290279Y241305D01*
X290917Y240900D01*
X291005Y240748D01*
X289645Y239963D01*
X289558Y240115D01*
G37*
G36*
G01X268851Y228948D02*
X268561Y229732D01*
X269198Y230369D01*
X269982Y230079D01*
X270106Y229955D01*
X268975Y228824D01*
X268851Y228948D01*
G37*
G36*
G01X260841Y225260D02*
X261191Y226020D01*
X262091D01*
X262441Y225260D01*
Y225085D01*
X260841D01*
Y225260D01*
G37*
G36*
G01X266051Y226148D02*
X265761Y226932D01*
X266398Y227569D01*
X267182Y227279D01*
X267306Y227155D01*
X266175Y226024D01*
X266051Y226148D01*
G37*
G36*
G01X279412Y234261D02*
X279380Y235016D01*
X280133Y235451D01*
X280771Y235046D01*
X280859Y234895D01*
X279499Y234109D01*
X279412Y234261D01*
G37*
G36*
G01X276047Y232320D02*
X276015Y233075D01*
X276768Y233510D01*
X277406Y233105D01*
X277494Y232954D01*
X276134Y232168D01*
X276047Y232320D01*
G37*
G36*
G01X272081Y231109D02*
X272431Y231869D01*
X273331D01*
X273681Y231109D01*
Y230934D01*
X272081D01*
Y231109D01*
G37*
G36*
G01X282792Y236212D02*
X282760Y236967D01*
X283513Y237402D01*
X284151Y236997D01*
X284239Y236846D01*
X282879Y236060D01*
X282792Y236212D01*
G37*
G36*
G01X268016Y223841D02*
X267726Y224625D01*
X268363Y225262D01*
X269147Y224972D01*
X269271Y224848D01*
X268140Y223717D01*
X268016Y223841D01*
G37*
G36*
G01X276032Y228412D02*
X276000Y229167D01*
X276753Y229602D01*
X277391Y229197D01*
X277479Y229046D01*
X276119Y228260D01*
X276032Y228412D01*
G37*
G36*
G01X279412Y230362D02*
X279380Y231117D01*
X280133Y231552D01*
X280771Y231147D01*
X280859Y230996D01*
X279499Y230210D01*
X279412Y230362D01*
G37*
G36*
G01X282807Y232320D02*
X282775Y233075D01*
X283528Y233510D01*
X284166Y233105D01*
X284254Y232954D01*
X282894Y232168D01*
X282807Y232320D01*
G37*
G36*
G01X286172Y234261D02*
X286140Y235016D01*
X286893Y235451D01*
X287531Y235046D01*
X287619Y234895D01*
X286259Y234109D01*
X286172Y234261D01*
G37*
G36*
G01X260880Y221266D02*
X261230Y222026D01*
X262130D01*
X262480Y221266D01*
Y221091D01*
X260880D01*
Y221266D01*
G37*
G36*
G01X289552Y236212D02*
X289520Y236967D01*
X290273Y237402D01*
X290911Y236997D01*
X290999Y236846D01*
X289639Y236060D01*
X289552Y236212D01*
G37*
G36*
G01X286172Y261561D02*
X286140Y262316D01*
X286893Y262751D01*
X287531Y262346D01*
X287619Y262194D01*
X286259Y261409D01*
X286172Y261561D01*
G37*
G36*
G01X289588Y263532D02*
X289556Y264287D01*
X290309Y264722D01*
X290947Y264317D01*
X291035Y264166D01*
X289675Y263380D01*
X289588Y263532D01*
G37*
G36*
G01X292091Y264317D02*
X292729Y264722D01*
X293482Y264287D01*
X293450Y263532D01*
X293363Y263380D01*
X292003Y264166D01*
X292091Y264317D01*
G37*
G36*
G01X265074Y256504D02*
X265712Y256909D01*
X266465Y256474D01*
X266433Y255719D01*
X266346Y255567D01*
X264986Y256352D01*
X265074Y256504D01*
G37*
G36*
G01X269307Y255732D02*
X269275Y256487D01*
X270028Y256922D01*
X270666Y256517D01*
X270754Y256366D01*
X269394Y255580D01*
X269307Y255732D01*
G37*
G36*
G01X271812Y256517D02*
X272450Y256922D01*
X273203Y256487D01*
X273171Y255732D01*
X273084Y255580D01*
X271724Y256366D01*
X271812Y256517D01*
G37*
G36*
G01X279412Y257661D02*
X279380Y258416D01*
X280133Y258851D01*
X280771Y258446D01*
X280859Y258295D01*
X279499Y257509D01*
X279412Y257661D01*
G37*
G36*
G01X276032Y255712D02*
X276000Y256467D01*
X276753Y256902D01*
X277391Y256497D01*
X277479Y256346D01*
X276119Y255560D01*
X276032Y255712D01*
G37*
G36*
G01X261440Y256460D02*
X261790Y257220D01*
X262690D01*
X263040Y256460D01*
Y256285D01*
X261440D01*
Y256460D01*
G37*
G36*
G01X282798Y259615D02*
X282766Y260370D01*
X283519Y260805D01*
X284157Y260400D01*
X284245Y260248D01*
X282885Y259463D01*
X282798Y259615D01*
G37*
G36*
G01X280777Y335269D02*
X280139Y334864D01*
X279386Y335299D01*
X279418Y336054D01*
X279505Y336205D01*
X280865Y335420D01*
X280777Y335269D01*
G37*
G36*
G01X277391Y337223D02*
X276753Y336818D01*
X276000Y337253D01*
X276032Y338008D01*
X276119Y338160D01*
X277479Y337375D01*
X277391Y337223D01*
G37*
G36*
G01X274017Y339169D02*
X273379Y338764D01*
X272626Y339199D01*
X272658Y339954D01*
X272745Y340105D01*
X274105Y339320D01*
X274017Y339169D01*
G37*
G36*
G01X270631Y341123D02*
X269993Y340718D01*
X269240Y341153D01*
X269272Y341908D01*
X269359Y342060D01*
X270719Y341275D01*
X270631Y341123D01*
G37*
G36*
G01X287537Y331369D02*
X286899Y330964D01*
X286146Y331399D01*
X286178Y332154D01*
X286265Y332305D01*
X287625Y331520D01*
X287537Y331369D01*
G37*
G36*
G01X284151Y333323D02*
X283513Y332918D01*
X282760Y333353D01*
X282792Y334108D01*
X282879Y334260D01*
X284239Y333475D01*
X284151Y333323D01*
G37*
G36*
G01X290911Y329423D02*
X290273Y329018D01*
X289520Y329453D01*
X289552Y330208D01*
X289639Y330360D01*
X290999Y329575D01*
X290911Y329423D01*
G37*
G36*
G01X293486Y330208D02*
X293518Y329453D01*
X292765Y329018D01*
X292127Y329423D01*
X292039Y329575D01*
X293399Y330360D01*
X293486Y330208D01*
G37*
G36*
G01X278601Y338400D02*
X279239Y338805D01*
X279992Y338370D01*
X279960Y337615D01*
X279873Y337463D01*
X278513Y338249D01*
X278601Y338400D01*
G37*
G36*
G01X275227Y340346D02*
X275865Y340751D01*
X276618Y340316D01*
X276586Y339561D01*
X276499Y339409D01*
X275139Y340195D01*
X275227Y340346D01*
G37*
G36*
G01X281987Y336446D02*
X282625Y336851D01*
X283378Y336416D01*
X283346Y335661D01*
X283259Y335509D01*
X281899Y336295D01*
X281987Y336446D01*
G37*
G36*
G01X288747Y332546D02*
X289385Y332951D01*
X290138Y332516D01*
X290106Y331761D01*
X290019Y331609D01*
X288659Y332395D01*
X288747Y332546D01*
G37*
G36*
G01X285361Y334500D02*
X285999Y334905D01*
X286752Y334470D01*
X286720Y333715D01*
X286633Y333563D01*
X285273Y334349D01*
X285361Y334500D01*
G37*
G36*
G01X274017Y335269D02*
X273379Y334864D01*
X272626Y335299D01*
X272658Y336054D01*
X272745Y336205D01*
X274105Y335420D01*
X274017Y335269D01*
G37*
G36*
G01X270631Y337223D02*
X269993Y336818D01*
X269240Y337253D01*
X269272Y338008D01*
X269359Y338160D01*
X270719Y337375D01*
X270631Y337223D01*
G37*
G36*
G01X267257Y339169D02*
X266619Y338764D01*
X265866Y339199D01*
X265898Y339954D01*
X265985Y340105D01*
X267345Y339320D01*
X267257Y339169D01*
G37*
G36*
G01X262682Y339106D02*
X262907Y338385D01*
X262292Y337771D01*
X261571Y337997D01*
X261447Y338121D01*
X262559Y339230D01*
X262682Y339106D01*
G37*
G36*
G01X277391Y333323D02*
X276753Y332918D01*
X276000Y333353D01*
X276032Y334108D01*
X276119Y334260D01*
X277479Y333475D01*
X277391Y333323D01*
G37*
G36*
G01X280777Y331369D02*
X280139Y330964D01*
X279386Y331399D01*
X279418Y332154D01*
X279505Y332305D01*
X280865Y331520D01*
X280777Y331369D01*
G37*
G36*
G01X284151Y329423D02*
X283513Y329018D01*
X282760Y329453D01*
X282792Y330208D01*
X282879Y330360D01*
X284239Y329575D01*
X284151Y329423D01*
G37*
G36*
G01X287537Y327469D02*
X286899Y327064D01*
X286146Y327499D01*
X286178Y328254D01*
X286265Y328405D01*
X287625Y327620D01*
X287537Y327469D01*
G37*
G36*
G01X290911Y325523D02*
X290273Y325118D01*
X289520Y325553D01*
X289552Y326308D01*
X289639Y326460D01*
X290999Y325675D01*
X290911Y325523D01*
G37*
G36*
G01X293486Y326308D02*
X293518Y325553D01*
X292765Y325118D01*
X292127Y325523D01*
X292039Y325675D01*
X293399Y326460D01*
X293486Y326308D01*
G37*
G36*
G01X259110Y338981D02*
X259463Y339649D01*
X260333Y339645D01*
X260679Y338973D01*
Y338798D01*
X259109Y338807D01*
X259110Y338981D01*
G37*
G36*
G01X261910Y341077D02*
X261687Y341799D01*
X262305Y342411D01*
X263025Y342181D01*
X263149Y342057D01*
X262032Y340953D01*
X261910Y341077D01*
G37*
G36*
G01X275227Y336446D02*
X275865Y336851D01*
X276618Y336416D01*
X276586Y335661D01*
X276499Y335509D01*
X275139Y336295D01*
X275227Y336446D01*
G37*
G36*
G01X271841Y338400D02*
X272479Y338805D01*
X273232Y338370D01*
X273200Y337615D01*
X273113Y337463D01*
X271753Y338249D01*
X271841Y338400D01*
G37*
G36*
G01X268467Y340346D02*
X269105Y340751D01*
X269858Y340316D01*
X269826Y339561D01*
X269739Y339409D01*
X268379Y340195D01*
X268467Y340346D01*
G37*
G36*
G01X278601Y334500D02*
X279239Y334905D01*
X279992Y334470D01*
X279960Y333715D01*
X279873Y333563D01*
X278513Y334349D01*
X278601Y334500D01*
G37*
G36*
G01X281987Y332546D02*
X282625Y332951D01*
X283378Y332516D01*
X283346Y331761D01*
X283259Y331609D01*
X281899Y332395D01*
X281987Y332546D01*
G37*
G36*
G01X288747Y328647D02*
X289385Y329052D01*
X290138Y328617D01*
X290106Y327862D01*
X290019Y327711D01*
X288659Y328495D01*
X288747Y328647D01*
G37*
G36*
G01X285361Y330600D02*
X285999Y331005D01*
X286752Y330570D01*
X286720Y329815D01*
X286633Y329663D01*
X285273Y330449D01*
X285361Y330600D01*
G37*
G36*
G01X290911Y341123D02*
X290273Y340718D01*
X289520Y341153D01*
X289552Y341908D01*
X289639Y342060D01*
X290999Y341275D01*
X290911Y341123D01*
G37*
G36*
G01X287537Y339169D02*
X286899Y338764D01*
X286146Y339199D01*
X286178Y339954D01*
X286265Y340105D01*
X287625Y339320D01*
X287537Y339169D01*
G37*
G36*
G01X284151Y341123D02*
X283513Y340718D01*
X282760Y341153D01*
X282792Y341908D01*
X282879Y342060D01*
X284239Y341275D01*
X284151Y341123D01*
G37*
G36*
G01X290911Y337223D02*
X290273Y336818D01*
X289520Y337253D01*
X289552Y338008D01*
X289639Y338160D01*
X290999Y337375D01*
X290911Y337223D01*
G37*
G36*
G01X281987Y340346D02*
X282625Y340751D01*
X283378Y340316D01*
X283346Y339561D01*
X283259Y339409D01*
X281899Y340195D01*
X281987Y340346D01*
G37*
G36*
G01X288747Y336446D02*
X289385Y336851D01*
X290138Y336416D01*
X290106Y335661D01*
X290019Y335509D01*
X288659Y336295D01*
X288747Y336446D01*
G37*
G36*
G01X285361Y338400D02*
X285999Y338805D01*
X286752Y338370D01*
X286720Y337615D01*
X286633Y337463D01*
X285273Y338249D01*
X285361Y338400D01*
G37*
G36*
G01X288747Y340346D02*
X289385Y340751D01*
X290138Y340316D01*
X290106Y339561D01*
X290019Y339409D01*
X288659Y340195D01*
X288747Y340346D01*
G37*
G36*
G01X280777Y339169D02*
X280139Y338764D01*
X279386Y339199D01*
X279418Y339954D01*
X279505Y340105D01*
X280865Y339320D01*
X280777Y339169D01*
G37*
G36*
G01X277391Y341123D02*
X276753Y340718D01*
X276000Y341153D01*
X276032Y341908D01*
X276119Y342060D01*
X277479Y341275D01*
X277391Y341123D01*
G37*
G36*
G01X287537Y335269D02*
X286899Y334864D01*
X286146Y335299D01*
X286178Y336054D01*
X286265Y336205D01*
X287625Y335420D01*
X287537Y335269D01*
G37*
G36*
G01X284151Y337223D02*
X283513Y336818D01*
X282760Y337253D01*
X282792Y338008D01*
X282879Y338160D01*
X284239Y337375D01*
X284151Y337223D01*
G37*
G36*
G01X290911Y333323D02*
X290273Y332918D01*
X289520Y333353D01*
X289552Y334108D01*
X289639Y334260D01*
X290999Y333475D01*
X290911Y333323D01*
G37*
G36*
G01X293486Y334108D02*
X293518Y333353D01*
X292765Y332918D01*
X292127Y333323D01*
X292039Y333475D01*
X293399Y334260D01*
X293486Y334108D01*
G37*
G36*
G01X259175Y343166D02*
X258825Y342406D01*
X257925D01*
X257575Y343166D01*
Y343341D01*
X259175D01*
Y343166D01*
G37*
G36*
G01X262536Y344814D02*
X262826Y344029D01*
X262189Y343393D01*
X261404Y343683D01*
X261281Y343807D01*
X262412Y344938D01*
X262536Y344814D01*
G37*
G36*
G01X267257Y343069D02*
X266619Y342664D01*
X265866Y343099D01*
X265898Y343854D01*
X265985Y344005D01*
X267345Y343220D01*
X267257Y343069D01*
G37*
G36*
G01X270601Y379988D02*
X269963Y379583D01*
X269210Y380017D01*
X269241Y380772D01*
X269328Y380924D01*
X270689Y380139D01*
X270601Y379988D01*
G37*
G36*
G01X268737Y385750D02*
X268067Y386100D01*
Y386970D01*
X268737Y387320D01*
X268912D01*
Y385750D01*
X268737D01*
G37*
G36*
G01X277391Y376223D02*
X276753Y375818D01*
X276000Y376253D01*
X276032Y377008D01*
X276119Y377160D01*
X277479Y376375D01*
X277391Y376223D01*
G37*
G36*
G01X273213Y378667D02*
X272492Y378441D01*
X271877Y379056D01*
X272104Y379777D01*
X272227Y379901D01*
X273337Y378790D01*
X273213Y378667D01*
G37*
G36*
G01X268737Y389675D02*
X268067Y390025D01*
Y390895D01*
X268737Y391245D01*
X268912D01*
Y389675D01*
X268737D01*
G37*
G36*
G01X280777Y374269D02*
X280139Y373864D01*
X279386Y374299D01*
X279418Y375054D01*
X279505Y375205D01*
X280865Y374420D01*
X280777Y374269D01*
G37*
G36*
G01X287531Y370372D02*
X286893Y369967D01*
X286140Y370402D01*
X286172Y371157D01*
X286259Y371309D01*
X287619Y370523D01*
X287531Y370372D01*
G37*
G36*
G01X284166Y372314D02*
X283528Y371909D01*
X282775Y372344D01*
X282807Y373099D01*
X282894Y373251D01*
X284254Y372465D01*
X284166Y372314D01*
G37*
G36*
G01X290917Y368419D02*
X290279Y368014D01*
X289526Y368449D01*
X289558Y369204D01*
X289645Y369355D01*
X291005Y368570D01*
X290917Y368419D01*
G37*
G36*
G01X265202Y393965D02*
X264852Y393205D01*
X263952D01*
X263602Y393965D01*
Y394140D01*
X265202D01*
Y393965D01*
G37*
G36*
G01X268737Y381850D02*
X268067Y382200D01*
Y383070D01*
X268737Y383420D01*
X268912D01*
Y381850D01*
X268737D01*
G37*
G36*
G01X271841Y381300D02*
X272479Y381705D01*
X273232Y381270D01*
X273200Y380515D01*
X273113Y380363D01*
X271753Y381149D01*
X271841Y381300D01*
G37*
G36*
G01X270361Y385419D02*
X271031Y385069D01*
Y384199D01*
X270361Y383849D01*
X270186D01*
Y385419D01*
X270361D01*
G37*
G36*
G01X275227Y379346D02*
X275865Y379751D01*
X276618Y379316D01*
X276586Y378561D01*
X276499Y378409D01*
X275139Y379195D01*
X275227Y379346D01*
G37*
G36*
G01X270361Y389319D02*
X271031Y388969D01*
Y388099D01*
X270361Y387749D01*
X270186D01*
Y389319D01*
X270361D01*
G37*
G36*
G01X278601Y377400D02*
X279239Y377805D01*
X279992Y377370D01*
X279960Y376615D01*
X279873Y376463D01*
X278513Y377249D01*
X278601Y377400D01*
G37*
G36*
G01X281987Y375446D02*
X282625Y375851D01*
X283378Y375416D01*
X283346Y374661D01*
X283259Y374509D01*
X281899Y375295D01*
X281987Y375446D01*
G37*
G36*
G01X288741Y371550D02*
X289379Y371955D01*
X290132Y371520D01*
X290100Y370765D01*
X290013Y370613D01*
X288653Y371399D01*
X288741Y371550D01*
G37*
G36*
G01X285352Y373505D02*
X285990Y373910D01*
X286743Y373475D01*
X286711Y372720D01*
X286624Y372568D01*
X285264Y373353D01*
X285352Y373505D01*
G37*
G36*
G01X270361Y393170D02*
X271031Y392820D01*
Y391950D01*
X270361Y391600D01*
X270186D01*
Y393170D01*
X270361D01*
G37*
G36*
G01X263602Y395063D02*
X263952Y395823D01*
X264852D01*
X265202Y395063D01*
Y394888D01*
X263602D01*
Y395063D01*
G37*
G36*
G01X292127Y369597D02*
X292765Y370002D01*
X293518Y369567D01*
X293486Y368812D01*
X293399Y368661D01*
X292039Y369445D01*
X292127Y369597D01*
G37*
G36*
G01X260402Y366340D02*
X259617Y366050D01*
X258981Y366686D01*
X259271Y367471D01*
X259394Y367595D01*
X260526Y366463D01*
X260402Y366340D01*
G37*
G36*
G01X280777Y354769D02*
X280139Y354364D01*
X279386Y354799D01*
X279418Y355554D01*
X279505Y355705D01*
X280865Y354920D01*
X280777Y354769D01*
G37*
G36*
G01X277391Y356723D02*
X276753Y356318D01*
X276000Y356753D01*
X276032Y357508D01*
X276119Y357660D01*
X277479Y356875D01*
X277391Y356723D01*
G37*
G36*
G01X287537Y350869D02*
X286899Y350464D01*
X286146Y350899D01*
X286178Y351654D01*
X286265Y351805D01*
X287625Y351020D01*
X287537Y350869D01*
G37*
G36*
G01X284151Y352823D02*
X283513Y352418D01*
X282760Y352853D01*
X282792Y353608D01*
X282879Y353760D01*
X284239Y352975D01*
X284151Y352823D01*
G37*
G36*
G01X290911Y348923D02*
X290273Y348518D01*
X289520Y348953D01*
X289552Y349708D01*
X289639Y349860D01*
X290999Y349075D01*
X290911Y348923D01*
G37*
G36*
G01X263160Y363582D02*
X262375Y363292D01*
X261739Y363928D01*
X262029Y364713D01*
X262152Y364837D01*
X263284Y363705D01*
X263160Y363582D01*
G37*
G36*
G01X266926Y362966D02*
X266576Y362206D01*
X265676D01*
X265326Y362966D01*
Y363141D01*
X266926D01*
Y362966D01*
G37*
G36*
G01X270868Y360273D02*
X270084Y359983D01*
X269447Y360620D01*
X269737Y361404D01*
X269861Y361528D01*
X270992Y360397D01*
X270868Y360273D01*
G37*
G36*
G01X256551Y368732D02*
X256902Y369493D01*
X257801D01*
X258151Y368732D01*
X258152Y368558D01*
X256551D01*
Y368732D01*
G37*
G36*
G01X278601Y357900D02*
X279239Y358305D01*
X279992Y357870D01*
X279960Y357115D01*
X279873Y356963D01*
X278513Y357749D01*
X278601Y357900D01*
G37*
G36*
G01X281987Y355946D02*
X282625Y356351D01*
X283378Y355916D01*
X283346Y355161D01*
X283259Y355009D01*
X281899Y355795D01*
X281987Y355946D01*
G37*
G36*
G01X285361Y354000D02*
X285999Y354405D01*
X286752Y353970D01*
X286720Y353215D01*
X286633Y353063D01*
X285273Y353849D01*
X285361Y354000D01*
G37*
G36*
G01X288747Y352046D02*
X289385Y352451D01*
X290138Y352016D01*
X290106Y351261D01*
X290019Y351109D01*
X288659Y351895D01*
X288747Y352046D01*
G37*
G36*
G01X275227Y359846D02*
X275865Y360251D01*
X276618Y359816D01*
X276586Y359061D01*
X276499Y358909D01*
X275139Y359695D01*
X275227Y359846D01*
G37*
G36*
G01X270515Y362182D02*
X271300Y362472D01*
X271936Y361836D01*
X271646Y361051D01*
X271523Y360927D01*
X270391Y362059D01*
X270515Y362182D01*
G37*
G36*
G01X262805Y365489D02*
X263590Y365779D01*
X264226Y365143D01*
X263936Y364358D01*
X263813Y364234D01*
X262681Y365366D01*
X262805Y365489D01*
G37*
G36*
G01X260047Y368247D02*
X260832Y368537D01*
X261468Y367901D01*
X261178Y367116D01*
X261055Y366992D01*
X259923Y368124D01*
X260047Y368247D01*
G37*
G36*
G01X265326Y364064D02*
X265676Y364824D01*
X266576D01*
X266926Y364064D01*
Y363889D01*
X265326D01*
Y364064D01*
G37*
G36*
G01X292121Y350100D02*
X292759Y350505D01*
X293512Y350070D01*
X293480Y349315D01*
X293393Y349163D01*
X292033Y349949D01*
X292121Y350100D01*
G37*
G36*
G01X259238Y388566D02*
X258888Y387806D01*
X257988D01*
X257638Y388566D01*
Y388741D01*
X259238D01*
Y388566D01*
G37*
G36*
G01X271989Y376014D02*
X271204Y375724D01*
X270568Y376360D01*
X270858Y377145D01*
X270981Y377269D01*
X272113Y376137D01*
X271989Y376014D01*
G37*
G36*
G01X269988Y377266D02*
X269638Y376506D01*
X268738D01*
X268388Y377266D01*
Y377441D01*
X269988D01*
Y377266D01*
G37*
G36*
G01X264773Y385751D02*
X264013Y386101D01*
Y387001D01*
X264773Y387351D01*
X264948D01*
Y385751D01*
X264773D01*
G37*
G36*
G01Y381851D02*
X264013Y382201D01*
Y383101D01*
X264773Y383451D01*
X264948D01*
Y381851D01*
X264773D01*
G37*
G36*
G01X266240Y378002D02*
X265455Y377712D01*
X264819Y378348D01*
X265109Y379133D01*
X265232Y379257D01*
X266364Y378125D01*
X266240Y378002D01*
G37*
G36*
G01X277406Y372314D02*
X276768Y371909D01*
X276015Y372344D01*
X276047Y373099D01*
X276134Y373251D01*
X277494Y372465D01*
X277406Y372314D01*
G37*
G36*
G01X274011Y374272D02*
X273373Y373867D01*
X272620Y374302D01*
X272652Y375057D01*
X272739Y375209D01*
X274099Y374423D01*
X274011Y374272D01*
G37*
G36*
G01X263138Y388566D02*
X262788Y387806D01*
X261888D01*
X261538Y388566D01*
Y388741D01*
X263138D01*
Y388566D01*
G37*
G36*
G01X280771Y370372D02*
X280133Y369967D01*
X279380Y370402D01*
X279412Y371157D01*
X279499Y371309D01*
X280859Y370523D01*
X280771Y370372D01*
G37*
G36*
G01X287546Y366464D02*
X286908Y366059D01*
X286155Y366494D01*
X286187Y367249D01*
X286274Y367401D01*
X287634Y366615D01*
X287546Y366464D01*
G37*
G36*
G01X284157Y368419D02*
X283519Y368014D01*
X282766Y368449D01*
X282798Y369204D01*
X282885Y369355D01*
X284245Y368570D01*
X284157Y368419D01*
G37*
G36*
G01X290911Y364523D02*
X290273Y364118D01*
X289520Y364553D01*
X289552Y365308D01*
X289639Y365460D01*
X290999Y364675D01*
X290911Y364523D01*
G37*
G36*
G01X257638Y389664D02*
X257988Y390424D01*
X258888D01*
X259238Y389664D01*
Y389489D01*
X257638D01*
Y389664D01*
G37*
G36*
G01X268388Y378364D02*
X268738Y379124D01*
X269638D01*
X269988Y378364D01*
Y378189D01*
X268388D01*
Y378364D01*
G37*
G36*
G01X265871Y387351D02*
X266631Y387001D01*
Y386101D01*
X265871Y385751D01*
X265696D01*
Y387351D01*
X265871D01*
G37*
G36*
G01Y383451D02*
X266631Y383101D01*
Y382201D01*
X265871Y381851D01*
X265696D01*
Y383451D01*
X265871D01*
G37*
G36*
G01X275221Y375450D02*
X275859Y375855D01*
X276612Y375420D01*
X276580Y374665D01*
X276493Y374513D01*
X275133Y375299D01*
X275221Y375450D01*
G37*
G36*
G01X271902Y377696D02*
X272687Y377986D01*
X273323Y377350D01*
X273033Y376565D01*
X272910Y376441D01*
X271778Y377573D01*
X271902Y377696D01*
G37*
G36*
G01X261538Y389664D02*
X261888Y390424D01*
X262788D01*
X263138Y389664D01*
Y389489D01*
X261538D01*
Y389664D01*
G37*
G36*
G01X278592Y373505D02*
X279230Y373910D01*
X279983Y373475D01*
X279951Y372720D01*
X279864Y372568D01*
X278504Y373353D01*
X278592Y373505D01*
G37*
G36*
G01X281981Y371550D02*
X282619Y371955D01*
X283372Y371520D01*
X283340Y370765D01*
X283253Y370613D01*
X281893Y371399D01*
X281981Y371550D01*
G37*
G36*
G01X288732Y367655D02*
X289370Y368060D01*
X290123Y367625D01*
X290091Y366870D01*
X290004Y366718D01*
X288644Y367503D01*
X288732Y367655D01*
G37*
G36*
G01X285367Y369597D02*
X286005Y370002D01*
X286758Y369567D01*
X286726Y368812D01*
X286639Y368661D01*
X285279Y369445D01*
X285367Y369597D01*
G37*
G36*
G01X276204Y384667D02*
X275449Y384635D01*
X275014Y385388D01*
X275419Y386026D01*
X275570Y386114D01*
X276356Y384754D01*
X276204Y384667D01*
G37*
G36*
G01X275497Y389675D02*
X274827Y390025D01*
Y390895D01*
X275497Y391245D01*
X275672D01*
Y389675D01*
X275497D01*
G37*
G36*
G01X280777Y382069D02*
X280139Y381664D01*
X279386Y382099D01*
X279418Y382854D01*
X279505Y383005D01*
X280865Y382220D01*
X280777Y382069D01*
G37*
G36*
G01X284151Y380123D02*
X283513Y379718D01*
X282760Y380153D01*
X282792Y380908D01*
X282879Y381060D01*
X284239Y380275D01*
X284151Y380123D01*
G37*
G36*
G01X287537Y378169D02*
X286899Y377764D01*
X286146Y378199D01*
X286178Y378954D01*
X286265Y379105D01*
X287625Y378320D01*
X287537Y378169D01*
G37*
G36*
G01X290911Y376223D02*
X290273Y375818D01*
X289520Y376253D01*
X289552Y377008D01*
X289639Y377160D01*
X290999Y376375D01*
X290911Y376223D01*
G37*
G36*
G01X275497Y393599D02*
X274827Y393949D01*
Y394819D01*
X275497Y395169D01*
X275672D01*
Y393599D01*
X275497D01*
G37*
G36*
G01X274017Y397669D02*
X273379Y397264D01*
X272626Y397699D01*
X272658Y398454D01*
X272745Y398605D01*
X274105Y397820D01*
X274017Y397669D01*
G37*
G36*
G01X277121Y389295D02*
X277791Y388945D01*
Y388075D01*
X277121Y387725D01*
X276946D01*
Y389295D01*
X277121D01*
G37*
G36*
G01X278601Y385200D02*
X279239Y385605D01*
X279992Y385170D01*
X279960Y384415D01*
X279873Y384263D01*
X278513Y385049D01*
X278601Y385200D01*
G37*
G36*
G01X281987Y383246D02*
X282625Y383651D01*
X283378Y383216D01*
X283346Y382461D01*
X283259Y382309D01*
X281899Y383095D01*
X281987Y383246D01*
G37*
G36*
G01X288747Y379346D02*
X289385Y379751D01*
X290138Y379316D01*
X290106Y378561D01*
X290019Y378409D01*
X288659Y379195D01*
X288747Y379346D01*
G37*
G36*
G01X285361Y381300D02*
X285999Y381705D01*
X286752Y381270D01*
X286720Y380515D01*
X286633Y380363D01*
X285273Y381149D01*
X285361Y381300D01*
G37*
G36*
G01X277121Y393170D02*
X277791Y392820D01*
Y391950D01*
X277121Y391600D01*
X276946D01*
Y393170D01*
X277121D01*
G37*
G36*
G01X277120Y397051D02*
X277790Y396701D01*
Y395831D01*
X277120Y395481D01*
X276946D01*
X276945Y397052D01*
X277120Y397051D01*
G37*
G36*
G01X275227Y398846D02*
X275865Y399251D01*
X276618Y398816D01*
X276587Y398061D01*
X276500Y397910D01*
X275139Y398695D01*
X275227Y398846D01*
G37*
G36*
G01X292121Y377400D02*
X292759Y377805D01*
X293512Y377370D01*
X293480Y376615D01*
X293393Y376463D01*
X292033Y377249D01*
X292121Y377400D01*
G37*
G36*
G01X257575Y344264D02*
X257925Y345024D01*
X258825D01*
X259175Y344264D01*
Y344089D01*
X257575D01*
Y344264D01*
G37*
G36*
G01X254175D02*
X254525Y345024D01*
X255425D01*
X255775Y344264D01*
Y344089D01*
X254175D01*
Y344264D01*
G37*
G36*
G01X260628Y344459D02*
X260338Y345244D01*
X260975Y345880D01*
X261759Y345591D01*
X261883Y345467D01*
X260752Y344335D01*
X260628Y344459D01*
G37*
G36*
G01X268467Y344246D02*
X269105Y344651D01*
X269858Y344216D01*
X269826Y343461D01*
X269739Y343309D01*
X268379Y344095D01*
X268467Y344246D01*
G37*
G36*
G01X265081Y346200D02*
X265719Y346605D01*
X266472Y346170D01*
X266440Y345415D01*
X266353Y345263D01*
X264993Y346049D01*
X265081Y346200D01*
G37*
G36*
G01X271841Y342300D02*
X272479Y342705D01*
X273232Y342270D01*
X273200Y341515D01*
X273113Y341363D01*
X271753Y342149D01*
X271841Y342300D01*
G37*
G36*
G01X277391Y380123D02*
X276753Y379718D01*
X276000Y380153D01*
X276032Y380908D01*
X276119Y381060D01*
X277479Y380275D01*
X277391Y380123D01*
G37*
G36*
G01X272008Y384523D02*
X271451Y385035D01*
X271676Y385875D01*
X272414Y386039D01*
X272583Y385994D01*
X272177Y384477D01*
X272008Y384523D01*
G37*
G36*
G01X274026Y382065D02*
X273388Y381659D01*
X272634Y382094D01*
X272667Y382849D01*
X272754Y383001D01*
X274114Y382216D01*
X274026Y382065D01*
G37*
G36*
G01X272117Y387725D02*
X271447Y388075D01*
Y388945D01*
X272117Y389295D01*
X272292D01*
Y387725D01*
X272117D01*
G37*
G36*
G01X280777Y378169D02*
X280139Y377764D01*
X279386Y378199D01*
X279418Y378954D01*
X279505Y379105D01*
X280865Y378320D01*
X280777Y378169D01*
G37*
G36*
G01X287537Y374269D02*
X286899Y373864D01*
X286146Y374299D01*
X286178Y375054D01*
X286265Y375205D01*
X287625Y374420D01*
X287537Y374269D01*
G37*
G36*
G01X284151Y376223D02*
X283513Y375818D01*
X282760Y376253D01*
X282792Y377008D01*
X282879Y377160D01*
X284239Y376375D01*
X284151Y376223D01*
G37*
G36*
G01X290926Y372314D02*
X290288Y371909D01*
X289535Y372344D01*
X289567Y373099D01*
X289654Y373251D01*
X291014Y372465D01*
X290926Y372314D01*
G37*
G36*
G01X272117Y391600D02*
X271447Y391950D01*
Y392820D01*
X272117Y393170D01*
X272292D01*
Y391600D01*
X272117D01*
G37*
G36*
G01X270646Y395714D02*
X270008Y395309D01*
X269255Y395744D01*
X269287Y396499D01*
X269374Y396651D01*
X270734Y395865D01*
X270646Y395714D01*
G37*
G36*
G01X275212Y383255D02*
X275850Y383660D01*
X276603Y383225D01*
X276571Y382470D01*
X276484Y382318D01*
X275124Y383103D01*
X275212Y383255D01*
G37*
G36*
G01X273741Y387345D02*
X274411Y386995D01*
Y386125D01*
X273741Y385775D01*
X273566D01*
Y387345D01*
X273741D01*
G37*
G36*
G01Y391245D02*
X274411Y390895D01*
Y390025D01*
X273741Y389675D01*
X273566D01*
Y391245D01*
X273741D01*
G37*
G36*
G01X278601Y381300D02*
X279239Y381705D01*
X279992Y381270D01*
X279960Y380515D01*
X279873Y380363D01*
X278513Y381149D01*
X278601Y381300D01*
G37*
G36*
G01X281987Y379346D02*
X282625Y379751D01*
X283378Y379316D01*
X283346Y378561D01*
X283259Y378409D01*
X281899Y379195D01*
X281987Y379346D01*
G37*
G36*
G01X288747Y375446D02*
X289385Y375851D01*
X290138Y375416D01*
X290106Y374661D01*
X290019Y374509D01*
X288659Y375295D01*
X288747Y375446D01*
G37*
G36*
G01X285361Y377400D02*
X285999Y377805D01*
X286752Y377370D01*
X286720Y376615D01*
X286633Y376463D01*
X285273Y377249D01*
X285361Y377400D01*
G37*
G36*
G01X273740Y395143D02*
X274410Y394794D01*
Y393924D01*
X273741Y393574D01*
X273565D01*
Y395144D01*
X273740Y395143D01*
G37*
G36*
G01X271811Y396917D02*
X272448Y397323D01*
X273201Y396888D01*
X273170Y396133D01*
X273082Y395981D01*
X271722Y396766D01*
X271811Y396917D01*
G37*
G36*
G01X292112Y373505D02*
X292750Y373910D01*
X293503Y373475D01*
X293471Y372720D01*
X293384Y372568D01*
X292024Y373353D01*
X292112Y373505D01*
G37*
G36*
G01X290911Y387923D02*
X290273Y387518D01*
X289520Y387953D01*
X289551Y388708D01*
X289638Y388859D01*
X290999Y388074D01*
X290911Y387923D01*
G37*
G36*
G01X289017Y397450D02*
X288347Y397800D01*
Y398670D01*
X289017Y399020D01*
X289192D01*
Y397450D01*
X289017D01*
G37*
G36*
G01Y393599D02*
X288347Y393949D01*
Y394819D01*
X289017Y395169D01*
X289192D01*
Y393599D01*
X289017D01*
G37*
G36*
G01X289018Y389718D02*
X288348Y390068D01*
Y390938D01*
X289018Y391288D01*
X289192D01*
X289193Y389717D01*
X289018Y389718D01*
G37*
G36*
G01X289617Y402050D02*
X288947Y402400D01*
Y403270D01*
X289617Y403620D01*
X289792D01*
Y402050D01*
X289617D01*
G37*
G36*
G01X292121Y389100D02*
X292759Y389505D01*
X293512Y389070D01*
X293480Y388315D01*
X293393Y388163D01*
X292033Y388949D01*
X292121Y389100D01*
G37*
G36*
G01X290641Y393170D02*
X291311Y392820D01*
Y391950D01*
X290641Y391600D01*
X290466D01*
Y393170D01*
X290641D01*
G37*
G36*
G01Y397094D02*
X291311Y396744D01*
Y395874D01*
X290641Y395524D01*
X290466D01*
Y397094D01*
X290641D01*
G37*
G36*
G01X290675Y401883D02*
X291435Y401533D01*
Y400633D01*
X290675Y400283D01*
X290500D01*
Y401883D01*
X290675D01*
G37*
G36*
G01X256621Y361566D02*
X256271Y360806D01*
X255371D01*
X255021Y361566D01*
Y361741D01*
X256621D01*
Y361566D01*
G37*
G36*
G01X252721D02*
X252371Y360806D01*
X251471D01*
X251121Y361566D01*
Y361741D01*
X252721D01*
Y361566D01*
G37*
G36*
G01X260521D02*
X260171Y360806D01*
X259271D01*
X258921Y361566D01*
Y361741D01*
X260521D01*
Y361566D01*
G37*
G36*
G01X274017Y354769D02*
X273379Y354364D01*
X272626Y354799D01*
X272658Y355554D01*
X272745Y355705D01*
X274105Y354920D01*
X274017Y354769D01*
G37*
G36*
G01X280777Y350869D02*
X280139Y350464D01*
X279386Y350899D01*
X279418Y351654D01*
X279505Y351805D01*
X280865Y351020D01*
X280777Y350869D01*
G37*
G36*
G01X277391Y352823D02*
X276753Y352418D01*
X276000Y352853D01*
X276032Y353608D01*
X276119Y353760D01*
X277479Y352975D01*
X277391Y352823D01*
G37*
G36*
G01X268155Y358670D02*
X267808Y357998D01*
X266939Y357995D01*
X266586Y358663D01*
X266584Y358838D01*
X268155Y358845D01*
Y358670D01*
G37*
G36*
G01X270631Y356723D02*
X269993Y356318D01*
X269240Y356753D01*
X269272Y357508D01*
X269359Y357660D01*
X270719Y356875D01*
X270631Y356723D01*
G37*
G36*
G01X284151Y348923D02*
X283513Y348518D01*
X282760Y348953D01*
X282792Y349708D01*
X282879Y349860D01*
X284239Y349075D01*
X284151Y348923D01*
G37*
G36*
G01X287537Y346969D02*
X286899Y346564D01*
X286146Y346999D01*
X286178Y347754D01*
X286265Y347905D01*
X287625Y347120D01*
X287537Y346969D01*
G37*
G36*
G01X290911Y345023D02*
X290273Y344618D01*
X289520Y345053D01*
X289552Y345808D01*
X289639Y345960D01*
X290999Y345175D01*
X290911Y345023D01*
G37*
G36*
G01X264921Y359786D02*
X264571Y359026D01*
X263671D01*
X263321Y359786D01*
Y359961D01*
X264921D01*
Y359786D01*
G37*
G36*
G01X251121Y362664D02*
X251471Y363424D01*
X252371D01*
X252721Y362664D01*
Y362489D01*
X251121D01*
Y362664D01*
G37*
G36*
G01X255021D02*
X255371Y363424D01*
X256271D01*
X256621Y362664D01*
Y362489D01*
X255021D01*
Y362664D01*
G37*
G36*
G01X258921D02*
X259271Y363424D01*
X260171D01*
X260521Y362664D01*
Y362489D01*
X258921D01*
Y362664D01*
G37*
G36*
G01X278601Y354000D02*
X279239Y354405D01*
X279992Y353970D01*
X279960Y353215D01*
X279873Y353063D01*
X278513Y353849D01*
X278601Y354000D01*
G37*
G36*
G01X275227Y355946D02*
X275865Y356351D01*
X276618Y355916D01*
X276586Y355161D01*
X276499Y355009D01*
X275139Y355795D01*
X275227Y355946D01*
G37*
G36*
G01X269412Y359275D02*
X270133Y359502D01*
X270747Y358886D01*
X270521Y358165D01*
X270398Y358042D01*
X269287Y359151D01*
X269412Y359275D01*
G37*
G36*
G01X271716Y358008D02*
X272354Y358413D01*
X273107Y357978D01*
X273075Y357223D01*
X272988Y357072D01*
X271628Y357856D01*
X271716Y358008D01*
G37*
G36*
G01X281987Y352046D02*
X282625Y352451D01*
X283378Y352016D01*
X283346Y351261D01*
X283259Y351109D01*
X281899Y351895D01*
X281987Y352046D01*
G37*
G36*
G01X285361Y350100D02*
X285999Y350505D01*
X286752Y350070D01*
X286720Y349315D01*
X286633Y349163D01*
X285273Y349949D01*
X285361Y350100D01*
G37*
G36*
G01X288747Y348146D02*
X289385Y348551D01*
X290138Y348116D01*
X290106Y347361D01*
X290019Y347209D01*
X288659Y347995D01*
X288747Y348146D01*
G37*
G36*
G01X263321Y360884D02*
X263671Y361644D01*
X264571D01*
X264921Y360884D01*
Y360709D01*
X263321D01*
Y360884D01*
G37*
G36*
G01X265081Y342300D02*
X265719Y342705D01*
X266472Y342270D01*
X266440Y341515D01*
X266353Y341363D01*
X264993Y342149D01*
X265081Y342300D01*
G37*
G36*
G01X256460Y356466D02*
X256110Y355706D01*
X255210D01*
X254860Y356466D01*
Y356641D01*
X256460D01*
Y356466D01*
G37*
G36*
G01X252560D02*
X252210Y355706D01*
X251310D01*
X250960Y356466D01*
Y356641D01*
X252560D01*
Y356466D01*
G37*
G36*
G01X260360D02*
X260010Y355706D01*
X259110D01*
X258760Y356466D01*
Y356641D01*
X260360D01*
Y356466D01*
G37*
G36*
G01X270631Y352823D02*
X269993Y352418D01*
X269240Y352853D01*
X269272Y353608D01*
X269359Y353760D01*
X270719Y352975D01*
X270631Y352823D01*
G37*
G36*
G01X280777Y346969D02*
X280139Y346564D01*
X279386Y346999D01*
X279418Y347754D01*
X279505Y347905D01*
X280865Y347120D01*
X280777Y346969D01*
G37*
G36*
G01X277391Y348923D02*
X276753Y348518D01*
X276000Y348953D01*
X276032Y349708D01*
X276119Y349860D01*
X277479Y349075D01*
X277391Y348923D01*
G37*
G36*
G01X274017Y350869D02*
X273379Y350464D01*
X272626Y350899D01*
X272658Y351654D01*
X272745Y351805D01*
X274105Y351020D01*
X274017Y350869D01*
G37*
G36*
G01X287537Y343069D02*
X286899Y342664D01*
X286146Y343099D01*
X286178Y343854D01*
X286265Y344005D01*
X287625Y343220D01*
X287537Y343069D01*
G37*
G36*
G01X284151Y345023D02*
X283513Y344618D01*
X282760Y345053D01*
X282792Y345808D01*
X282879Y345960D01*
X284239Y345175D01*
X284151Y345023D01*
G37*
G36*
G01X267251Y354772D02*
X266613Y354367D01*
X265860Y354802D01*
X265892Y355557D01*
X265979Y355709D01*
X267339Y354924D01*
X267251Y354772D01*
G37*
G36*
G01X251260Y357564D02*
X251610Y358324D01*
X252510D01*
X252860Y357564D01*
Y357389D01*
X251260D01*
Y357564D01*
G37*
G36*
G01X255160D02*
X255510Y358324D01*
X256410D01*
X256760Y357564D01*
Y357389D01*
X255160D01*
Y357564D01*
G37*
G36*
G01X259060D02*
X259410Y358324D01*
X260310D01*
X260660Y357564D01*
Y357389D01*
X259060D01*
Y357564D01*
G37*
G36*
G01X271841Y354000D02*
X272479Y354405D01*
X273232Y353970D01*
X273200Y353215D01*
X273113Y353063D01*
X271753Y353849D01*
X271841Y354000D01*
G37*
G36*
G01X278601Y350100D02*
X279239Y350505D01*
X279992Y350070D01*
X279960Y349315D01*
X279873Y349163D01*
X278513Y349949D01*
X278601Y350100D01*
G37*
G36*
G01X275227Y352046D02*
X275865Y352451D01*
X276618Y352016D01*
X276586Y351261D01*
X276499Y351109D01*
X275139Y351895D01*
X275227Y352046D01*
G37*
G36*
G01X268467Y355946D02*
X269105Y356351D01*
X269858Y355916D01*
X269826Y355161D01*
X269739Y355009D01*
X268379Y355795D01*
X268467Y355946D01*
G37*
G36*
G01X266065Y357162D02*
X266801Y357332D01*
X267366Y356671D01*
X267086Y355969D01*
X266953Y355856D01*
X265932Y357049D01*
X266065Y357162D01*
G37*
G36*
G01X281987Y348146D02*
X282625Y348551D01*
X283378Y348116D01*
X283346Y347361D01*
X283259Y347209D01*
X281899Y347995D01*
X281987Y348146D01*
G37*
G36*
G01X288747Y344246D02*
X289385Y344651D01*
X290138Y344216D01*
X290106Y343461D01*
X290019Y343309D01*
X288659Y344095D01*
X288747Y344246D01*
G37*
G36*
G01X285361Y346200D02*
X285999Y346605D01*
X286752Y346170D01*
X286720Y345415D01*
X286633Y345263D01*
X285273Y346049D01*
X285361Y346200D01*
G37*
G36*
G01X259603Y371481D02*
X258818Y371191D01*
X258182Y371827D01*
X258472Y372612D01*
X258595Y372736D01*
X259727Y371604D01*
X259603Y371481D01*
G37*
G36*
G01X280777Y358669D02*
X280139Y358264D01*
X279386Y358699D01*
X279418Y359454D01*
X279505Y359605D01*
X280865Y358820D01*
X280777Y358669D01*
G37*
G36*
G01X290911Y352823D02*
X290273Y352418D01*
X289520Y352853D01*
X289552Y353608D01*
X289639Y353760D01*
X290999Y352975D01*
X290911Y352823D01*
G37*
G36*
G01X287537Y354769D02*
X286899Y354364D01*
X286146Y354799D01*
X286178Y355554D01*
X286265Y355705D01*
X287625Y354920D01*
X287537Y354769D01*
G37*
G36*
G01X284151Y356723D02*
X283513Y356318D01*
X282760Y356753D01*
X282792Y357508D01*
X282879Y357660D01*
X284239Y356875D01*
X284151Y356723D01*
G37*
G36*
G01X264719Y366365D02*
X263934Y366075D01*
X263297Y366711D01*
X263587Y367496D01*
X263711Y367620D01*
X264842Y366489D01*
X264719Y366365D01*
G37*
G36*
G01X262361Y368723D02*
X261576Y368433D01*
X260940Y369069D01*
X261230Y369854D01*
X261353Y369978D01*
X262485Y368846D01*
X262361Y368723D01*
G37*
G36*
G01X277391Y360623D02*
X276753Y360218D01*
X276000Y360653D01*
X276032Y361408D01*
X276119Y361560D01*
X277479Y360775D01*
X277391Y360623D01*
G37*
G36*
G01X271174Y363910D02*
X270389Y363620D01*
X269753Y364256D01*
X270043Y365041D01*
X270166Y365165D01*
X271298Y364033D01*
X271174Y363910D01*
G37*
G36*
G01X268348Y365818D02*
X267998Y365058D01*
X267098D01*
X266748Y365818D01*
Y365993D01*
X268348D01*
Y365818D01*
G37*
G36*
G01X254537Y374318D02*
X254887Y375078D01*
X255786D01*
X256136Y374318D01*
X256137Y374143D01*
X254536D01*
X254537Y374318D01*
G37*
G36*
G01X259248Y373388D02*
X260033Y373678D01*
X260669Y373042D01*
X260379Y372257D01*
X260256Y372133D01*
X259124Y373265D01*
X259248Y373388D01*
G37*
G36*
G01X288747Y355946D02*
X289385Y356351D01*
X290138Y355916D01*
X290106Y355161D01*
X290019Y355009D01*
X288659Y355795D01*
X288747Y355946D01*
G37*
G36*
G01X285361Y357900D02*
X285999Y358305D01*
X286752Y357870D01*
X286720Y357115D01*
X286633Y356963D01*
X285273Y357749D01*
X285361Y357900D01*
G37*
G36*
G01X264364Y368273D02*
X265149Y368563D01*
X265785Y367926D01*
X265495Y367141D01*
X265371Y367018D01*
X264240Y368149D01*
X264364Y368273D01*
G37*
G36*
G01X278601Y361800D02*
X279239Y362205D01*
X279992Y361770D01*
X279960Y361015D01*
X279873Y360863D01*
X278513Y361649D01*
X278601Y361800D01*
G37*
G36*
G01X275227Y363746D02*
X275865Y364151D01*
X276618Y363716D01*
X276586Y362961D01*
X276499Y362809D01*
X275139Y363595D01*
X275227Y363746D01*
G37*
G36*
G01X270819Y365817D02*
X271604Y366107D01*
X272240Y365471D01*
X271950Y364686D01*
X271827Y364562D01*
X270695Y365694D01*
X270819Y365817D01*
G37*
G36*
G01X267748Y366916D02*
X268098Y367676D01*
X268998D01*
X269348Y366916D01*
Y366741D01*
X267748D01*
Y366916D01*
G37*
G36*
G01X262006Y370630D02*
X262791Y370920D01*
X263427Y370284D01*
X263137Y369499D01*
X263014Y369375D01*
X261882Y370507D01*
X262006Y370630D01*
G37*
G36*
G01X281987Y359846D02*
X282625Y360251D01*
X283378Y359816D01*
X283346Y359061D01*
X283259Y358909D01*
X281899Y359695D01*
X281987Y359846D01*
G37*
G36*
G01X292121Y354000D02*
X292759Y354405D01*
X293512Y353970D01*
X293480Y353215D01*
X293393Y353063D01*
X292033Y353849D01*
X292121Y354000D01*
G37*
G36*
G01X255309Y351637D02*
X255659Y350967D01*
X256529D01*
X256878Y351637D01*
X256880Y351813D01*
X255309Y351811D01*
Y351637D01*
G37*
G36*
G01X251409D02*
X251759Y350967D01*
X252629D01*
X252978Y351637D01*
X252980Y351813D01*
X251409Y351811D01*
Y351637D01*
G37*
G36*
G01X259209D02*
X259559Y350967D01*
X260429D01*
X260778Y351637D01*
X260780Y351813D01*
X259209Y351811D01*
Y351637D01*
G37*
G36*
G01X280777Y343069D02*
X280139Y342664D01*
X279386Y343099D01*
X279418Y343854D01*
X279505Y344005D01*
X280865Y343220D01*
X280777Y343069D01*
G37*
G36*
G01X277391Y345023D02*
X276753Y344618D01*
X276000Y345053D01*
X276032Y345808D01*
X276119Y345960D01*
X277479Y345175D01*
X277391Y345023D01*
G37*
G36*
G01X274017Y346969D02*
X273379Y346564D01*
X272626Y346999D01*
X272658Y347754D01*
X272745Y347905D01*
X274105Y347120D01*
X274017Y346969D01*
G37*
G36*
G01X270631Y348923D02*
X269993Y348518D01*
X269240Y348953D01*
X269272Y349708D01*
X269359Y349860D01*
X270719Y349075D01*
X270631Y348923D01*
G37*
G36*
G01X267257Y350869D02*
X266619Y350464D01*
X265866Y350899D01*
X265898Y351654D01*
X265985Y351805D01*
X267345Y351020D01*
X267257Y350869D01*
G37*
G36*
G01X278601Y365700D02*
X279239Y366105D01*
X279992Y365670D01*
X279960Y364915D01*
X279873Y364763D01*
X278513Y365549D01*
X278601Y365700D01*
G37*
G36*
G01X275212Y367655D02*
X275850Y368060D01*
X276603Y367625D01*
X276571Y366870D01*
X276484Y366718D01*
X275124Y367503D01*
X275212Y367655D01*
G37*
G36*
G01X270715Y369882D02*
X271500Y370172D01*
X272136Y369536D01*
X271846Y368751D01*
X271723Y368627D01*
X270591Y369759D01*
X270715Y369882D01*
G37*
G36*
G01X288747Y359846D02*
X289385Y360251D01*
X290138Y359816D01*
X290106Y359061D01*
X290019Y358909D01*
X288659Y359695D01*
X288747Y359846D01*
G37*
G36*
G01X265648Y372066D02*
X265998Y372826D01*
X266898D01*
X267248Y372066D01*
Y371891D01*
X265648D01*
Y372066D01*
G37*
G36*
G01X259722Y377075D02*
X260507Y377365D01*
X261143Y376729D01*
X260853Y375944D01*
X260730Y375820D01*
X259598Y376952D01*
X259722Y377075D01*
G37*
G36*
G01X262480Y374318D02*
X263265Y374608D01*
X263901Y373971D01*
X263611Y373186D01*
X263487Y373063D01*
X262356Y374194D01*
X262480Y374318D01*
G37*
G36*
G01X281987Y363746D02*
X282625Y364151D01*
X283378Y363716D01*
X283346Y362961D01*
X283259Y362809D01*
X281899Y363595D01*
X281987Y363746D01*
G37*
G36*
G01X285361Y361800D02*
X285999Y362205D01*
X286752Y361770D01*
X286720Y361015D01*
X286633Y360863D01*
X285273Y361649D01*
X285361Y361800D01*
G37*
G36*
G01X292114Y357904D02*
X292752Y358309D01*
X293505Y357874D01*
X293473Y357119D01*
X293386Y356967D01*
X292026Y357753D01*
X292114Y357904D01*
G37*
G36*
G01X288747Y383246D02*
X289385Y383651D01*
X290138Y383216D01*
X290106Y382461D01*
X290019Y382309D01*
X288659Y383095D01*
X288747Y383246D01*
G37*
G36*
G01X285361Y385200D02*
X285999Y385605D01*
X286752Y385170D01*
X286720Y384415D01*
X286633Y384263D01*
X285273Y385049D01*
X285361Y385200D01*
G37*
G36*
G01X281987Y387146D02*
X282625Y387551D01*
X283378Y387116D01*
X283346Y386361D01*
X283259Y386209D01*
X281899Y386995D01*
X281987Y387146D01*
G37*
G36*
G01X280501Y391245D02*
X281171Y390895D01*
Y390025D01*
X280501Y389675D01*
X280326D01*
Y391245D01*
X280501D01*
G37*
G36*
G01Y395169D02*
X281171Y394819D01*
Y393949D01*
X280501Y393599D01*
X280326D01*
Y395169D01*
X280501D01*
G37*
G36*
G01Y399020D02*
X281171Y398670D01*
Y397800D01*
X280501Y397450D01*
X280326D01*
Y399020D01*
X280501D01*
G37*
G36*
G01X292121Y381300D02*
X292759Y381705D01*
X293512Y381270D01*
X293480Y380515D01*
X293393Y380363D01*
X292033Y381149D01*
X292121Y381300D01*
G37*
G36*
G01X256660Y382636D02*
X256310Y381876D01*
X255410D01*
X255060Y382636D01*
Y382811D01*
X256660D01*
Y382636D01*
G37*
G36*
G01X260560D02*
X260210Y381876D01*
X259310D01*
X258960Y382636D01*
Y382811D01*
X260560D01*
Y382636D01*
G37*
G36*
G01X280786Y366464D02*
X280148Y366059D01*
X279395Y366494D01*
X279427Y367249D01*
X279514Y367401D01*
X280874Y366615D01*
X280786Y366464D01*
G37*
G36*
G01X277397Y368419D02*
X276759Y368014D01*
X276006Y368449D01*
X276038Y369204D01*
X276125Y369355D01*
X277485Y368570D01*
X277397Y368419D01*
G37*
G36*
G01X290911Y360623D02*
X290273Y360218D01*
X289520Y360653D01*
X289552Y361408D01*
X289639Y361560D01*
X290999Y360775D01*
X290911Y360623D01*
G37*
G36*
G01X271407Y371673D02*
X270623Y371383D01*
X269986Y372020D01*
X270276Y372804D01*
X270400Y372928D01*
X271531Y371797D01*
X271407Y371673D01*
G37*
G36*
G01X268296Y373966D02*
X267946Y373206D01*
X267046D01*
X266696Y373966D01*
Y374141D01*
X268296D01*
Y373966D01*
G37*
G36*
G01X264100Y375612D02*
X263314Y375326D01*
X262681Y375965D01*
X262974Y376748D01*
X263098Y376872D01*
X264225Y375735D01*
X264100Y375612D01*
G37*
G36*
G01X261343Y379529D02*
X260583Y379879D01*
Y380779D01*
X261343Y381129D01*
X261518D01*
Y379529D01*
X261343D01*
G37*
G36*
G01X287537Y362569D02*
X286899Y362164D01*
X286146Y362599D01*
X286178Y363354D01*
X286265Y363505D01*
X287625Y362720D01*
X287537Y362569D01*
G37*
G36*
G01X284151Y364523D02*
X283513Y364118D01*
X282760Y364553D01*
X282792Y365308D01*
X282879Y365460D01*
X284239Y364675D01*
X284151Y364523D01*
G37*
G36*
G01X287537Y385969D02*
X286899Y385564D01*
X286146Y385999D01*
X286178Y386754D01*
X286265Y386905D01*
X287625Y386120D01*
X287537Y385969D01*
G37*
G36*
G01X290911Y384023D02*
X290273Y383618D01*
X289520Y384053D01*
X289552Y384808D01*
X289639Y384960D01*
X290999Y384175D01*
X290911Y384023D01*
G37*
G36*
G01X284151Y387923D02*
X283513Y387518D01*
X282760Y387953D01*
X282791Y388708D01*
X282878Y388859D01*
X284239Y388074D01*
X284151Y387923D01*
G37*
G36*
G01X282257Y393599D02*
X281587Y393949D01*
Y394819D01*
X282257Y395169D01*
X282432D01*
Y393599D01*
X282257D01*
G37*
G36*
G01Y397451D02*
X281587Y397801D01*
Y398671D01*
X282257Y399021D01*
X282432D01*
Y397451D01*
X282257D01*
G37*
G36*
G01X282258Y389718D02*
X281588Y390068D01*
Y390938D01*
X282258Y391288D01*
X282432D01*
X282433Y389717D01*
X282258Y389718D01*
G37*
G36*
G01X282793Y401440D02*
X282033Y401790D01*
Y402690D01*
X282793Y403040D01*
X282968D01*
Y401440D01*
X282793D01*
G37*
G36*
G01X259987Y348859D02*
X260337Y349619D01*
X261237D01*
X261587Y348859D01*
Y348684D01*
X259987D01*
Y348859D01*
G37*
G36*
G01X275227Y344246D02*
X275865Y344651D01*
X276618Y344216D01*
X276586Y343461D01*
X276499Y343309D01*
X275139Y344095D01*
X275227Y344246D01*
G37*
G36*
G01X271841Y346200D02*
X272479Y346605D01*
X273232Y346170D01*
X273200Y345415D01*
X273113Y345263D01*
X271753Y346049D01*
X271841Y346200D01*
G37*
G36*
G01X268467Y348146D02*
X269105Y348551D01*
X269858Y348116D01*
X269826Y347361D01*
X269739Y347209D01*
X268379Y347995D01*
X268467Y348146D01*
G37*
G36*
G01X265074Y350104D02*
X265712Y350509D01*
X266465Y350074D01*
X266433Y349319D01*
X266346Y349167D01*
X264986Y349953D01*
X265074Y350104D01*
G37*
G36*
G01X278601Y342300D02*
X279239Y342705D01*
X279992Y342270D01*
X279960Y341515D01*
X279873Y341363D01*
X278513Y342149D01*
X278601Y342300D01*
G37*
G36*
G01X255309Y352745D02*
X255659Y353415D01*
X256529D01*
X256878Y352745D01*
X256880Y352569D01*
X255309Y352571D01*
Y352745D01*
G37*
G36*
G01X251409D02*
X251759Y353415D01*
X252629D01*
X252978Y352745D01*
X252980Y352569D01*
X251409Y352571D01*
Y352745D01*
G37*
G36*
G01X259209D02*
X259559Y353415D01*
X260429D01*
X260778Y352745D01*
X260780Y352569D01*
X259209Y352571D01*
Y352745D01*
G37*
G36*
G01X265074Y354004D02*
X265712Y354409D01*
X266465Y353974D01*
X266433Y353219D01*
X266346Y353067D01*
X264986Y353853D01*
X265074Y354004D01*
G37*
G36*
G01X278601Y346200D02*
X279239Y346605D01*
X279992Y346170D01*
X279960Y345415D01*
X279873Y345263D01*
X278513Y346049D01*
X278601Y346200D01*
G37*
G36*
G01X275227Y348146D02*
X275865Y348551D01*
X276618Y348116D01*
X276586Y347361D01*
X276499Y347209D01*
X275139Y347995D01*
X275227Y348146D01*
G37*
G36*
G01X271841Y350100D02*
X272479Y350505D01*
X273232Y350070D01*
X273200Y349315D01*
X273113Y349163D01*
X271753Y349949D01*
X271841Y350100D01*
G37*
G36*
G01X268467Y352046D02*
X269105Y352451D01*
X269858Y352016D01*
X269826Y351261D01*
X269739Y351109D01*
X268379Y351895D01*
X268467Y352046D01*
G37*
G36*
G01X281987Y344246D02*
X282625Y344651D01*
X283378Y344216D01*
X283346Y343461D01*
X283259Y343309D01*
X281899Y344095D01*
X281987Y344246D01*
G37*
G36*
G01X285361Y342300D02*
X285999Y342705D01*
X286752Y342270D01*
X286720Y341515D01*
X286633Y341363D01*
X285273Y342149D01*
X285361Y342300D01*
G37*
G36*
G01X260075Y375166D02*
X259291Y374876D01*
X258654Y375513D01*
X258944Y376297D01*
X259068Y376421D01*
X260199Y375290D01*
X260075Y375166D01*
G37*
G36*
G01X290911Y356723D02*
X290273Y356318D01*
X289520Y356753D01*
X289552Y357508D01*
X289639Y357660D01*
X290999Y356875D01*
X290911Y356723D01*
G37*
G36*
G01X287537Y358669D02*
X286899Y358264D01*
X286146Y358699D01*
X286178Y359454D01*
X286265Y359605D01*
X287625Y358820D01*
X287537Y358669D01*
G37*
G36*
G01X280777Y362569D02*
X280139Y362164D01*
X279386Y362599D01*
X279418Y363354D01*
X279505Y363505D01*
X280865Y362720D01*
X280777Y362569D01*
G37*
G36*
G01X277391Y364523D02*
X276753Y364118D01*
X276000Y364553D01*
X276032Y365308D01*
X276119Y365460D01*
X277479Y364675D01*
X277391Y364523D01*
G37*
G36*
G01X271068Y367973D02*
X270284Y367683D01*
X269647Y368320D01*
X269937Y369104D01*
X270061Y369228D01*
X271192Y368097D01*
X271068Y367973D01*
G37*
G36*
G01X284151Y360623D02*
X283513Y360218D01*
X282760Y360653D01*
X282792Y361408D01*
X282879Y361560D01*
X284239Y360775D01*
X284151Y360623D01*
G37*
G36*
G01X266448Y370966D02*
X266098Y370206D01*
X265198D01*
X264848Y370966D01*
Y371141D01*
X266448D01*
Y370966D01*
G37*
G36*
G01X262833Y372408D02*
X262048Y372118D01*
X261412Y372755D01*
X261702Y373540D01*
X261826Y373663D01*
X262957Y372532D01*
X262833Y372408D01*
G37*
G36*
G01X280840Y385926D02*
X280202Y385521D01*
X279450Y385955D01*
X279482Y386710D01*
X279568Y386862D01*
X280929Y386077D01*
X280840Y385926D01*
G37*
G36*
G01X278947Y387691D02*
X278277Y388041D01*
Y388910D01*
X278947Y389260D01*
X279121Y389261D01*
X279122Y387690D01*
X278947Y387691D01*
G37*
G36*
G01X284151Y384023D02*
X283513Y383618D01*
X282760Y384053D01*
X282792Y384808D01*
X282879Y384960D01*
X284239Y384175D01*
X284151Y384023D01*
G37*
G36*
G01X287537Y382069D02*
X286899Y381664D01*
X286146Y382099D01*
X286178Y382854D01*
X286265Y383005D01*
X287625Y382220D01*
X287537Y382069D01*
G37*
G36*
G01X290911Y380123D02*
X290273Y379718D01*
X289520Y380153D01*
X289552Y380908D01*
X289639Y381060D01*
X290999Y380275D01*
X290911Y380123D01*
G37*
G36*
G01X278877Y391600D02*
X278207Y391950D01*
Y392820D01*
X278877Y393170D01*
X279052D01*
Y391600D01*
X278877D01*
G37*
G36*
G01Y395524D02*
X278207Y395874D01*
Y396744D01*
X278877Y397094D01*
X279052D01*
Y395524D01*
X278877D01*
G37*
G36*
G01X278843Y400451D02*
X278083Y400801D01*
Y401701D01*
X278843Y402051D01*
X279018D01*
Y400451D01*
X278843D01*
G37*
G36*
G01X255060Y383736D02*
X255410Y384496D01*
X256310D01*
X256660Y383736D01*
Y383561D01*
X255060D01*
Y383736D01*
G37*
G36*
G01X258960D02*
X259310Y384496D01*
X260210D01*
X260560Y383736D01*
Y383561D01*
X258960D01*
Y383736D01*
G37*
G36*
G01X278607Y369597D02*
X279245Y370002D01*
X279998Y369567D01*
X279966Y368812D01*
X279879Y368661D01*
X278519Y369445D01*
X278607Y369597D01*
G37*
G36*
G01X271054Y373582D02*
X271839Y373872D01*
X272475Y373236D01*
X272185Y372451D01*
X272062Y372327D01*
X270930Y373459D01*
X271054Y373582D01*
G37*
G36*
G01X266696Y375066D02*
X267046Y375826D01*
X267946D01*
X268296Y375066D01*
Y374891D01*
X266696D01*
Y375066D01*
G37*
G36*
G01X263755Y377523D02*
X264542Y377809D01*
X265175Y377170D01*
X264882Y376387D01*
X264758Y376263D01*
X263631Y377400D01*
X263755Y377523D01*
G37*
G36*
G01X262443Y381129D02*
X263203Y380779D01*
Y379879D01*
X262443Y379529D01*
X262268D01*
Y381129D01*
X262443D01*
G37*
G36*
G01X275221Y371550D02*
X275859Y371955D01*
X276612Y371520D01*
X276580Y370765D01*
X276493Y370613D01*
X275133Y371399D01*
X275221Y371550D01*
G37*
G36*
G01X281972Y367655D02*
X282610Y368060D01*
X283363Y367625D01*
X283331Y366870D01*
X283244Y366718D01*
X281884Y367503D01*
X281972Y367655D01*
G37*
G36*
G01X288747Y363746D02*
X289385Y364151D01*
X290138Y363716D01*
X290106Y362961D01*
X290019Y362809D01*
X288659Y363595D01*
X288747Y363746D01*
G37*
G36*
G01X285361Y365700D02*
X285999Y366105D01*
X286752Y365670D01*
X286720Y364915D01*
X286633Y364763D01*
X285273Y365549D01*
X285361Y365700D01*
G37*
G36*
G01X292121Y361800D02*
X292759Y362205D01*
X293512Y361770D01*
X293480Y361015D01*
X293393Y360863D01*
X292033Y361649D01*
X292121Y361800D01*
G37*
G36*
G01X288747Y387146D02*
X289385Y387551D01*
X290138Y387116D01*
X290106Y386361D01*
X290019Y386209D01*
X288659Y386995D01*
X288747Y387146D01*
G37*
G36*
G01X285361Y389100D02*
X285999Y389505D01*
X286752Y389070D01*
X286720Y388315D01*
X286633Y388163D01*
X285273Y388949D01*
X285361Y389100D01*
G37*
G36*
G01X283881Y393170D02*
X284551Y392820D01*
Y391950D01*
X283881Y391600D01*
X283706D01*
Y393170D01*
X283881D01*
G37*
G36*
G01Y397094D02*
X284551Y396744D01*
Y395874D01*
X283881Y395524D01*
X283706D01*
Y397094D01*
X283881D01*
G37*
G36*
G01X292121Y385200D02*
X292759Y385605D01*
X293512Y385170D01*
X293480Y384415D01*
X293393Y384263D01*
X292033Y385049D01*
X292121Y385200D01*
G37*
G36*
G01X283893Y403040D02*
X284653Y402690D01*
Y401790D01*
X283893Y401440D01*
X283718D01*
Y403040D01*
X283893D01*
G37*
G36*
G01X261587Y347759D02*
X261237Y346999D01*
X260337D01*
X259987Y347759D01*
Y347934D01*
X261587D01*
Y347759D01*
G37*
G36*
G01X274017Y343069D02*
X273379Y342664D01*
X272626Y343099D01*
X272658Y343854D01*
X272745Y344005D01*
X274105Y343220D01*
X274017Y343069D01*
G37*
G36*
G01X270631Y345023D02*
X269993Y344618D01*
X269240Y345053D01*
X269272Y345808D01*
X269359Y345960D01*
X270719Y345175D01*
X270631Y345023D01*
G37*
G36*
G01X267257Y346969D02*
X266619Y346564D01*
X265866Y346999D01*
X265898Y347754D01*
X265985Y347905D01*
X267345Y347120D01*
X267257Y346969D01*
G37*
G36*
G01X271584Y403058D02*
X270799Y402768D01*
X270163Y403404D01*
X270453Y404189D01*
X270576Y404313D01*
X271708Y403181D01*
X271584Y403058D01*
G37*
G36*
G01X271229Y404965D02*
X272014Y405255D01*
X272650Y404619D01*
X272360Y403834D01*
X272237Y403710D01*
X271105Y404842D01*
X271229Y404965D01*
G37*
G36*
G01X291732Y411715D02*
X290947Y411425D01*
X290310Y412061D01*
X290600Y412846D01*
X290724Y412970D01*
X291855Y411839D01*
X291732Y411715D01*
G37*
G36*
G01X290058Y414937D02*
X290843Y415227D01*
X291479Y414591D01*
X291189Y413806D01*
X291066Y413682D01*
X289934Y414813D01*
X290058Y414937D01*
G37*
G36*
G01X292816Y412179D02*
X293601Y412469D01*
X294237Y411833D01*
X293947Y411048D01*
X293824Y410924D01*
X292692Y412055D01*
X292816Y412179D01*
G37*
G36*
G01X286021Y409068D02*
X285236Y408778D01*
X284600Y409414D01*
X284890Y410199D01*
X285013Y410323D01*
X286145Y409191D01*
X286021Y409068D01*
G37*
G36*
G01X288521Y406568D02*
X287736Y406278D01*
X287100Y406914D01*
X287390Y407699D01*
X287513Y407823D01*
X288645Y406691D01*
X288521Y406568D01*
G37*
G36*
G01X285666Y410975D02*
X286451Y411265D01*
X287087Y410629D01*
X286797Y409844D01*
X286674Y409720D01*
X285542Y410852D01*
X285666Y410975D01*
G37*
G36*
G01X288166Y408475D02*
X288951Y408765D01*
X289587Y408129D01*
X289297Y407344D01*
X289174Y407220D01*
X288042Y408352D01*
X288166Y408475D01*
G37*
G36*
G01X290675Y405783D02*
X291435Y405433D01*
Y404533D01*
X290675Y404183D01*
X290500D01*
Y405783D01*
X290675D01*
G37*
G36*
G01X278512Y404668D02*
X279297Y404958D01*
X279933Y404322D01*
X279643Y403537D01*
X279520Y403413D01*
X278388Y404545D01*
X278512Y404668D01*
G37*
G36*
G01X275754Y407426D02*
X276539Y407716D01*
X277175Y407080D01*
X276885Y406295D01*
X276762Y406171D01*
X275630Y407303D01*
X275754Y407426D01*
G37*
G36*
G01X279945Y407267D02*
X279160Y406977D01*
X278524Y407613D01*
X278814Y408398D01*
X278937Y408522D01*
X280069Y407390D01*
X279945Y407267D01*
G37*
G36*
G01X282703Y404509D02*
X281918Y404219D01*
X281282Y404855D01*
X281572Y405640D01*
X281695Y405764D01*
X282827Y404632D01*
X282703Y404509D01*
G37*
G36*
G01X277107Y404517D02*
X276323Y404227D01*
X275686Y404864D01*
X275976Y405648D01*
X276100Y405772D01*
X277231Y404641D01*
X277107Y404517D01*
G37*
G36*
G01X276869Y411969D02*
X277654Y412259D01*
X278290Y411623D01*
X278000Y410838D01*
X277877Y410714D01*
X276745Y411846D01*
X276869Y411969D01*
G37*
G36*
G01X279627Y409211D02*
X280412Y409501D01*
X281048Y408865D01*
X280758Y408080D01*
X280635Y407956D01*
X279503Y409088D01*
X279627Y409211D01*
G37*
G36*
G01X282385Y406453D02*
X283170Y406743D01*
X283806Y406107D01*
X283516Y405322D01*
X283393Y405198D01*
X282261Y406330D01*
X282385Y406453D01*
G37*
G36*
G01X309837Y216715D02*
X309805Y217470D01*
X310558Y217905D01*
X311196Y217500D01*
X311284Y217348D01*
X309924Y216563D01*
X309837Y216715D01*
G37*
G36*
G01X303078Y212816D02*
X303046Y213571D01*
X303799Y214006D01*
X304437Y213601D01*
X304525Y213450D01*
X303165Y212664D01*
X303078Y212816D01*
G37*
G36*
G01X306457Y214764D02*
X306425Y215519D01*
X307178Y215954D01*
X307816Y215549D01*
X307904Y215397D01*
X306544Y214612D01*
X306457Y214764D01*
G37*
G36*
G01X292938Y206965D02*
X292906Y207720D01*
X293659Y208155D01*
X294297Y207750D01*
X294385Y207598D01*
X293025Y206813D01*
X292938Y206965D01*
G37*
G36*
G01X296327Y208920D02*
X296295Y209675D01*
X297048Y210110D01*
X297686Y209705D01*
X297774Y209554D01*
X296414Y208768D01*
X296327Y208920D01*
G37*
G36*
G01X299698Y210864D02*
X299666Y211619D01*
X300419Y212054D01*
X301057Y211649D01*
X301145Y211497D01*
X299785Y210712D01*
X299698Y210864D01*
G37*
G36*
G01X310385Y215157D02*
X310417Y214402D01*
X309664Y213967D01*
X309026Y214372D01*
X308938Y214523D01*
X310298Y215308D01*
X310385Y215157D01*
G37*
G36*
G01X307006Y213208D02*
X307038Y212453D01*
X306285Y212018D01*
X305647Y212423D01*
X305559Y212574D01*
X306919Y213359D01*
X307006Y213208D01*
G37*
G36*
G01X313765Y217108D02*
X313797Y216353D01*
X313044Y215918D01*
X312406Y216323D01*
X312318Y216474D01*
X313678Y217260D01*
X313765Y217108D01*
G37*
G36*
G01X296866Y207357D02*
X296898Y206602D01*
X296145Y206167D01*
X295507Y206572D01*
X295419Y206723D01*
X296779Y207508D01*
X296866Y207357D01*
G37*
G36*
G01X300246Y209308D02*
X300278Y208553D01*
X299525Y208118D01*
X298887Y208523D01*
X298799Y208674D01*
X300159Y209459D01*
X300246Y209308D01*
G37*
G36*
G01X303620Y211254D02*
X303652Y210499D01*
X302899Y210064D01*
X302261Y210469D01*
X302173Y210620D01*
X303533Y211406D01*
X303620Y211254D01*
G37*
G36*
G01X299692Y214761D02*
X299660Y215516D01*
X300413Y215951D01*
X301051Y215546D01*
X301139Y215395D01*
X299779Y214609D01*
X299692Y214761D01*
G37*
G36*
G01X296318Y212815D02*
X296286Y213570D01*
X297039Y214005D01*
X297677Y213600D01*
X297765Y213448D01*
X296405Y212663D01*
X296318Y212815D01*
G37*
G36*
G01X303078Y216715D02*
X303046Y217470D01*
X303799Y217905D01*
X304437Y217500D01*
X304525Y217348D01*
X303165Y216563D01*
X303078Y216715D01*
G37*
G36*
G01X292932Y210861D02*
X292900Y211616D01*
X293653Y212051D01*
X294291Y211646D01*
X294379Y211495D01*
X293019Y210709D01*
X292932Y210861D01*
G37*
G36*
G01X300246Y213208D02*
X300278Y212453D01*
X299525Y212018D01*
X298887Y212423D01*
X298799Y212574D01*
X300159Y213360D01*
X300246Y213208D01*
G37*
G36*
G01X307000Y217105D02*
X307032Y216350D01*
X306279Y215915D01*
X305641Y216320D01*
X305553Y216471D01*
X306913Y217257D01*
X307000Y217105D01*
G37*
G36*
G01X303620Y215154D02*
X303652Y214399D01*
X302899Y213964D01*
X302261Y214369D01*
X302173Y214520D01*
X303533Y215306D01*
X303620Y215154D01*
G37*
G36*
G01X296860Y211254D02*
X296892Y210499D01*
X296139Y210064D01*
X295501Y210469D01*
X295413Y210620D01*
X296773Y211406D01*
X296860Y211254D01*
G37*
G36*
G01X318273Y206513D02*
X317983Y207298D01*
X318619Y207934D01*
X319404Y207644D01*
X319528Y207521D01*
X318396Y206389D01*
X318273Y206513D01*
G37*
G36*
G01X321073Y209313D02*
X320783Y210098D01*
X321419Y210734D01*
X322204Y210444D01*
X322328Y210321D01*
X321196Y209189D01*
X321073Y209313D01*
G37*
G36*
G01X323692Y214050D02*
X322932Y214400D01*
Y215300D01*
X323692Y215650D01*
X323867D01*
Y214050D01*
X323692D01*
G37*
G36*
G01X324426Y217244D02*
X324136Y218028D01*
X324772Y218665D01*
X325557Y218375D01*
X325681Y218251D01*
X324549Y217120D01*
X324426Y217244D01*
G37*
G36*
G01X320180Y206868D02*
X320470Y206083D01*
X319834Y205447D01*
X319049Y205737D01*
X318925Y205860D01*
X320057Y206992D01*
X320180Y206868D01*
G37*
G36*
G01X322980Y209668D02*
X323270Y208883D01*
X322634Y208247D01*
X321849Y208537D01*
X321725Y208660D01*
X322857Y209792D01*
X322980Y209668D01*
G37*
G36*
G01X324791Y215513D02*
X325552Y215163D01*
Y214263D01*
X324791Y213913D01*
X324617Y213912D01*
Y215513D01*
X324791D01*
G37*
G36*
G01X326549Y217813D02*
X326839Y217029D01*
X326202Y216392D01*
X325418Y216682D01*
X325294Y216806D01*
X326425Y217937D01*
X326549Y217813D01*
G37*
G36*
G01X333434Y196408D02*
X332649Y196118D01*
X332013Y196754D01*
X332303Y197539D01*
X332426Y197663D01*
X333558Y196531D01*
X333434Y196408D01*
G37*
G36*
G01X333519Y201839D02*
X333229Y202624D01*
X333865Y203260D01*
X334650Y202970D01*
X334774Y202847D01*
X333642Y201715D01*
X333519Y201839D01*
G37*
G36*
G01X336303Y205886D02*
X335543Y206236D01*
Y207136D01*
X336303Y207486D01*
X336478D01*
Y205886D01*
X336303D01*
G37*
G36*
G01Y209786D02*
X335543Y210136D01*
Y211036D01*
X336303Y211386D01*
X336478D01*
Y209786D01*
X336303D01*
G37*
G36*
G01X339716Y216149D02*
X339046Y216499D01*
Y217369D01*
X339716Y217719D01*
X339891D01*
Y216149D01*
X339716D01*
G37*
G36*
G01X335427Y202193D02*
X335717Y201408D01*
X335081Y200772D01*
X334296Y201062D01*
X334172Y201185D01*
X335304Y202317D01*
X335427Y202193D01*
G37*
G36*
G01X337403Y209893D02*
X338163Y209543D01*
Y208643D01*
X337403Y208293D01*
X337228D01*
Y209893D01*
X337403D01*
G37*
G36*
G01Y205993D02*
X338163Y205643D01*
Y204743D01*
X337403Y204393D01*
X337228D01*
Y205993D01*
X337403D01*
G37*
G36*
G01X341342Y215756D02*
X342011Y215404D01*
X342008Y214535D01*
X341338Y214187D01*
X341163D01*
X341166Y215757D01*
X341342Y215756D01*
G37*
G36*
G01X306020Y204965D02*
X305730Y205749D01*
X306367Y206386D01*
X307151Y206096D01*
X307275Y205972D01*
X306144Y204841D01*
X306020Y204965D01*
G37*
G36*
G01X308820Y207765D02*
X308530Y208549D01*
X309167Y209186D01*
X309951Y208896D01*
X310075Y208772D01*
X308944Y207641D01*
X308820Y207765D01*
G37*
G36*
G01X318153Y214855D02*
X317863Y215639D01*
X318500Y216276D01*
X319284Y215986D01*
X319408Y215862D01*
X318277Y214731D01*
X318153Y214855D01*
G37*
G36*
G01X320953Y217655D02*
X320663Y218439D01*
X321300Y219076D01*
X322084Y218786D01*
X322208Y218662D01*
X321077Y217531D01*
X320953Y217655D01*
G37*
G36*
G01X310731Y208116D02*
X311021Y207332D01*
X310384Y206695D01*
X309600Y206985D01*
X309476Y207109D01*
X310607Y208240D01*
X310731Y208116D01*
G37*
G36*
G01X318467Y212232D02*
X318757Y211448D01*
X318120Y210811D01*
X317336Y211101D01*
X317212Y211225D01*
X318343Y212356D01*
X318467Y212232D01*
G37*
G36*
G01X320064Y215206D02*
X320354Y214422D01*
X319717Y213785D01*
X318933Y214075D01*
X318809Y214199D01*
X319940Y215330D01*
X320064Y215206D01*
G37*
G36*
G01X322864Y218006D02*
X323154Y217222D01*
X322517Y216585D01*
X321733Y216875D01*
X321609Y216999D01*
X322740Y218130D01*
X322864Y218006D01*
G37*
G36*
G01X307931Y205316D02*
X308221Y204532D01*
X307584Y203895D01*
X306800Y204185D01*
X306676Y204309D01*
X307807Y205440D01*
X307931Y205316D01*
G37*
G36*
G01X328922Y202891D02*
X328632Y203675D01*
X329269Y204312D01*
X330053Y204022D01*
X330177Y203898D01*
X329046Y202767D01*
X328922Y202891D01*
G37*
G36*
G01X328450Y199080D02*
X327690Y199429D01*
Y200330D01*
X328450Y200679D01*
X328625D01*
Y199080D01*
X328450D01*
G37*
G36*
G01X331722Y205691D02*
X331432Y206475D01*
X332069Y207112D01*
X332853Y206822D01*
X332977Y206698D01*
X331846Y205567D01*
X331722Y205691D01*
G37*
G36*
G01X333277Y209119D02*
X332517Y209469D01*
Y210369D01*
X333277Y210719D01*
X333452D01*
Y209119D01*
X333277D01*
G37*
G36*
G01X334388Y213847D02*
X334098Y214631D01*
X334735Y215268D01*
X335519Y214978D01*
X335643Y214854D01*
X334512Y213723D01*
X334388Y213847D01*
G37*
G36*
G01X332258Y204671D02*
X332548Y203887D01*
X331911Y203250D01*
X331127Y203540D01*
X331003Y203664D01*
X332134Y204795D01*
X332258Y204671D01*
G37*
G36*
G01X329549Y200228D02*
X330309Y199879D01*
Y198978D01*
X329549Y198628D01*
X329374D01*
Y200228D01*
X329549D01*
G37*
G36*
G01X336298Y214199D02*
X336588Y213415D01*
X335951Y212778D01*
X335167Y213068D01*
X335043Y213192D01*
X336174Y214323D01*
X336298Y214199D01*
G37*
G36*
G01X334377Y210719D02*
X335137Y210369D01*
Y209469D01*
X334377Y209119D01*
X334202D01*
Y210719D01*
X334377D01*
G37*
G36*
G01X337960Y217719D02*
X338630Y217369D01*
Y216499D01*
X337960Y216149D01*
X337785D01*
Y217719D01*
X337960D01*
G37*
G36*
G01X324925Y206281D02*
X325215Y205497D01*
X324578Y204860D01*
X323794Y205150D01*
X323670Y205274D01*
X324801Y206405D01*
X324925Y206281D01*
G37*
G36*
G01X321994Y200763D02*
X322284Y199979D01*
X321647Y199342D01*
X320863Y199632D01*
X320739Y199756D01*
X321870Y200887D01*
X321994Y200763D01*
G37*
G36*
G01X327725Y209081D02*
X328015Y208297D01*
X327378Y207660D01*
X326594Y207950D01*
X326470Y208074D01*
X327601Y209205D01*
X327725Y209081D01*
G37*
G36*
G01X328173Y214156D02*
X328933Y213806D01*
Y212906D01*
X328173Y212556D01*
X327998D01*
Y214156D01*
X328173D01*
G37*
G36*
G01X330281Y218493D02*
X330686Y217854D01*
X330251Y217101D01*
X329496Y217133D01*
X329344Y217220D01*
X330130Y218580D01*
X330281Y218493D01*
G37*
G36*
G01X300246Y217108D02*
X300278Y216353D01*
X299525Y215918D01*
X298887Y216323D01*
X298799Y216474D01*
X300159Y217260D01*
X300246Y217108D01*
G37*
G36*
G01X296860Y215154D02*
X296892Y214399D01*
X296139Y213964D01*
X295501Y214369D01*
X295413Y214520D01*
X296773Y215306D01*
X296860Y215154D01*
G37*
G36*
G01X326700Y202347D02*
X327460Y201998D01*
Y201097D01*
X326700Y200748D01*
X326525D01*
Y202347D01*
X326700D01*
G37*
G36*
G01X329540Y206214D02*
X329830Y205430D01*
X329193Y204793D01*
X328409Y205083D01*
X328285Y205207D01*
X329416Y206338D01*
X329540Y206214D01*
G37*
G36*
G01X331351Y211363D02*
X332111Y211013D01*
Y210113D01*
X331351Y209763D01*
X331176D01*
Y211363D01*
X331351D01*
G37*
G36*
G01X325316Y208228D02*
X325026Y209013D01*
X325662Y209649D01*
X326447Y209359D01*
X326571Y209236D01*
X325439Y208104D01*
X325316Y208228D01*
G37*
G36*
G01X322416Y205328D02*
X322126Y206113D01*
X322762Y206749D01*
X323547Y206459D01*
X323671Y206336D01*
X322539Y205204D01*
X322416Y205328D01*
G37*
G36*
G01X319585Y199910D02*
X319295Y200695D01*
X319931Y201331D01*
X320716Y201041D01*
X320840Y200918D01*
X319708Y199786D01*
X319585Y199910D01*
G37*
G36*
G01X327073Y212056D02*
X326313Y212406D01*
Y213306D01*
X327073Y213656D01*
X327248D01*
Y212056D01*
X327073D01*
G37*
G36*
G01X328490Y217590D02*
X328085Y218228D01*
X328520Y218982D01*
X329275Y218950D01*
X329427Y218862D01*
X328642Y217503D01*
X328490Y217590D01*
G37*
G36*
G01X296318Y216715D02*
X296286Y217470D01*
X297039Y217905D01*
X297677Y217500D01*
X297765Y217348D01*
X296405Y216563D01*
X296318Y216715D01*
G37*
G36*
G01X292932Y214761D02*
X292900Y215516D01*
X293653Y215951D01*
X294291Y215546D01*
X294379Y215395D01*
X293019Y214609D01*
X292932Y214761D01*
G37*
G36*
G01X325601Y198504D02*
X324841Y198854D01*
Y199753D01*
X325601Y200103D01*
X325776Y200104D01*
Y198503D01*
X325601Y198504D01*
G37*
G36*
G01X327631Y205861D02*
X327341Y206646D01*
X327977Y207282D01*
X328762Y206992D01*
X328886Y206869D01*
X327754Y205737D01*
X327631Y205861D01*
G37*
G36*
G01X330251Y209763D02*
X329491Y210113D01*
Y211013D01*
X330251Y211363D01*
X330426D01*
Y209763D01*
X330251D01*
G37*
G36*
G01X295507Y266246D02*
X296145Y266651D01*
X296898Y266216D01*
X296866Y265461D01*
X296779Y265310D01*
X295419Y266094D01*
X295507Y266246D01*
G37*
G36*
G01X298494Y248057D02*
X299132Y248462D01*
X299885Y248027D01*
X299853Y247272D01*
X299766Y247120D01*
X298406Y247906D01*
X298494Y248057D01*
G37*
G36*
G01X297671Y247523D02*
X297033Y247118D01*
X296280Y247553D01*
X296312Y248308D01*
X296399Y248460D01*
X297759Y247674D01*
X297671Y247523D01*
G37*
G36*
G01X298881Y244800D02*
X299519Y245205D01*
X300272Y244770D01*
X300240Y244015D01*
X300153Y243863D01*
X298793Y244648D01*
X298881Y244800D01*
G37*
G36*
G01X295507Y246746D02*
X296145Y247151D01*
X296898Y246716D01*
X296866Y245961D01*
X296779Y245809D01*
X295419Y246595D01*
X295507Y246746D01*
G37*
G36*
G01X299707Y226470D02*
X299675Y227225D01*
X300428Y227660D01*
X301066Y227255D01*
X301154Y227104D01*
X299794Y226318D01*
X299707Y226470D01*
G37*
G36*
G01X303072Y228412D02*
X303040Y229167D01*
X303793Y229602D01*
X304431Y229197D01*
X304519Y229046D01*
X303159Y228260D01*
X303072Y228412D01*
G37*
G36*
G01X306457Y230365D02*
X306425Y231120D01*
X307178Y231555D01*
X307816Y231150D01*
X307904Y230998D01*
X306544Y230213D01*
X306457Y230365D01*
G37*
G36*
G01X296318Y224515D02*
X296286Y225270D01*
X297039Y225705D01*
X297677Y225300D01*
X297765Y225148D01*
X296405Y224363D01*
X296318Y224515D01*
G37*
G36*
G01X292932Y222561D02*
X292900Y223316D01*
X293653Y223751D01*
X294291Y223346D01*
X294379Y223195D01*
X293019Y222409D01*
X292932Y222561D01*
G37*
G36*
G01X307006Y228807D02*
X307038Y228052D01*
X306285Y227617D01*
X305647Y228022D01*
X305559Y228173D01*
X306919Y228958D01*
X307006Y228807D01*
G37*
G36*
G01X303611Y226849D02*
X303643Y226094D01*
X302890Y225659D01*
X302252Y226064D01*
X302164Y226215D01*
X303524Y227000D01*
X303611Y226849D01*
G37*
G36*
G01X300246Y224908D02*
X300278Y224153D01*
X299525Y223718D01*
X298887Y224123D01*
X298799Y224274D01*
X300159Y225060D01*
X300246Y224908D01*
G37*
G36*
G01X296866Y222957D02*
X296898Y222202D01*
X296145Y221767D01*
X295507Y222172D01*
X295419Y222323D01*
X296779Y223109D01*
X296866Y222957D01*
G37*
G36*
G01X313211Y218661D02*
X313179Y219416D01*
X313932Y219851D01*
X314570Y219446D01*
X314658Y219295D01*
X313298Y218509D01*
X313211Y218661D01*
G37*
G36*
G01X320609Y222100D02*
X320139Y222692D01*
X320493Y223487D01*
X321248Y223534D01*
X321408Y223462D01*
X320769Y222029D01*
X320609Y222100D01*
G37*
G36*
G01X320510Y221037D02*
X320568Y220283D01*
X319830Y219822D01*
X319178Y220205D01*
X319086Y220354D01*
X320417Y221185D01*
X320510Y221037D01*
G37*
G36*
G01X317139Y219054D02*
X317171Y218299D01*
X316418Y217864D01*
X315780Y218269D01*
X315692Y218420D01*
X317052Y219206D01*
X317139Y219054D01*
G37*
G36*
G01X294297Y265069D02*
X293659Y264664D01*
X292906Y265099D01*
X292938Y265854D01*
X293025Y266006D01*
X294385Y265220D01*
X294297Y265069D01*
G37*
G36*
G01X292947Y226470D02*
X292915Y227225D01*
X293668Y227660D01*
X294306Y227255D01*
X294394Y227104D01*
X293034Y226318D01*
X292947Y226470D01*
G37*
G36*
G01X296312Y228412D02*
X296280Y229167D01*
X297033Y229602D01*
X297671Y229197D01*
X297759Y229046D01*
X296399Y228260D01*
X296312Y228412D01*
G37*
G36*
G01X299698Y230365D02*
X299666Y231120D01*
X300419Y231555D01*
X301057Y231150D01*
X301145Y230998D01*
X299785Y230213D01*
X299698Y230365D01*
G37*
G36*
G01X303087Y232320D02*
X303055Y233075D01*
X303808Y233510D01*
X304446Y233105D01*
X304534Y232954D01*
X303174Y232168D01*
X303087Y232320D01*
G37*
G36*
G01X296851Y226849D02*
X296883Y226094D01*
X296130Y225659D01*
X295492Y226064D01*
X295404Y226215D01*
X296764Y227000D01*
X296851Y226849D01*
G37*
G36*
G01X300240Y228804D02*
X300272Y228049D01*
X299519Y227614D01*
X298881Y228019D01*
X298793Y228170D01*
X300153Y228956D01*
X300240Y228804D01*
G37*
G36*
G01X306999Y232703D02*
X307031Y231948D01*
X306278Y231513D01*
X305640Y231918D01*
X305552Y232069D01*
X306912Y232854D01*
X306999Y232703D01*
G37*
G36*
G01X303626Y230757D02*
X303658Y230002D01*
X302905Y229567D01*
X302267Y229972D01*
X302179Y230123D01*
X303539Y230908D01*
X303626Y230757D01*
G37*
G36*
G01X309837Y220615D02*
X309805Y221370D01*
X310558Y221805D01*
X311196Y221400D01*
X311284Y221248D01*
X309924Y220463D01*
X309837Y220615D01*
G37*
G36*
G01X306457Y218664D02*
X306425Y219419D01*
X307178Y219854D01*
X307816Y219449D01*
X307904Y219297D01*
X306544Y218512D01*
X306457Y218664D01*
G37*
G36*
G01X310379Y219054D02*
X310411Y218299D01*
X309658Y217864D01*
X309020Y218269D01*
X308932Y218420D01*
X310292Y219206D01*
X310379Y219054D01*
G37*
G36*
G01X313765Y221008D02*
X313797Y220253D01*
X313044Y219818D01*
X312406Y220223D01*
X312318Y220374D01*
X313678Y221160D01*
X313765Y221008D01*
G37*
G36*
G01X316984Y223872D02*
X316952Y224627D01*
X317705Y225062D01*
X318343Y224657D01*
X318431Y224506D01*
X317071Y223720D01*
X316984Y223872D01*
G37*
G36*
G01X317145Y222957D02*
X317177Y222202D01*
X316424Y221767D01*
X315786Y222172D01*
X315698Y222323D01*
X317058Y223109D01*
X317145Y222957D01*
G37*
G36*
G01X326196Y231724D02*
X325526Y232074D01*
Y232944D01*
X326196Y233294D01*
X326371D01*
Y231724D01*
X326196D01*
G37*
G36*
G01Y235649D02*
X325526Y235999D01*
Y236869D01*
X326196Y237219D01*
X326371D01*
Y235649D01*
X326196D01*
G37*
G36*
G01Y239549D02*
X325526Y239899D01*
Y240769D01*
X326196Y241119D01*
X326371D01*
Y239549D01*
X326196D01*
G37*
G36*
G01Y243449D02*
X325526Y243799D01*
Y244669D01*
X326196Y245019D01*
X326371D01*
Y243449D01*
X326196D01*
G37*
G36*
G01Y247349D02*
X325526Y247699D01*
Y248569D01*
X326196Y248919D01*
X326371D01*
Y247349D01*
X326196D01*
G37*
G36*
G01Y251225D02*
X325526Y251575D01*
Y252445D01*
X326196Y252795D01*
X326371D01*
Y251225D01*
X326196D01*
G37*
G36*
G01X326956Y253971D02*
X326608Y254642D01*
X327107Y255355D01*
X327857Y255257D01*
X328000Y255157D01*
X327100Y253871D01*
X326956Y253971D01*
G37*
G36*
G01X326180Y219315D02*
X325510Y219665D01*
Y220535D01*
X326180Y220885D01*
X326355D01*
Y219315D01*
X326180D01*
G37*
G36*
G01X326196Y223949D02*
X325526Y224299D01*
Y225169D01*
X326196Y225519D01*
X326371D01*
Y223949D01*
X326196D01*
G37*
G36*
G01Y227800D02*
X325526Y228150D01*
Y229020D01*
X326196Y229370D01*
X326371D01*
Y227800D01*
X326196D01*
G37*
G36*
G01X327820Y235220D02*
X328490Y234870D01*
Y234000D01*
X327820Y233650D01*
X327645D01*
Y235220D01*
X327820D01*
G37*
G36*
G01Y239120D02*
X328490Y238770D01*
Y237900D01*
X327820Y237550D01*
X327645D01*
Y239120D01*
X327820D01*
G37*
G36*
G01X327819Y250845D02*
X328489Y250495D01*
Y249625D01*
X327819Y249275D01*
X327644D01*
Y250845D01*
X327819D01*
G37*
G36*
G01X327820Y246920D02*
X328490Y246570D01*
Y245700D01*
X327820Y245350D01*
X327645D01*
Y246920D01*
X327820D01*
G37*
G36*
G01Y243020D02*
X328490Y242670D01*
Y241800D01*
X327820Y241450D01*
X327645D01*
Y243020D01*
X327820D01*
G37*
G36*
G01X328738Y258283D02*
X329437Y258571D01*
X330103Y258012D01*
X329941Y257273D01*
X329828Y257139D01*
X328626Y258149D01*
X328738Y258283D01*
G37*
G36*
G01X327387Y261160D02*
X326914Y261750D01*
X327263Y262546D01*
X328018Y262599D01*
X328178Y262528D01*
X327547Y261090D01*
X327387Y261160D01*
G37*
G36*
G01X327820Y223520D02*
X328490Y223170D01*
Y222300D01*
X327820Y221950D01*
X327645D01*
Y223520D01*
X327820D01*
G37*
G36*
G01Y227445D02*
X328490Y227095D01*
Y226225D01*
X327820Y225875D01*
X327645D01*
Y227445D01*
X327820D01*
G37*
G36*
G01Y231369D02*
X328490Y231019D01*
Y230149D01*
X327820Y229799D01*
X327645D01*
Y231369D01*
X327820D01*
G37*
G36*
G01X339716Y231724D02*
X339046Y232074D01*
Y232944D01*
X339716Y233294D01*
X339891D01*
Y231724D01*
X339716D01*
G37*
G36*
G01Y239549D02*
X339046Y239899D01*
Y240769D01*
X339716Y241119D01*
X339891D01*
Y239549D01*
X339716D01*
G37*
G36*
G01Y235649D02*
X339046Y235999D01*
Y236869D01*
X339716Y237219D01*
X339891D01*
Y235649D01*
X339716D01*
G37*
G36*
G01Y251249D02*
X339046Y251599D01*
Y252469D01*
X339716Y252819D01*
X339891D01*
Y251249D01*
X339716D01*
G37*
G36*
G01Y247349D02*
X339046Y247699D01*
Y248569D01*
X339716Y248919D01*
X339891D01*
Y247349D01*
X339716D01*
G37*
G36*
G01Y243449D02*
X339046Y243799D01*
Y244669D01*
X339716Y245019D01*
X339891D01*
Y243449D01*
X339716D01*
G37*
G36*
G01Y220049D02*
X339046Y220399D01*
Y221269D01*
X339716Y221619D01*
X339891D01*
Y220049D01*
X339716D01*
G37*
G36*
G01Y223949D02*
X339046Y224299D01*
Y225169D01*
X339716Y225519D01*
X339891D01*
Y223949D01*
X339716D01*
G37*
G36*
G01Y227800D02*
X339046Y228150D01*
Y229020D01*
X339716Y229370D01*
X339891D01*
Y227800D01*
X339716D01*
G37*
G36*
G01X341340Y235220D02*
X342010Y234870D01*
Y234000D01*
X341340Y233650D01*
X341165D01*
Y235220D01*
X341340D01*
G37*
G36*
G01Y239120D02*
X342010Y238770D01*
Y237900D01*
X341340Y237550D01*
X341165D01*
Y239120D01*
X341340D01*
G37*
G36*
G01Y243020D02*
X342010Y242670D01*
Y241800D01*
X341340Y241450D01*
X341165D01*
Y243020D01*
X341340D01*
G37*
G36*
G01Y246920D02*
X342010Y246570D01*
Y245700D01*
X341340Y245350D01*
X341165D01*
Y246920D01*
X341340D01*
G37*
G36*
G01Y250820D02*
X342010Y250470D01*
Y249600D01*
X341340Y249250D01*
X341165D01*
Y250820D01*
X341340D01*
G37*
G36*
G01Y254720D02*
X342010Y254370D01*
Y253500D01*
X341340Y253150D01*
X341165D01*
Y254720D01*
X341340D01*
G37*
G36*
G01Y258620D02*
X342010Y258270D01*
Y257400D01*
X341340Y257050D01*
X341165D01*
Y258620D01*
X341340D01*
G37*
G36*
G01Y219620D02*
X342010Y219270D01*
Y218400D01*
X341340Y218050D01*
X341165D01*
Y219620D01*
X341340D01*
G37*
G36*
G01Y223520D02*
X342010Y223170D01*
Y222300D01*
X341340Y221950D01*
X341165D01*
Y223520D01*
X341340D01*
G37*
G36*
G01Y227445D02*
X342010Y227095D01*
Y226225D01*
X341340Y225875D01*
X341165D01*
Y227445D01*
X341340D01*
G37*
G36*
G01Y231369D02*
X342010Y231019D01*
Y230149D01*
X341340Y229799D01*
X341165D01*
Y231369D01*
X341340D01*
G37*
G36*
G01X322816Y225875D02*
X322146Y226225D01*
Y227095D01*
X322816Y227445D01*
X322991D01*
Y225875D01*
X322816D01*
G37*
G36*
G01Y221950D02*
X322146Y222300D01*
Y223170D01*
X322816Y223520D01*
X322991D01*
Y221950D01*
X322816D01*
G37*
G36*
G01Y229799D02*
X322146Y230149D01*
Y231019D01*
X322816Y231369D01*
X322991D01*
Y229799D01*
X322816D01*
G37*
G36*
G01Y233650D02*
X322146Y234000D01*
Y234870D01*
X322816Y235220D01*
X322991D01*
Y233650D01*
X322816D01*
G37*
G36*
G01Y237550D02*
X322146Y237900D01*
Y238770D01*
X322816Y239120D01*
X322991D01*
Y237550D01*
X322816D01*
G37*
G36*
G01Y241450D02*
X322146Y241800D01*
Y242670D01*
X322816Y243020D01*
X322991D01*
Y241450D01*
X322816D01*
G37*
G36*
G01Y245350D02*
X322146Y245700D01*
Y246570D01*
X322816Y246920D01*
X322991D01*
Y245350D01*
X322816D01*
G37*
G36*
G01Y249250D02*
X322146Y249600D01*
Y250470D01*
X322816Y250820D01*
X322991D01*
Y249250D01*
X322816D01*
G37*
G36*
G01Y253150D02*
X322146Y253500D01*
Y254370D01*
X322816Y254720D01*
X322991D01*
Y253150D01*
X322816D01*
G37*
G36*
G01X324440Y221594D02*
X325110Y221244D01*
Y220374D01*
X324440Y220024D01*
X324265D01*
Y221594D01*
X324440D01*
G37*
G36*
G01Y225519D02*
X325110Y225169D01*
Y224299D01*
X324440Y223949D01*
X324265D01*
Y225519D01*
X324440D01*
G37*
G36*
G01Y229370D02*
X325110Y229020D01*
Y228150D01*
X324440Y227800D01*
X324265D01*
Y229370D01*
X324440D01*
G37*
G36*
G01Y233294D02*
X325110Y232944D01*
Y232074D01*
X324440Y231724D01*
X324265D01*
Y233294D01*
X324440D01*
G37*
G36*
G01Y237219D02*
X325110Y236869D01*
Y235999D01*
X324440Y235649D01*
X324265D01*
Y237219D01*
X324440D01*
G37*
G36*
G01Y241119D02*
X325110Y240769D01*
Y239899D01*
X324440Y239549D01*
X324265D01*
Y241119D01*
X324440D01*
G37*
G36*
G01Y245019D02*
X325110Y244669D01*
Y243799D01*
X324440Y243449D01*
X324265D01*
Y245019D01*
X324440D01*
G37*
G36*
G01Y248919D02*
X325110Y248569D01*
Y247699D01*
X324440Y247349D01*
X324265D01*
Y248919D01*
X324440D01*
G37*
G36*
G01Y252819D02*
X325110Y252469D01*
Y251599D01*
X324440Y251249D01*
X324265D01*
Y252819D01*
X324440D01*
G37*
G36*
G01X336336Y233650D02*
X335666Y234000D01*
Y234870D01*
X336336Y235220D01*
X336511D01*
Y233650D01*
X336336D01*
G37*
G36*
G01Y237550D02*
X335666Y237900D01*
Y238770D01*
X336336Y239120D01*
X336511D01*
Y237550D01*
X336336D01*
G37*
G36*
G01X336337Y249275D02*
X335667Y249625D01*
Y250495D01*
X336337Y250845D01*
X336512D01*
Y249275D01*
X336337D01*
G37*
G36*
G01X336336Y245350D02*
X335666Y245700D01*
Y246570D01*
X336336Y246920D01*
X336511D01*
Y245350D01*
X336336D01*
G37*
G36*
G01Y241450D02*
X335666Y241800D01*
Y242670D01*
X336336Y243020D01*
X336511D01*
Y241450D01*
X336336D01*
G37*
G36*
G01Y218099D02*
X335666Y218449D01*
Y219319D01*
X336336Y219669D01*
X336511D01*
Y218099D01*
X336336D01*
G37*
G36*
G01Y221950D02*
X335666Y222300D01*
Y223170D01*
X336336Y223520D01*
X336511D01*
Y221950D01*
X336336D01*
G37*
G36*
G01Y225875D02*
X335666Y226225D01*
Y227095D01*
X336336Y227445D01*
X336511D01*
Y225875D01*
X336336D01*
G37*
G36*
G01Y229799D02*
X335666Y230149D01*
Y231019D01*
X336336Y231369D01*
X336511D01*
Y229799D01*
X336336D01*
G37*
G36*
G01X337960Y233294D02*
X338630Y232944D01*
Y232074D01*
X337960Y231724D01*
X337785D01*
Y233294D01*
X337960D01*
G37*
G36*
G01Y241119D02*
X338630Y240769D01*
Y239899D01*
X337960Y239549D01*
X337785D01*
Y241119D01*
X337960D01*
G37*
G36*
G01Y237219D02*
X338630Y236869D01*
Y235999D01*
X337960Y235649D01*
X337785D01*
Y237219D01*
X337960D01*
G37*
G36*
G01Y252795D02*
X338630Y252445D01*
Y251575D01*
X337960Y251225D01*
X337785D01*
Y252795D01*
X337960D01*
G37*
G36*
G01Y248919D02*
X338630Y248569D01*
Y247699D01*
X337960Y247349D01*
X337785D01*
Y248919D01*
X337960D01*
G37*
G36*
G01Y245019D02*
X338630Y244669D01*
Y243799D01*
X337960Y243449D01*
X337785D01*
Y245019D01*
X337960D01*
G37*
G36*
G01Y256695D02*
X338630Y256345D01*
Y255475D01*
X337960Y255125D01*
X337785D01*
Y256695D01*
X337960D01*
G37*
G36*
G01Y221619D02*
X338630Y221269D01*
Y220399D01*
X337960Y220049D01*
X337785D01*
Y221619D01*
X337960D01*
G37*
G36*
G01Y225519D02*
X338630Y225169D01*
Y224299D01*
X337960Y223949D01*
X337785D01*
Y225519D01*
X337960D01*
G37*
G36*
G01Y229370D02*
X338630Y229020D01*
Y228150D01*
X337960Y227800D01*
X337785D01*
Y229370D01*
X337960D01*
G37*
G36*
G01X295507Y270146D02*
X296145Y270551D01*
X296898Y270116D01*
X296866Y269361D01*
X296779Y269210D01*
X295419Y269994D01*
X295507Y270146D01*
G37*
G36*
G01X294297Y268969D02*
X293659Y268564D01*
X292906Y268999D01*
X292938Y269754D01*
X293025Y269906D01*
X294385Y269120D01*
X294297Y268969D01*
G37*
G36*
G01X297671Y267023D02*
X297033Y266618D01*
X296280Y267053D01*
X296312Y267808D01*
X296399Y267960D01*
X297759Y267174D01*
X297671Y267023D01*
G37*
G36*
G01X294297Y253369D02*
X293659Y252964D01*
X292906Y253399D01*
X292938Y254154D01*
X293025Y254306D01*
X294385Y253520D01*
X294297Y253369D01*
G37*
G36*
G01X295121Y253903D02*
X295759Y254308D01*
X296512Y253873D01*
X296480Y253118D01*
X296393Y252966D01*
X295033Y253752D01*
X295121Y253903D01*
G37*
G36*
G01X295507Y242846D02*
X296145Y243251D01*
X296898Y242816D01*
X296866Y242061D01*
X296779Y241909D01*
X295419Y242695D01*
X295507Y242846D01*
G37*
G36*
G01X294304Y257265D02*
X293666Y256860D01*
X292913Y257295D01*
X292945Y258050D01*
X293032Y258202D01*
X294392Y257416D01*
X294304Y257265D01*
G37*
G36*
G01X297671Y255323D02*
X297033Y254918D01*
X296280Y255353D01*
X296312Y256108D01*
X296399Y256260D01*
X297759Y255474D01*
X297671Y255323D01*
G37*
G36*
G01X300246Y221008D02*
X300278Y220253D01*
X299525Y219818D01*
X298887Y220223D01*
X298799Y220374D01*
X300159Y221160D01*
X300246Y221008D01*
G37*
G36*
G01X296860Y219054D02*
X296892Y218299D01*
X296139Y217864D01*
X295501Y218269D01*
X295413Y218420D01*
X296773Y219206D01*
X296860Y219054D01*
G37*
G36*
G01X307006Y224908D02*
X307038Y224153D01*
X306285Y223718D01*
X305647Y224123D01*
X305559Y224274D01*
X306919Y225060D01*
X307006Y224908D01*
G37*
G36*
G01X303626Y222957D02*
X303658Y222202D01*
X302905Y221767D01*
X302267Y222172D01*
X302179Y222323D01*
X303539Y223109D01*
X303626Y222957D01*
G37*
G36*
G01X331200Y233294D02*
X331870Y232944D01*
Y232074D01*
X331200Y231724D01*
X331025D01*
Y233294D01*
X331200D01*
G37*
G36*
G01Y237219D02*
X331870Y236869D01*
Y235999D01*
X331200Y235649D01*
X331025D01*
Y237219D01*
X331200D01*
G37*
G36*
G01Y241119D02*
X331870Y240769D01*
Y239899D01*
X331200Y239549D01*
X331025D01*
Y241119D01*
X331200D01*
G37*
G36*
G01Y245019D02*
X331870Y244669D01*
Y243799D01*
X331200Y243449D01*
X331025D01*
Y245019D01*
X331200D01*
G37*
G36*
G01Y248919D02*
X331870Y248569D01*
Y247699D01*
X331200Y247349D01*
X331025D01*
Y248919D01*
X331200D01*
G37*
G36*
G01Y221619D02*
X331870Y221269D01*
Y220399D01*
X331200Y220049D01*
X331025D01*
Y221619D01*
X331200D01*
G37*
G36*
G01Y225519D02*
X331870Y225169D01*
Y224299D01*
X331200Y223949D01*
X331025D01*
Y225519D01*
X331200D01*
G37*
G36*
G01Y229370D02*
X331870Y229020D01*
Y228150D01*
X331200Y227800D01*
X331025D01*
Y229370D01*
X331200D01*
G37*
G36*
G01X301057Y233869D02*
X300419Y233464D01*
X299666Y233899D01*
X299698Y234654D01*
X299785Y234806D01*
X301145Y234020D01*
X301057Y233869D01*
G37*
G36*
G01X297671Y235823D02*
X297033Y235418D01*
X296280Y235853D01*
X296312Y236608D01*
X296399Y236760D01*
X297759Y235974D01*
X297671Y235823D01*
G37*
G36*
G01X310379Y222954D02*
X310411Y222199D01*
X309658Y221764D01*
X309020Y222169D01*
X308932Y222320D01*
X310292Y223106D01*
X310379Y222954D01*
G37*
G36*
G01X303620Y219054D02*
X303652Y218299D01*
X302899Y217864D01*
X302261Y218269D01*
X302173Y218420D01*
X303533Y219206D01*
X303620Y219054D01*
G37*
G36*
G01X307000Y221005D02*
X307032Y220250D01*
X306279Y219815D01*
X305641Y220220D01*
X305553Y220371D01*
X306913Y221157D01*
X307000Y221005D01*
G37*
G36*
G01X313765Y224908D02*
X313797Y224153D01*
X313044Y223718D01*
X312406Y224123D01*
X312318Y224274D01*
X313678Y225060D01*
X313765Y224908D01*
G37*
G36*
G01X317130Y226849D02*
X317162Y226094D01*
X316409Y225659D01*
X315771Y226064D01*
X315683Y226215D01*
X317043Y227000D01*
X317130Y226849D01*
G37*
G36*
G01X334580Y235220D02*
X335250Y234870D01*
Y234000D01*
X334580Y233650D01*
X334405D01*
Y235220D01*
X334580D01*
G37*
G36*
G01Y239120D02*
X335250Y238770D01*
Y237900D01*
X334580Y237550D01*
X334405D01*
Y239120D01*
X334580D01*
G37*
G36*
G01Y250820D02*
X335250Y250470D01*
Y249600D01*
X334580Y249250D01*
X334405D01*
Y250820D01*
X334580D01*
G37*
G36*
G01Y246920D02*
X335250Y246570D01*
Y245700D01*
X334580Y245350D01*
X334405D01*
Y246920D01*
X334580D01*
G37*
G36*
G01Y243020D02*
X335250Y242670D01*
Y241800D01*
X334580Y241450D01*
X334405D01*
Y243020D01*
X334580D01*
G37*
G36*
G01Y254720D02*
X335250Y254370D01*
Y253500D01*
X334580Y253150D01*
X334405D01*
Y254720D01*
X334580D01*
G37*
G36*
G01Y258620D02*
X335250Y258270D01*
Y257400D01*
X334580Y257050D01*
X334405D01*
Y258620D01*
X334580D01*
G37*
G36*
G01X334564Y262559D02*
X335240Y262219D01*
X335254Y261350D01*
X334589Y260990D01*
X334415Y260987D01*
X334389Y262556D01*
X334564Y262559D01*
G37*
G36*
G01X334580Y219620D02*
X335250Y219270D01*
Y218400D01*
X334580Y218050D01*
X334405D01*
Y219620D01*
X334580D01*
G37*
G36*
G01Y223520D02*
X335250Y223170D01*
Y222300D01*
X334580Y221950D01*
X334405D01*
Y223520D01*
X334580D01*
G37*
G36*
G01Y227445D02*
X335250Y227095D01*
Y226225D01*
X334580Y225875D01*
X334405D01*
Y227445D01*
X334580D01*
G37*
G36*
G01Y231369D02*
X335250Y231019D01*
Y230149D01*
X334580Y229799D01*
X334405D01*
Y231369D01*
X334580D01*
G37*
G36*
G01X295507Y258446D02*
X296145Y258851D01*
X296898Y258416D01*
X296866Y257661D01*
X296779Y257509D01*
X295419Y258295D01*
X295507Y258446D01*
G37*
G36*
G01X298881Y256500D02*
X299519Y256905D01*
X300272Y256470D01*
X300240Y255715D01*
X300153Y255563D01*
X298793Y256348D01*
X298881Y256500D01*
G37*
G36*
G01X306500Y226489D02*
X306468Y227244D01*
X307221Y227679D01*
X307859Y227274D01*
X307947Y227123D01*
X306587Y226338D01*
X306500Y226489D01*
G37*
G36*
G01X296318Y220615D02*
X296286Y221370D01*
X297039Y221805D01*
X297677Y221400D01*
X297765Y221249D01*
X296405Y220463D01*
X296318Y220615D01*
G37*
G36*
G01X299698Y222564D02*
X299666Y223319D01*
X300419Y223754D01*
X301057Y223349D01*
X301145Y223198D01*
X299785Y222412D01*
X299698Y222564D01*
G37*
G36*
G01X292938Y218664D02*
X292906Y219419D01*
X293659Y219854D01*
X294297Y219449D01*
X294385Y219298D01*
X293025Y218512D01*
X292938Y218664D01*
G37*
G36*
G01X303078Y224515D02*
X303046Y225270D01*
X303799Y225705D01*
X304437Y225300D01*
X304525Y225149D01*
X303165Y224363D01*
X303078Y224515D01*
G37*
G36*
G01X329576Y233650D02*
X328906Y234000D01*
Y234870D01*
X329576Y235220D01*
X329751D01*
Y233650D01*
X329576D01*
G37*
G36*
G01Y237550D02*
X328906Y237900D01*
Y238770D01*
X329576Y239120D01*
X329751D01*
Y237550D01*
X329576D01*
G37*
G36*
G01Y241450D02*
X328906Y241800D01*
Y242670D01*
X329576Y243020D01*
X329751D01*
Y241450D01*
X329576D01*
G37*
G36*
G01Y245350D02*
X328906Y245700D01*
Y246570D01*
X329576Y246920D01*
X329751D01*
Y245350D01*
X329576D01*
G37*
G36*
G01Y249250D02*
X328906Y249600D01*
Y250470D01*
X329576Y250820D01*
X329751D01*
Y249250D01*
X329576D01*
G37*
G36*
G01Y221950D02*
X328906Y222300D01*
Y223170D01*
X329576Y223520D01*
X329751D01*
Y221950D01*
X329576D01*
G37*
G36*
G01Y225875D02*
X328906Y226225D01*
Y227095D01*
X329576Y227445D01*
X329751D01*
Y225875D01*
X329576D01*
G37*
G36*
G01Y229799D02*
X328906Y230149D01*
Y231019D01*
X329576Y231369D01*
X329751D01*
Y229799D01*
X329576D01*
G37*
G36*
G01X292932Y238161D02*
X292900Y238916D01*
X293653Y239351D01*
X294291Y238946D01*
X294379Y238795D01*
X293019Y238009D01*
X292932Y238161D01*
G37*
G36*
G01X295507Y238946D02*
X296145Y239351D01*
X296898Y238916D01*
X296866Y238161D01*
X296779Y238009D01*
X295419Y238795D01*
X295507Y238946D01*
G37*
G36*
G01X298881Y237000D02*
X299519Y237405D01*
X300272Y236970D01*
X300240Y236215D01*
X300153Y236063D01*
X298793Y236848D01*
X298881Y237000D01*
G37*
G36*
G01X299692Y218661D02*
X299660Y219416D01*
X300413Y219851D01*
X301051Y219446D01*
X301139Y219295D01*
X299779Y218509D01*
X299692Y218661D01*
G37*
G36*
G01X309837Y224515D02*
X309805Y225270D01*
X310558Y225705D01*
X311196Y225300D01*
X311284Y225148D01*
X309924Y224363D01*
X309837Y224515D01*
G37*
G36*
G01X306457Y222564D02*
X306425Y223319D01*
X307178Y223754D01*
X307816Y223349D01*
X307904Y223197D01*
X306544Y222412D01*
X306457Y222564D01*
G37*
G36*
G01X303072Y220612D02*
X303040Y221367D01*
X303793Y221802D01*
X304431Y221397D01*
X304519Y221246D01*
X303159Y220460D01*
X303072Y220612D01*
G37*
G36*
G01X313226Y226470D02*
X313194Y227225D01*
X313947Y227660D01*
X314585Y227255D01*
X314673Y227104D01*
X313313Y226318D01*
X313226Y226470D01*
G37*
G36*
G01X316591Y228412D02*
X316559Y229167D01*
X317312Y229602D01*
X317950Y229197D01*
X318038Y229046D01*
X316678Y228260D01*
X316591Y228412D01*
G37*
G36*
G01X332956Y231724D02*
X332286Y232074D01*
Y232944D01*
X332956Y233294D01*
X333131D01*
Y231724D01*
X332956D01*
G37*
G36*
G01Y239549D02*
X332286Y239899D01*
Y240769D01*
X332956Y241119D01*
X333131D01*
Y239549D01*
X332956D01*
G37*
G36*
G01Y235649D02*
X332286Y235999D01*
Y236869D01*
X332956Y237219D01*
X333131D01*
Y235649D01*
X332956D01*
G37*
G36*
G01Y251249D02*
X332286Y251599D01*
Y252469D01*
X332956Y252819D01*
X333131D01*
Y251249D01*
X332956D01*
G37*
G36*
G01Y247349D02*
X332286Y247699D01*
Y248569D01*
X332956Y248919D01*
X333131D01*
Y247349D01*
X332956D01*
G37*
G36*
G01Y243449D02*
X332286Y243799D01*
Y244669D01*
X332956Y245019D01*
X333131D01*
Y243449D01*
X332956D01*
G37*
G36*
G01Y255149D02*
X332286Y255499D01*
Y256369D01*
X332956Y256719D01*
X333131D01*
Y255149D01*
X332956D01*
G37*
G36*
G01Y259049D02*
X332286Y259399D01*
Y260269D01*
X332956Y260619D01*
X333131D01*
Y259049D01*
X332956D01*
G37*
G36*
G01Y227800D02*
X332286Y228150D01*
Y229020D01*
X332956Y229370D01*
X333131D01*
Y227800D01*
X332956D01*
G37*
G36*
G01Y220049D02*
X332286Y220399D01*
Y221269D01*
X332956Y221619D01*
X333131D01*
Y220049D01*
X332956D01*
G37*
G36*
G01Y223949D02*
X332286Y224299D01*
Y225169D01*
X332956Y225519D01*
X333131D01*
Y223949D01*
X332956D01*
G37*
G36*
G01X296860Y332154D02*
X296892Y331399D01*
X296139Y330964D01*
X295501Y331369D01*
X295413Y331520D01*
X296773Y332305D01*
X296860Y332154D01*
G37*
G36*
G01X300246Y334108D02*
X300278Y333353D01*
X299525Y332918D01*
X298887Y333323D01*
X298799Y333475D01*
X300159Y334260D01*
X300246Y334108D01*
G37*
G36*
G01X292932Y331761D02*
X292900Y332516D01*
X293653Y332951D01*
X294291Y332546D01*
X294379Y332395D01*
X293019Y331609D01*
X292932Y331761D01*
G37*
G36*
G01X340467Y340944D02*
X339797Y341294D01*
Y342164D01*
X340467Y342514D01*
X340642D01*
Y340944D01*
X340467D01*
G37*
G36*
G01X326196Y340949D02*
X325526Y341299D01*
Y342169D01*
X326196Y342519D01*
X326371D01*
Y340949D01*
X326196D01*
G37*
G36*
G01X337087Y338955D02*
X336417Y339305D01*
Y340175D01*
X337087Y340525D01*
X337262D01*
Y338955D01*
X337087D01*
G37*
G36*
G01X337960Y342519D02*
X338630Y342169D01*
Y341299D01*
X337960Y340949D01*
X337785D01*
Y342519D01*
X337960D01*
G37*
G36*
G01X296860Y328254D02*
X296892Y327499D01*
X296139Y327064D01*
X295501Y327469D01*
X295413Y327620D01*
X296773Y328405D01*
X296860Y328254D01*
G37*
G36*
G01X303620Y332154D02*
X303652Y331399D01*
X302899Y330964D01*
X302261Y331369D01*
X302173Y331520D01*
X303533Y332305D01*
X303620Y332154D01*
G37*
G36*
G01X300246Y330208D02*
X300278Y329453D01*
X299525Y329018D01*
X298887Y329423D01*
X298799Y329575D01*
X300159Y330360D01*
X300246Y330208D01*
G37*
G36*
G01X292932Y327862D02*
X292900Y328617D01*
X293653Y329052D01*
X294291Y328647D01*
X294379Y328495D01*
X293019Y327711D01*
X292932Y327862D01*
G37*
G36*
G01X296318Y329815D02*
X296286Y330570D01*
X297039Y331005D01*
X297677Y330600D01*
X297765Y330449D01*
X296405Y329663D01*
X296318Y329815D01*
G37*
G36*
G01X300246Y341908D02*
X300278Y341153D01*
X299525Y340718D01*
X298887Y341123D01*
X298799Y341275D01*
X300159Y342060D01*
X300246Y341908D01*
G37*
G36*
G01X334580Y340520D02*
X335250Y340170D01*
Y339300D01*
X334580Y338950D01*
X334405D01*
Y340520D01*
X334580D01*
G37*
G36*
G01X296318Y337615D02*
X296286Y338370D01*
X297039Y338805D01*
X297677Y338400D01*
X297765Y338249D01*
X296405Y337463D01*
X296318Y337615D01*
G37*
G36*
G01X292932Y335661D02*
X292900Y336416D01*
X293653Y336851D01*
X294291Y336446D01*
X294379Y336295D01*
X293019Y335509D01*
X292932Y335661D01*
G37*
G36*
G01X299692Y339561D02*
X299660Y340316D01*
X300413Y340751D01*
X301051Y340346D01*
X301139Y340195D01*
X299779Y339409D01*
X299692Y339561D01*
G37*
G36*
G01X332956Y340949D02*
X332286Y341299D01*
Y342169D01*
X332956Y342519D01*
X333131D01*
Y340949D01*
X332956D01*
G37*
G36*
G01Y337049D02*
X332286Y337399D01*
Y338269D01*
X332956Y338619D01*
X333131D01*
Y337049D01*
X332956D01*
G37*
G36*
G01X296860Y336054D02*
X296892Y335299D01*
X296139Y334864D01*
X295501Y335269D01*
X295413Y335420D01*
X296773Y336205D01*
X296860Y336054D01*
G37*
G36*
G01X300246Y338008D02*
X300278Y337253D01*
X299525Y336818D01*
X298887Y337223D01*
X298799Y337375D01*
X300159Y338160D01*
X300246Y338008D01*
G37*
G36*
G01X303552Y339933D02*
X303583Y339178D01*
X302830Y338743D01*
X302192Y339148D01*
X302105Y339299D01*
X303465Y340085D01*
X303552Y339933D01*
G37*
G36*
G01X297671Y364523D02*
X297033Y364118D01*
X296280Y364553D01*
X296312Y365308D01*
X296399Y365460D01*
X297759Y364675D01*
X297671Y364523D01*
G37*
G36*
G01X294306Y366464D02*
X293668Y366059D01*
X292915Y366494D01*
X292947Y367249D01*
X293034Y367401D01*
X294394Y366615D01*
X294306Y366464D01*
G37*
G36*
G01X296860Y347754D02*
X296892Y346999D01*
X296139Y346564D01*
X295501Y346969D01*
X295413Y347120D01*
X296773Y347905D01*
X296860Y347754D01*
G37*
G36*
G01X294297Y346969D02*
X293659Y346564D01*
X292906Y346999D01*
X292938Y347754D01*
X293025Y347905D01*
X294385Y347120D01*
X294297Y346969D01*
G37*
G36*
G01X300246Y349708D02*
X300278Y348953D01*
X299525Y348518D01*
X298887Y348923D01*
X298799Y349075D01*
X300159Y349860D01*
X300246Y349708D01*
G37*
G36*
G01X303620Y351654D02*
X303652Y350899D01*
X302899Y350464D01*
X302261Y350869D01*
X302173Y351020D01*
X303533Y351805D01*
X303620Y351654D01*
G37*
G36*
G01X296318Y349315D02*
X296286Y350070D01*
X297039Y350505D01*
X297677Y350100D01*
X297765Y349949D01*
X296405Y349163D01*
X296318Y349315D01*
G37*
G36*
G01X297686Y372314D02*
X297048Y371909D01*
X296295Y372344D01*
X296327Y373099D01*
X296414Y373251D01*
X297774Y372465D01*
X297686Y372314D01*
G37*
G36*
G01X294297Y374269D02*
X293659Y373864D01*
X292906Y374299D01*
X292938Y375054D01*
X293025Y375205D01*
X294385Y374420D01*
X294297Y374269D01*
G37*
G36*
G01X301051Y370372D02*
X300413Y369967D01*
X299660Y370402D01*
X299692Y371157D01*
X299779Y371309D01*
X301139Y370523D01*
X301051Y370372D01*
G37*
G36*
G01X307866Y366456D02*
X307228Y366051D01*
X306475Y366486D01*
X306507Y367241D01*
X306594Y367393D01*
X307954Y366607D01*
X307866Y366456D01*
G37*
G36*
G01X304437Y368419D02*
X303799Y368014D01*
X303046Y368449D01*
X303078Y369204D01*
X303165Y369355D01*
X304525Y368570D01*
X304437Y368419D01*
G37*
G36*
G01X314963Y363212D02*
X314325Y362807D01*
X313572Y363242D01*
X313604Y363997D01*
X313691Y364149D01*
X315051Y363363D01*
X314963Y363212D01*
G37*
G36*
G01X311576Y365166D02*
X310938Y364761D01*
X310185Y365196D01*
X310217Y365951D01*
X310304Y366103D01*
X311664Y365317D01*
X311576Y365166D01*
G37*
G36*
G01X295507Y375446D02*
X296145Y375851D01*
X296898Y375416D01*
X296866Y374661D01*
X296779Y374509D01*
X295419Y375295D01*
X295507Y375446D01*
G37*
G36*
G01X298872Y373505D02*
X299510Y373910D01*
X300263Y373475D01*
X300231Y372720D01*
X300144Y372568D01*
X298784Y373353D01*
X298872Y373505D01*
G37*
G36*
G01X305647Y369597D02*
X306285Y370002D01*
X307038Y369567D01*
X307006Y368812D01*
X306919Y368661D01*
X305559Y369445D01*
X305647Y369597D01*
G37*
G36*
G01X302261Y371550D02*
X302899Y371955D01*
X303652Y371520D01*
X303620Y370765D01*
X303533Y370613D01*
X302173Y371399D01*
X302261Y371550D01*
G37*
G36*
G01X297671Y387923D02*
X297033Y387518D01*
X296280Y387953D01*
X296311Y388708D01*
X296398Y388859D01*
X297759Y388074D01*
X297671Y387923D01*
G37*
G36*
G01X301057Y385969D02*
X300419Y385564D01*
X299666Y385999D01*
X299698Y386754D01*
X299785Y386905D01*
X301145Y386120D01*
X301057Y385969D01*
G37*
G36*
G01X311190Y380123D02*
X310552Y379718D01*
X309799Y380153D01*
X309831Y380908D01*
X309918Y381060D01*
X311278Y380275D01*
X311190Y380123D01*
G37*
G36*
G01X307816Y382069D02*
X307178Y381664D01*
X306425Y382099D01*
X306457Y382854D01*
X306544Y383005D01*
X307904Y382220D01*
X307816Y382069D01*
G37*
G36*
G01X304431Y384023D02*
X303793Y383618D01*
X303040Y384053D01*
X303072Y384808D01*
X303159Y384960D01*
X304519Y384175D01*
X304431Y384023D01*
G37*
G36*
G01X314576Y378169D02*
X313938Y377764D01*
X313185Y378199D01*
X313217Y378954D01*
X313304Y379105D01*
X314664Y378320D01*
X314576Y378169D01*
G37*
G36*
G01X318336Y372966D02*
X317698Y372561D01*
X316945Y372996D01*
X316977Y373751D01*
X317064Y373903D01*
X318424Y373117D01*
X318336Y372966D01*
G37*
G36*
G01X295777Y393599D02*
X295107Y393949D01*
Y394819D01*
X295777Y395169D01*
X295952D01*
Y393599D01*
X295777D01*
G37*
G36*
G01Y397450D02*
X295107Y397800D01*
Y398670D01*
X295777Y399020D01*
X295952D01*
Y397450D01*
X295777D01*
G37*
G36*
G01X295778Y389718D02*
X295108Y390068D01*
Y390938D01*
X295778Y391288D01*
X295952D01*
X295953Y389717D01*
X295778Y389718D01*
G37*
G36*
G01X296478Y401097D02*
X295718Y401447D01*
Y402347D01*
X296478Y402697D01*
X296653D01*
Y401097D01*
X296478D01*
G37*
G36*
G01X298881Y389100D02*
X299519Y389505D01*
X300272Y389070D01*
X300240Y388315D01*
X300153Y388163D01*
X298793Y388949D01*
X298881Y389100D01*
G37*
G36*
G01X309026Y383246D02*
X309664Y383651D01*
X310417Y383216D01*
X310385Y382461D01*
X310298Y382309D01*
X308938Y383095D01*
X309026Y383246D01*
G37*
G36*
G01X305641Y385200D02*
X306279Y385605D01*
X307032Y385170D01*
X307000Y384415D01*
X306913Y384263D01*
X305553Y385049D01*
X305641Y385200D01*
G37*
G36*
G01X302267Y387146D02*
X302905Y387551D01*
X303658Y387116D01*
X303626Y386361D01*
X303539Y386209D01*
X302179Y386995D01*
X302267Y387146D01*
G37*
G36*
G01X315786Y379346D02*
X316424Y379751D01*
X317177Y379316D01*
X317145Y378561D01*
X317058Y378409D01*
X315698Y379195D01*
X315786Y379346D01*
G37*
G36*
G01X312400Y381300D02*
X313038Y381705D01*
X313791Y381270D01*
X313759Y380515D01*
X313672Y380363D01*
X312312Y381149D01*
X312400Y381300D01*
G37*
G36*
G01X317719Y377401D02*
X318472Y377346D01*
X318818Y376548D01*
X318343Y375961D01*
X318182Y375890D01*
X317558Y377332D01*
X317719Y377401D01*
G37*
G36*
G01X297401Y393170D02*
X298071Y392820D01*
Y391950D01*
X297401Y391600D01*
X297226D01*
Y393170D01*
X297401D01*
G37*
G36*
G01Y397094D02*
X298071Y396744D01*
Y395874D01*
X297401Y395524D01*
X297226D01*
Y397094D01*
X297401D01*
G37*
G36*
G01X297576Y402197D02*
X298336Y401847D01*
Y400947D01*
X297576Y400597D01*
X297401D01*
Y402197D01*
X297576D01*
G37*
G36*
G01X297677Y368419D02*
X297039Y368014D01*
X296286Y368449D01*
X296318Y369204D01*
X296405Y369355D01*
X297765Y368570D01*
X297677Y368419D01*
G37*
G36*
G01X294291Y370372D02*
X293653Y369967D01*
X292900Y370402D01*
X292932Y371157D01*
X293019Y371309D01*
X294379Y370523D01*
X294291Y370372D01*
G37*
G36*
G01X301066Y366464D02*
X300428Y366059D01*
X299675Y366494D01*
X299707Y367249D01*
X299794Y367401D01*
X301154Y366615D01*
X301066Y366464D01*
G37*
G36*
G01X307816Y362569D02*
X307178Y362164D01*
X306425Y362599D01*
X306457Y363354D01*
X306544Y363505D01*
X307904Y362720D01*
X307816Y362569D01*
G37*
G36*
G01X304431Y364523D02*
X303793Y364118D01*
X303040Y364553D01*
X303072Y365308D01*
X303159Y365460D01*
X304519Y364675D01*
X304431Y364523D01*
G37*
G36*
G01X311837Y361352D02*
X311488Y360681D01*
X310619Y360679D01*
X310267Y361348D01*
Y361523D01*
X311836Y361528D01*
X311837Y361352D01*
G37*
G36*
G01X295501Y371550D02*
X296139Y371955D01*
X296892Y371520D01*
X296860Y370765D01*
X296773Y370613D01*
X295413Y371399D01*
X295501Y371550D01*
G37*
G36*
G01X305641Y365700D02*
X306279Y366105D01*
X307032Y365670D01*
X307000Y364915D01*
X306913Y364763D01*
X305553Y365549D01*
X305641Y365700D01*
G37*
G36*
G01X302252Y367655D02*
X302890Y368060D01*
X303643Y367625D01*
X303611Y366870D01*
X303524Y366718D01*
X302164Y367503D01*
X302252Y367655D01*
G37*
G36*
G01X298887Y369597D02*
X299525Y370002D01*
X300278Y369567D01*
X300246Y368812D01*
X300159Y368661D01*
X298799Y369445D01*
X298887Y369597D01*
G37*
G36*
G01X297671Y384023D02*
X297033Y383618D01*
X296280Y384053D01*
X296312Y384808D01*
X296399Y384960D01*
X297759Y384175D01*
X297671Y384023D01*
G37*
G36*
G01X294297Y385969D02*
X293659Y385564D01*
X292906Y385999D01*
X292938Y386754D01*
X293025Y386905D01*
X294385Y386120D01*
X294297Y385969D01*
G37*
G36*
G01X307816Y378169D02*
X307178Y377764D01*
X306425Y378199D01*
X306457Y378954D01*
X306544Y379105D01*
X307904Y378320D01*
X307816Y378169D01*
G37*
G36*
G01X304431Y380123D02*
X303793Y379718D01*
X303040Y380153D01*
X303072Y380908D01*
X303159Y381060D01*
X304519Y380275D01*
X304431Y380123D01*
G37*
G36*
G01X301057Y382069D02*
X300419Y381664D01*
X299666Y382099D01*
X299698Y382854D01*
X299785Y383005D01*
X301145Y382220D01*
X301057Y382069D01*
G37*
G36*
G01X311190Y376223D02*
X310552Y375818D01*
X309799Y376253D01*
X309831Y377008D01*
X309918Y377160D01*
X311278Y376375D01*
X311190Y376223D01*
G37*
G36*
G01X315780Y371550D02*
X316418Y371955D01*
X317171Y371520D01*
X317139Y370765D01*
X317052Y370613D01*
X315692Y371399D01*
X315780Y371550D01*
G37*
G36*
G01X318331Y369069D02*
X317693Y368664D01*
X316940Y369099D01*
X316972Y369854D01*
X317059Y370005D01*
X318419Y369220D01*
X318331Y369069D01*
G37*
G36*
G01X320672Y368959D02*
X320238Y368341D01*
X319376Y368454D01*
X319116Y369163D01*
X319138Y369336D01*
X320695Y369133D01*
X320672Y368959D01*
G37*
G36*
G01X295507Y387146D02*
X296145Y387551D01*
X296898Y387116D01*
X296866Y386361D01*
X296779Y386209D01*
X295419Y386995D01*
X295507Y387146D01*
G37*
G36*
G01X309026Y379346D02*
X309664Y379751D01*
X310417Y379316D01*
X310385Y378561D01*
X310298Y378409D01*
X308938Y379195D01*
X309026Y379346D01*
G37*
G36*
G01X305641Y381300D02*
X306279Y381705D01*
X307032Y381270D01*
X307000Y380515D01*
X306913Y380363D01*
X305553Y381149D01*
X305641Y381300D01*
G37*
G36*
G01X298881Y385200D02*
X299519Y385605D01*
X300272Y385170D01*
X300240Y384415D01*
X300153Y384263D01*
X298793Y385049D01*
X298881Y385200D01*
G37*
G36*
G01X302267Y383246D02*
X302905Y383651D01*
X303658Y383216D01*
X303626Y382461D01*
X303539Y382309D01*
X302179Y383095D01*
X302267Y383246D01*
G37*
G36*
G01X312400Y377400D02*
X313038Y377805D01*
X313791Y377370D01*
X313759Y376615D01*
X313672Y376463D01*
X312312Y377249D01*
X312400Y377400D01*
G37*
G36*
G01X314284Y375448D02*
X315038Y375406D01*
X315397Y374614D01*
X314931Y374019D01*
X314772Y373946D01*
X314124Y375377D01*
X314284Y375448D01*
G37*
G36*
G01X317950Y384023D02*
X317312Y383618D01*
X316559Y384053D01*
X316591Y384808D01*
X316678Y384960D01*
X318038Y384175D01*
X317950Y384023D01*
G37*
G36*
G01X314585Y385963D02*
X313947Y385558D01*
X313194Y385993D01*
X313225Y386748D01*
X313313Y386899D01*
X314672Y386115D01*
X314585Y385963D01*
G37*
G36*
G01X321367Y382052D02*
X320729Y381647D01*
X319976Y382082D01*
X320008Y382837D01*
X320095Y382989D01*
X321455Y382203D01*
X321367Y382052D01*
G37*
G36*
G01X312676Y389669D02*
X311916Y390019D01*
Y390919D01*
X312676Y391269D01*
X312851D01*
Y389669D01*
X312676D01*
G37*
G36*
G01X310273Y395849D02*
X309513Y396199D01*
Y397099D01*
X310273Y397449D01*
X310448D01*
Y395849D01*
X310273D01*
G37*
G36*
G01X329576Y358476D02*
X328906Y358826D01*
Y359696D01*
X329576Y360046D01*
X329751D01*
Y358476D01*
X329576D01*
G37*
G36*
G01Y354576D02*
X328906Y354926D01*
Y355796D01*
X329576Y356146D01*
X329751D01*
Y354576D01*
X329576D01*
G37*
G36*
G01Y350676D02*
X328906Y351026D01*
Y351896D01*
X329576Y352246D01*
X329751D01*
Y350676D01*
X329576D01*
G37*
G36*
G01Y342876D02*
X328906Y343226D01*
Y344096D01*
X329576Y344446D01*
X329751D01*
Y342876D01*
X329576D01*
G37*
G36*
G01Y346776D02*
X328906Y347126D01*
Y347996D01*
X329576Y348346D01*
X329751D01*
Y346776D01*
X329576D01*
G37*
G36*
G01X326196Y372124D02*
X325526Y372474D01*
Y373344D01*
X326196Y373694D01*
X326371D01*
Y372124D01*
X326196D01*
G37*
G36*
G01X324731Y376210D02*
X324094Y375805D01*
X323340Y376239D01*
X323372Y376994D01*
X323460Y377147D01*
X324819Y376361D01*
X324731Y376210D01*
G37*
G36*
G01X322816Y377993D02*
X322147Y378343D01*
X322146Y379212D01*
X322816Y379562D01*
X322992Y379563D01*
X322991Y377993D01*
X322816D01*
G37*
G36*
G01X326196Y368200D02*
X325526Y368550D01*
Y369420D01*
X326196Y369770D01*
X326371D01*
Y368200D01*
X326196D01*
G37*
G36*
G01X326197Y364325D02*
X325527Y364675D01*
Y365545D01*
X326197Y365895D01*
X326372D01*
Y364325D01*
X326197D01*
G37*
G36*
G01X328126Y362551D02*
X327488Y362146D01*
X326735Y362581D01*
X326767Y363336D01*
X326854Y363488D01*
X328214Y362703D01*
X328126Y362551D01*
G37*
G36*
G01X310273Y399749D02*
X309513Y400099D01*
Y400999D01*
X310273Y401349D01*
X310448D01*
Y399749D01*
X310273D01*
G37*
G36*
G01X319160Y385200D02*
X319798Y385605D01*
X320551Y385170D01*
X320519Y384415D01*
X320432Y384263D01*
X319072Y385049D01*
X319160Y385200D01*
G37*
G36*
G01X315786Y387146D02*
X316424Y387551D01*
X317177Y387116D01*
X317145Y386361D01*
X317058Y386209D01*
X315698Y386995D01*
X315786Y387146D01*
G37*
G36*
G01X313776Y391269D02*
X314536Y390919D01*
Y390019D01*
X313776Y389669D01*
X313601D01*
Y391269D01*
X313776D01*
G37*
G36*
G01X311371Y397449D02*
X312131Y397099D01*
Y396199D01*
X311371Y395849D01*
X311196D01*
Y397449D01*
X311371D01*
G37*
G36*
G01X331200Y358096D02*
X331870Y357746D01*
Y356876D01*
X331200Y356526D01*
X331025D01*
Y358096D01*
X331200D01*
G37*
G36*
G01Y354196D02*
X331870Y353846D01*
Y352976D01*
X331200Y352626D01*
X331025D01*
Y354196D01*
X331200D01*
G37*
G36*
G01Y350296D02*
X331870Y349946D01*
Y349076D01*
X331200Y348726D01*
X331025D01*
Y350296D01*
X331200D01*
G37*
G36*
G01X321845Y383324D02*
X322356Y383880D01*
X323196Y383656D01*
X323360Y382918D01*
X323316Y382748D01*
X321798Y383155D01*
X321845Y383324D01*
G37*
G36*
G01X327819Y375610D02*
X328489Y375260D01*
Y374391D01*
X327819Y374041D01*
X327644Y374040D01*
X327645Y375610D01*
X327819D01*
G37*
G36*
G01X325919Y377401D02*
X326557Y377806D01*
X327310Y377372D01*
X327278Y376616D01*
X327191Y376464D01*
X325832Y377250D01*
X325919Y377401D01*
G37*
G36*
G01X324440Y381476D02*
X325109Y381126D01*
X325110Y380257D01*
X324440Y379907D01*
X324264Y379906D01*
Y381477D01*
X324440Y381476D01*
G37*
G36*
G01X327819Y367846D02*
X328489Y367496D01*
Y366626D01*
X327819Y366276D01*
X327644D01*
Y367846D01*
X327819D01*
G37*
G36*
G01X327820Y371769D02*
X328490Y371419D01*
Y370549D01*
X327820Y370199D01*
X327645D01*
Y371769D01*
X327820D01*
G37*
G36*
G01X329269Y363767D02*
X329907Y364173D01*
X330660Y363738D01*
X330629Y362983D01*
X330542Y362831D01*
X329181Y363616D01*
X329269Y363767D01*
G37*
G36*
G01X331199Y361993D02*
X331869Y361644D01*
Y360774D01*
X331200Y360424D01*
X331025Y360423D01*
X331024Y361994D01*
X331199Y361993D01*
G37*
G36*
G01X311371Y401349D02*
X312131Y400999D01*
Y400099D01*
X311371Y399749D01*
X311196D01*
Y401349D01*
X311371D01*
G37*
G36*
G01X343096Y358450D02*
X342426Y358800D01*
Y359670D01*
X343096Y360020D01*
X343271D01*
Y358450D01*
X343096D01*
G37*
G36*
G01Y350650D02*
X342426Y351000D01*
Y351870D01*
X343096Y352220D01*
X343271D01*
Y350650D01*
X343096D01*
G37*
G36*
G01Y354550D02*
X342426Y354900D01*
Y355770D01*
X343096Y356120D01*
X343271D01*
Y354550D01*
X343096D01*
G37*
G36*
G01Y346750D02*
X342426Y347100D01*
Y347970D01*
X343096Y348320D01*
X343271D01*
Y346750D01*
X343096D01*
G37*
G36*
G01X336840Y388378D02*
X336055Y388088D01*
X335418Y388724D01*
X335708Y389509D01*
X335832Y389633D01*
X336963Y388502D01*
X336840Y388378D01*
G37*
G36*
G01X338958Y385256D02*
X338125Y385180D01*
X337675Y385959D01*
X338159Y386642D01*
X338310Y386730D01*
X339109Y385344D01*
X338958Y385256D01*
G37*
G36*
G01X339716Y379949D02*
X339046Y380299D01*
Y381169D01*
X339716Y381519D01*
X339891D01*
Y379949D01*
X339716D01*
G37*
G36*
G01Y376049D02*
X339046Y376399D01*
Y377269D01*
X339716Y377619D01*
X339891D01*
Y376049D01*
X339716D01*
G37*
G36*
G01X339717Y372167D02*
X339047Y372517D01*
Y373387D01*
X339717Y373737D01*
X339892D01*
Y372166D01*
X339717Y372167D01*
G37*
G36*
G01X343096Y366275D02*
X342426Y366625D01*
Y367495D01*
X343096Y367845D01*
X343271D01*
Y366275D01*
X343096D01*
G37*
G36*
G01X341610Y370372D02*
X340972Y369967D01*
X340219Y370402D01*
X340250Y371157D01*
X340338Y371309D01*
X341698Y370523D01*
X341610Y370372D01*
G37*
G36*
G01X343096Y362350D02*
X342426Y362700D01*
Y363570D01*
X343096Y363920D01*
X343271D01*
Y362350D01*
X343096D01*
G37*
G36*
G01X331324Y393893D02*
X330539Y393603D01*
X329903Y394240D01*
X330193Y395025D01*
X330317Y395148D01*
X331448Y394017D01*
X331324Y393893D01*
G37*
G36*
G01X334082Y391136D02*
X333297Y390846D01*
X332661Y391482D01*
X332951Y392267D01*
X333074Y392391D01*
X334206Y391259D01*
X334082Y391136D01*
G37*
G36*
G01X329373Y399608D02*
X328613Y399958D01*
Y400858D01*
X329373Y401208D01*
X329548D01*
Y399608D01*
X329373D01*
G37*
G36*
G01X344720Y358119D02*
X345390Y357769D01*
Y356899D01*
X344720Y356549D01*
X344545D01*
Y358119D01*
X344720D01*
G37*
G36*
G01Y354219D02*
X345390Y353869D01*
Y352999D01*
X344720Y352649D01*
X344545D01*
Y354219D01*
X344720D01*
G37*
G36*
G01Y350319D02*
X345390Y349969D01*
Y349099D01*
X344720Y348749D01*
X344545D01*
Y350319D01*
X344720D01*
G37*
G36*
G01Y346419D02*
X345390Y346069D01*
Y345199D01*
X344720Y344849D01*
X344545D01*
Y346419D01*
X344720D01*
G37*
G36*
G01X339111Y387191D02*
X339944Y387267D01*
X340393Y386488D01*
X339910Y385805D01*
X339758Y385717D01*
X338959Y387104D01*
X339111Y387191D01*
G37*
G36*
G01X341340Y383420D02*
X342010Y383070D01*
Y382200D01*
X341340Y381850D01*
X341165D01*
Y383420D01*
X341340D01*
G37*
G36*
G01Y379520D02*
X342010Y379170D01*
Y378300D01*
X341340Y377950D01*
X341165D01*
Y379520D01*
X341340D01*
G37*
G36*
G01Y375620D02*
X342010Y375270D01*
Y374400D01*
X341340Y374050D01*
X341165D01*
Y375620D01*
X341340D01*
G37*
G36*
G01X342819Y371551D02*
X343457Y371956D01*
X344210Y371522D01*
X344178Y370767D01*
X344091Y370614D01*
X342732Y371400D01*
X342819Y371551D01*
G37*
G36*
G01X344720Y362019D02*
X345390Y361669D01*
Y360799D01*
X344720Y360449D01*
X344545D01*
Y362019D01*
X344720D01*
G37*
G36*
G01Y365919D02*
X345390Y365569D01*
Y364699D01*
X344720Y364349D01*
X344545D01*
Y365919D01*
X344720D01*
G37*
G36*
G01X344719Y369760D02*
X345389Y369410D01*
Y368541D01*
X344720Y368191D01*
X344544Y368190D01*
X344545Y369760D01*
X344719D01*
G37*
G36*
G01X330471Y399808D02*
X331231Y399458D01*
Y398558D01*
X330471Y398208D01*
X330296D01*
Y399808D01*
X330471D01*
G37*
G36*
G01X331969Y394801D02*
X332754Y395091D01*
X333391Y394455D01*
X333101Y393670D01*
X332977Y393546D01*
X331846Y394677D01*
X331969Y394801D01*
G37*
G36*
G01X334727Y392043D02*
X335512Y392333D01*
X336148Y391697D01*
X335858Y390912D01*
X335735Y390788D01*
X334603Y391920D01*
X334727Y392043D01*
G37*
G36*
G01X330471Y403708D02*
X331231Y403358D01*
Y402458D01*
X330471Y402108D01*
X330296D01*
Y403708D01*
X330471D01*
G37*
G36*
G01X309296Y385793D02*
X308627Y386143D01*
X308626Y387012D01*
X309296Y387362D01*
X309472Y387363D01*
Y385792D01*
X309296Y385793D01*
G37*
G36*
G01X311211Y384010D02*
X310574Y383605D01*
X309821Y384039D01*
X309852Y384794D01*
X309940Y384947D01*
X311300Y384162D01*
X311211Y384010D01*
G37*
G36*
G01X314576Y382069D02*
X313938Y381664D01*
X313185Y382099D01*
X313217Y382854D01*
X313304Y383005D01*
X314664Y382220D01*
X314576Y382069D01*
G37*
G36*
G01X317950Y380123D02*
X317312Y379718D01*
X316559Y380153D01*
X316591Y380908D01*
X316678Y381060D01*
X318038Y380275D01*
X317950Y380123D01*
G37*
G36*
G01X321337Y374268D02*
X320699Y373863D01*
X319946Y374297D01*
X319978Y375052D01*
X320065Y375205D01*
X321424Y374419D01*
X321337Y374268D01*
G37*
G36*
G01X309146Y390788D02*
X308361Y390498D01*
X307725Y391135D01*
X308015Y391919D01*
X308139Y392043D01*
X309270Y390912D01*
X309146Y390788D01*
G37*
G36*
G01X306846Y396188D02*
X306061Y395898D01*
X305425Y396535D01*
X305715Y397319D01*
X305839Y397443D01*
X306970Y396312D01*
X306846Y396188D01*
G37*
G36*
G01X326196Y356549D02*
X325526Y356899D01*
Y357769D01*
X326196Y358119D01*
X326371D01*
Y356549D01*
X326196D01*
G37*
G36*
G01Y352649D02*
X325526Y352999D01*
Y353869D01*
X326196Y354219D01*
X326371D01*
Y352649D01*
X326196D01*
G37*
G36*
G01Y344849D02*
X325526Y345199D01*
Y346069D01*
X326196Y346419D01*
X326371D01*
Y344849D01*
X326196D01*
G37*
G36*
G01Y348749D02*
X325526Y349099D01*
Y349969D01*
X326196Y350319D01*
X326371D01*
Y348749D01*
X326196D01*
G37*
G36*
G01X322816Y366275D02*
X322146Y366625D01*
Y367495D01*
X322816Y367845D01*
X322991D01*
Y366275D01*
X322816D01*
G37*
G36*
G01Y370199D02*
X322146Y370549D01*
Y371419D01*
X322816Y371769D01*
X322991D01*
Y370199D01*
X322816D01*
G37*
G36*
G01X324731Y360610D02*
X324094Y360205D01*
X323340Y360639D01*
X323372Y361394D01*
X323460Y361547D01*
X324819Y360761D01*
X324731Y360610D01*
G37*
G36*
G01X322816Y362393D02*
X322147Y362743D01*
X322146Y363612D01*
X322816Y363962D01*
X322992Y363963D01*
X322991Y362393D01*
X322816D01*
G37*
G36*
G01X305073Y400627D02*
X304313Y400977D01*
Y401877D01*
X305073Y402227D01*
X305248D01*
Y400627D01*
X305073D01*
G37*
G36*
G01X311105Y389952D02*
X311865Y389602D01*
Y388701D01*
X311106Y388351D01*
X310931D01*
Y389951D01*
X311105Y389952D01*
G37*
G36*
G01X315786Y383246D02*
X316424Y383651D01*
X317177Y383216D01*
X317145Y382461D01*
X317058Y382309D01*
X315698Y383095D01*
X315786Y383246D01*
G37*
G36*
G01X312400Y385200D02*
X313038Y385605D01*
X313791Y385170D01*
X313759Y384415D01*
X313672Y384263D01*
X312312Y385049D01*
X312400Y385200D01*
G37*
G36*
G01X319159Y381301D02*
X319797Y381706D01*
X320550Y381272D01*
X320518Y380516D01*
X320431Y380364D01*
X319072Y381150D01*
X319159Y381301D01*
G37*
G36*
G01X321059Y379510D02*
X321729Y379160D01*
Y378291D01*
X321059Y377941D01*
X320884Y377940D01*
X320885Y379510D01*
X321059D01*
G37*
G36*
G01X308791Y392696D02*
X309576Y392986D01*
X310213Y392349D01*
X309923Y391565D01*
X309799Y391441D01*
X308668Y392572D01*
X308791Y392696D01*
G37*
G36*
G01X306491Y398096D02*
X307276Y398386D01*
X307913Y397749D01*
X307623Y396965D01*
X307499Y396841D01*
X306368Y397972D01*
X306491Y398096D01*
G37*
G36*
G01X327819Y360010D02*
X328489Y359660D01*
Y358791D01*
X327819Y358441D01*
X327644Y358440D01*
X327645Y360010D01*
X327819D01*
G37*
G36*
G01X327820Y356120D02*
X328490Y355770D01*
Y354900D01*
X327820Y354550D01*
X327645D01*
Y356120D01*
X327820D01*
G37*
G36*
G01Y352220D02*
X328490Y351870D01*
Y351000D01*
X327820Y350650D01*
X327645D01*
Y352220D01*
X327820D01*
G37*
G36*
G01Y348320D02*
X328490Y347970D01*
Y347100D01*
X327820Y346750D01*
X327645D01*
Y348320D01*
X327820D01*
G37*
G36*
G01X324439Y373651D02*
X325109Y373301D01*
Y372431D01*
X324439Y372081D01*
X324265D01*
Y373651D01*
X324439D01*
G37*
G36*
G01X322546Y375446D02*
X323184Y375851D01*
X323937Y375416D01*
X323906Y374661D01*
X323819Y374510D01*
X322459Y375295D01*
X322546Y375446D01*
G37*
G36*
G01X324440Y365919D02*
X325110Y365569D01*
Y364699D01*
X324440Y364349D01*
X324265D01*
Y365919D01*
X324440D01*
G37*
G36*
G01Y369770D02*
X325110Y369420D01*
Y368550D01*
X324440Y368200D01*
X324265D01*
Y369770D01*
X324440D01*
G37*
G36*
G01X325919Y361801D02*
X326557Y362206D01*
X327310Y361772D01*
X327278Y361016D01*
X327191Y360864D01*
X325832Y361650D01*
X325919Y361801D01*
G37*
G36*
G01X306171Y402227D02*
X306931Y401877D01*
Y400977D01*
X306171Y400627D01*
X305996D01*
Y402227D01*
X306171D01*
G37*
G36*
G01X294297Y343069D02*
X293659Y342664D01*
X292906Y343099D01*
X292938Y343854D01*
X293025Y344005D01*
X294385Y343220D01*
X294297Y343069D01*
G37*
G36*
G01X339716Y356549D02*
X339046Y356899D01*
Y357769D01*
X339716Y358119D01*
X339891D01*
Y356549D01*
X339716D01*
G37*
G36*
G01Y352649D02*
X339046Y352999D01*
Y353869D01*
X339716Y354219D01*
X339891D01*
Y352649D01*
X339716D01*
G37*
G36*
G01Y348749D02*
X339046Y349099D01*
Y349969D01*
X339716Y350319D01*
X339891D01*
Y348749D01*
X339716D01*
G37*
G36*
G01X332961Y385021D02*
X332201Y385371D01*
Y386271D01*
X332961Y386621D01*
X333136D01*
Y385021D01*
X332961D01*
G37*
G36*
G01X332818Y388066D02*
X332033Y387776D01*
X331396Y388412D01*
X331686Y389197D01*
X331810Y389321D01*
X332941Y388190D01*
X332818Y388066D01*
G37*
G36*
G01X339716Y364349D02*
X339046Y364699D01*
Y365569D01*
X339716Y365919D01*
X339891D01*
Y364349D01*
X339716D01*
G37*
G36*
G01X336336Y374050D02*
X335666Y374400D01*
Y375270D01*
X336336Y375620D01*
X336511D01*
Y374050D01*
X336336D01*
G37*
G36*
G01X336337Y370209D02*
X335667Y370559D01*
Y371428D01*
X336337Y371778D01*
X336512Y371779D01*
X336511Y370209D01*
X336337D01*
G37*
G36*
G01X338237Y368418D02*
X337599Y368013D01*
X336846Y368447D01*
X336878Y369203D01*
X336965Y369355D01*
X338324Y368569D01*
X338237Y368418D01*
G37*
G36*
G01X336336Y377950D02*
X335666Y378300D01*
Y379170D01*
X336336Y379520D01*
X336511D01*
Y377950D01*
X336336D01*
G37*
G36*
G01X339716Y360449D02*
X339046Y360799D01*
Y361669D01*
X339716Y362019D01*
X339891D01*
Y360449D01*
X339716D01*
G37*
G36*
G01X330060Y390824D02*
X329275Y390534D01*
X328639Y391170D01*
X328929Y391955D01*
X329052Y392079D01*
X330184Y390947D01*
X330060Y390824D01*
G37*
G36*
G01X327302Y393581D02*
X326517Y393291D01*
X325881Y393928D01*
X326171Y394713D01*
X326295Y394836D01*
X327426Y393705D01*
X327302Y393581D01*
G37*
G36*
G01X325925Y397360D02*
X325165Y397710D01*
Y398610D01*
X325925Y398960D01*
X326100D01*
Y397360D01*
X325925D01*
G37*
G36*
G01X325516Y401626D02*
X324731Y401336D01*
X324095Y401972D01*
X324385Y402757D01*
X324508Y402881D01*
X325640Y401749D01*
X325516Y401626D01*
G37*
G36*
G01X341340Y360020D02*
X342010Y359670D01*
Y358800D01*
X341340Y358450D01*
X341165D01*
Y360020D01*
X341340D01*
G37*
G36*
G01Y352220D02*
X342010Y351870D01*
Y351000D01*
X341340Y350650D01*
X341165D01*
Y352220D01*
X341340D01*
G37*
G36*
G01Y356120D02*
X342010Y355770D01*
Y354900D01*
X341340Y354550D01*
X341165D01*
Y356120D01*
X341340D01*
G37*
G36*
G01Y348320D02*
X342010Y347970D01*
Y347100D01*
X341340Y346750D01*
X341165D01*
Y348320D01*
X341340D01*
G37*
G36*
G01X334059Y387321D02*
X334819Y386971D01*
Y386071D01*
X334059Y385721D01*
X333884D01*
Y387321D01*
X334059D01*
G37*
G36*
G01X336045Y383259D02*
X336682Y383664D01*
X337436Y383230D01*
X337404Y382475D01*
X337317Y382323D01*
X335957Y383108D01*
X336045Y383259D01*
G37*
G36*
G01X332463Y389974D02*
X333248Y390264D01*
X333884Y389627D01*
X333594Y388842D01*
X333470Y388719D01*
X332339Y389850D01*
X332463Y389974D01*
G37*
G36*
G01X337960Y373694D02*
X338630Y373344D01*
Y372474D01*
X337960Y372124D01*
X337785D01*
Y373694D01*
X337960D01*
G37*
G36*
G01X339446Y369597D02*
X340084Y370002D01*
X340837Y369567D01*
X340805Y368812D01*
X340719Y368661D01*
X339359Y369446D01*
X339446Y369597D01*
G37*
G36*
G01X337960Y377619D02*
X338630Y377269D01*
Y376399D01*
X337960Y376049D01*
X337785D01*
Y377619D01*
X337960D01*
G37*
G36*
G01Y381476D02*
X338629Y381126D01*
X338630Y380257D01*
X337960Y379907D01*
X337785Y379906D01*
Y381476D01*
X337960D01*
G37*
G36*
G01X341339Y367802D02*
X342009Y367452D01*
Y366582D01*
X341339Y366233D01*
X341165Y366232D01*
Y367802D01*
X341339D01*
G37*
G36*
G01X341340Y363920D02*
X342010Y363570D01*
Y362700D01*
X341340Y362350D01*
X341165D01*
Y363920D01*
X341340D01*
G37*
G36*
G01X329705Y392731D02*
X330490Y393021D01*
X331126Y392385D01*
X330836Y391600D01*
X330713Y391476D01*
X329581Y392608D01*
X329705Y392731D01*
G37*
G36*
G01X327023Y398960D02*
X327783Y398610D01*
Y397710D01*
X327023Y397360D01*
X326848D01*
Y398960D01*
X327023D01*
G37*
G36*
G01X325282Y403454D02*
X326067Y403744D01*
X326703Y403108D01*
X326413Y402323D01*
X326290Y402199D01*
X325158Y403331D01*
X325282Y403454D01*
G37*
G36*
G01X326947Y395489D02*
X327732Y395779D01*
X328369Y395143D01*
X328079Y394358D01*
X327955Y394234D01*
X326824Y395365D01*
X326947Y395489D01*
G37*
G36*
G01X296662Y341491D02*
X297011Y342161D01*
X297881D01*
X298231Y341491D01*
X298232Y341317D01*
X296661Y341316D01*
X296662Y341491D01*
G37*
G36*
G01X296860Y351654D02*
X296892Y350899D01*
X296139Y350464D01*
X295501Y350869D01*
X295413Y351020D01*
X296773Y351805D01*
X296860Y351654D01*
G37*
G36*
G01X294297Y350869D02*
X293659Y350464D01*
X292906Y350899D01*
X292938Y351654D01*
X293025Y351805D01*
X294385Y351020D01*
X294297Y350869D01*
G37*
G36*
G01X300246Y353608D02*
X300278Y352853D01*
X299525Y352418D01*
X298887Y352823D01*
X298799Y352975D01*
X300159Y353760D01*
X300246Y353608D01*
G37*
G36*
G01X299692Y359061D02*
X299660Y359816D01*
X300413Y360251D01*
X301051Y359846D01*
X301139Y359695D01*
X299779Y358909D01*
X299692Y359061D01*
G37*
G36*
G01X295507Y379346D02*
X296145Y379751D01*
X296898Y379316D01*
X296866Y378561D01*
X296779Y378409D01*
X295419Y379195D01*
X295507Y379346D01*
G37*
G36*
G01X298881Y377400D02*
X299519Y377805D01*
X300272Y377370D01*
X300240Y376615D01*
X300153Y376463D01*
X298793Y377249D01*
X298881Y377400D01*
G37*
G36*
G01X309020Y371550D02*
X309658Y371955D01*
X310411Y371520D01*
X310379Y370765D01*
X310292Y370613D01*
X308932Y371399D01*
X309020Y371550D01*
G37*
G36*
G01X305632Y373505D02*
X306270Y373910D01*
X307023Y373475D01*
X306991Y372720D01*
X306904Y372568D01*
X305544Y373353D01*
X305632Y373505D01*
G37*
G36*
G01X302267Y375446D02*
X302905Y375851D01*
X303658Y375416D01*
X303626Y374661D01*
X303539Y374509D01*
X302179Y375295D01*
X302267Y375446D01*
G37*
G36*
G01X315771Y367655D02*
X316409Y368060D01*
X317162Y367625D01*
X317130Y366870D01*
X317043Y366718D01*
X315683Y367503D01*
X315771Y367655D01*
G37*
G36*
G01X312406Y369597D02*
X313044Y370002D01*
X313797Y369567D01*
X313765Y368812D01*
X313678Y368661D01*
X312318Y369445D01*
X312406Y369597D01*
G37*
G36*
G01X316225Y398167D02*
X316985Y397817D01*
Y396917D01*
X316225Y396567D01*
X316050D01*
Y398167D01*
X316225D01*
G37*
G36*
G01X334580Y360020D02*
X335250Y359670D01*
Y358800D01*
X334580Y358450D01*
X334405D01*
Y360020D01*
X334580D01*
G37*
G36*
G01Y352220D02*
X335250Y351870D01*
Y351000D01*
X334580Y350650D01*
X334405D01*
Y352220D01*
X334580D01*
G37*
G36*
G01Y356120D02*
X335250Y355770D01*
Y354900D01*
X334580Y354550D01*
X334405D01*
Y356120D01*
X334580D01*
G37*
G36*
G01Y344420D02*
X335250Y344070D01*
Y343200D01*
X334580Y342850D01*
X334405D01*
Y344420D01*
X334580D01*
G37*
G36*
G01Y348320D02*
X335250Y347970D01*
Y347100D01*
X334580Y346750D01*
X334405D01*
Y348320D01*
X334580D01*
G37*
G36*
G01X325229Y384449D02*
X326013Y384739D01*
X326650Y384102D01*
X326360Y383318D01*
X326236Y383194D01*
X325105Y384325D01*
X325229Y384449D01*
G37*
G36*
G01X322471Y387207D02*
X323256Y387497D01*
X323892Y386860D01*
X323602Y386075D01*
X323478Y385952D01*
X322347Y387083D01*
X322471Y387207D01*
G37*
G36*
G01X331200Y373694D02*
X331870Y373344D01*
Y372474D01*
X331200Y372124D01*
X331025D01*
Y373694D01*
X331200D01*
G37*
G36*
G01Y377619D02*
X331870Y377269D01*
Y376399D01*
X331200Y376049D01*
X331025D01*
Y377619D01*
X331200D01*
G37*
G36*
G01X327986Y381691D02*
X328771Y381981D01*
X329408Y381345D01*
X329118Y380560D01*
X328994Y380436D01*
X327863Y381567D01*
X327986Y381691D01*
G37*
G36*
G01X331200Y369770D02*
X331870Y369420D01*
Y368550D01*
X331200Y368200D01*
X331025D01*
Y369770D01*
X331200D01*
G37*
G36*
G01X332679Y365701D02*
X333317Y366106D01*
X334070Y365672D01*
X334038Y364917D01*
X333951Y364764D01*
X332592Y365550D01*
X332679Y365701D01*
G37*
G36*
G01X334579Y363910D02*
X335249Y363560D01*
Y362691D01*
X334580Y362341D01*
X334404Y362340D01*
X334405Y363910D01*
X334579D01*
G37*
G36*
G01X316225Y402067D02*
X316985Y401717D01*
Y400817D01*
X316225Y400467D01*
X316050D01*
Y402067D01*
X316225D01*
G37*
G36*
G01X294297Y358669D02*
X293659Y358264D01*
X292906Y358699D01*
X292938Y359454D01*
X293025Y359605D01*
X294385Y358820D01*
X294297Y358669D01*
G37*
G36*
G01X297671Y380123D02*
X297033Y379718D01*
X296280Y380153D01*
X296312Y380908D01*
X296399Y381060D01*
X297759Y380275D01*
X297671Y380123D01*
G37*
G36*
G01X294297Y382069D02*
X293659Y381664D01*
X292906Y382099D01*
X292938Y382854D01*
X293025Y383005D01*
X294385Y382220D01*
X294297Y382069D01*
G37*
G36*
G01X301057Y378169D02*
X300419Y377764D01*
X299666Y378199D01*
X299698Y378954D01*
X299785Y379105D01*
X301145Y378320D01*
X301057Y378169D01*
G37*
G36*
G01X307816Y374269D02*
X307178Y373864D01*
X306425Y374299D01*
X306457Y375054D01*
X306544Y375205D01*
X307904Y374420D01*
X307816Y374269D01*
G37*
G36*
G01X304431Y376223D02*
X303793Y375818D01*
X303040Y376253D01*
X303072Y377008D01*
X303159Y377160D01*
X304519Y376375D01*
X304431Y376223D01*
G37*
G36*
G01X321482Y393998D02*
X320697Y393708D01*
X320061Y394345D01*
X320351Y395130D01*
X320475Y395253D01*
X321606Y394122D01*
X321482Y393998D01*
G37*
G36*
G01X318223Y397641D02*
X317463Y397991D01*
Y398891D01*
X318223Y399241D01*
X318398D01*
Y397641D01*
X318223D01*
G37*
G36*
G01X336336Y358450D02*
X335666Y358800D01*
Y359670D01*
X336336Y360020D01*
X336511D01*
Y358450D01*
X336336D01*
G37*
G36*
G01Y350650D02*
X335666Y351000D01*
Y351870D01*
X336336Y352220D01*
X336511D01*
Y350650D01*
X336336D01*
G37*
G36*
G01Y354550D02*
X335666Y354900D01*
Y355770D01*
X336336Y356120D01*
X336511D01*
Y354550D01*
X336336D01*
G37*
G36*
G01X329023Y384453D02*
X328263Y384803D01*
Y385703D01*
X329023Y386053D01*
X329198D01*
Y384453D01*
X329023D01*
G37*
G36*
G01X326998Y388483D02*
X326213Y388193D01*
X325576Y388829D01*
X325866Y389614D01*
X325990Y389738D01*
X327121Y388607D01*
X326998Y388483D01*
G37*
G36*
G01X331638Y381288D02*
X330853Y380998D01*
X330217Y381634D01*
X330507Y382419D01*
X330630Y382543D01*
X331762Y381411D01*
X331638Y381288D01*
G37*
G36*
G01X332956Y376049D02*
X332286Y376399D01*
Y377269D01*
X332956Y377619D01*
X333131D01*
Y376049D01*
X332956D01*
G37*
G36*
G01Y372124D02*
X332286Y372474D01*
Y373344D01*
X332956Y373694D01*
X333131D01*
Y372124D01*
X332956D01*
G37*
G36*
G01X332957Y368226D02*
X332287Y368575D01*
Y369445D01*
X332956Y369795D01*
X333131Y369796D01*
X333132Y368225D01*
X332957Y368226D01*
G37*
G36*
G01X334886Y366452D02*
X334249Y366046D01*
X333496Y366481D01*
X333527Y367236D01*
X333614Y367388D01*
X334975Y366603D01*
X334886Y366452D01*
G37*
G36*
G01X336336Y362350D02*
X335666Y362700D01*
Y363570D01*
X336336Y363920D01*
X336511D01*
Y362350D01*
X336336D01*
G37*
G36*
G01X324240Y391241D02*
X323455Y390951D01*
X322819Y391587D01*
X323109Y392372D01*
X323232Y392496D01*
X324364Y391364D01*
X324240Y391241D01*
G37*
G36*
G01X318223Y401541D02*
X317463Y401891D01*
Y402791D01*
X318223Y403141D01*
X318398D01*
Y401541D01*
X318223D01*
G37*
G36*
G01X296831Y355537D02*
X296863Y354782D01*
X296110Y354347D01*
X295472Y354752D01*
X295384Y354903D01*
X296744Y355689D01*
X296831Y355537D01*
G37*
G36*
G01X294326Y354752D02*
X293688Y354347D01*
X292935Y354782D01*
X292967Y355537D01*
X293054Y355689D01*
X294414Y354903D01*
X294326Y354752D01*
G37*
G36*
G01X300246Y357508D02*
X300278Y356753D01*
X299525Y356318D01*
X298887Y356723D01*
X298799Y356875D01*
X300159Y357660D01*
X300246Y357508D01*
G37*
G36*
G01X303581Y359466D02*
X303644Y358713D01*
X302909Y358248D01*
X302255Y358627D01*
X302161Y358774D01*
X303488Y359614D01*
X303581Y359466D01*
G37*
G36*
G01X297671Y376223D02*
X297033Y375818D01*
X296280Y376253D01*
X296312Y377008D01*
X296399Y377160D01*
X297759Y376375D01*
X297671Y376223D01*
G37*
G36*
G01X294297Y378169D02*
X293659Y377764D01*
X292906Y378199D01*
X292938Y378954D01*
X293025Y379105D01*
X294385Y378320D01*
X294297Y378169D01*
G37*
G36*
G01X301057Y374269D02*
X300419Y373864D01*
X299666Y374299D01*
X299698Y375054D01*
X299785Y375205D01*
X301145Y374420D01*
X301057Y374269D01*
G37*
G36*
G01X307810Y370372D02*
X307172Y369967D01*
X306419Y370402D01*
X306451Y371157D01*
X306538Y371309D01*
X307898Y370523D01*
X307810Y370372D01*
G37*
G36*
G01X304446Y372314D02*
X303808Y371909D01*
X303055Y372344D01*
X303087Y373099D01*
X303174Y373251D01*
X304534Y372465D01*
X304446Y372314D01*
G37*
G36*
G01X311196Y368419D02*
X310558Y368014D01*
X309805Y368449D01*
X309837Y369204D01*
X309924Y369355D01*
X311284Y368570D01*
X311196Y368419D01*
G37*
G36*
G01X314585Y366464D02*
X313947Y366059D01*
X313194Y366494D01*
X313226Y367249D01*
X313313Y367401D01*
X314673Y366615D01*
X314585Y366464D01*
G37*
G36*
G01X322824Y385297D02*
X322039Y385007D01*
X321403Y385644D01*
X321693Y386429D01*
X321817Y386552D01*
X322948Y385421D01*
X322824Y385297D01*
G37*
G36*
G01X315125Y396567D02*
X314365Y396917D01*
Y397817D01*
X315125Y398167D01*
X315300D01*
Y396567D01*
X315125D01*
G37*
G36*
G01X332956Y356549D02*
X332286Y356899D01*
Y357769D01*
X332956Y358119D01*
X333131D01*
Y356549D01*
X332956D01*
G37*
G36*
G01Y352649D02*
X332286Y352999D01*
Y353869D01*
X332956Y354219D01*
X333131D01*
Y352649D01*
X332956D01*
G37*
G36*
G01Y348749D02*
X332286Y349099D01*
Y349969D01*
X332956Y350319D01*
X333131D01*
Y348749D01*
X332956D01*
G37*
G36*
G01Y344849D02*
X332286Y345199D01*
Y346069D01*
X332956Y346419D01*
X333131D01*
Y344849D01*
X332956D01*
G37*
G36*
G01X325582Y382540D02*
X324797Y382250D01*
X324161Y382886D01*
X324451Y383671D01*
X324574Y383795D01*
X325706Y382663D01*
X325582Y382540D01*
G37*
G36*
G01X329576Y374050D02*
X328906Y374400D01*
Y375270D01*
X329576Y375620D01*
X329751D01*
Y374050D01*
X329576D01*
G37*
G36*
G01X328340Y379782D02*
X327555Y379492D01*
X326918Y380128D01*
X327208Y380913D01*
X327332Y381037D01*
X328463Y379906D01*
X328340Y379782D01*
G37*
G36*
G01X329576Y370199D02*
X328906Y370549D01*
Y371419D01*
X329576Y371769D01*
X329751D01*
Y370199D01*
X329576D01*
G37*
G36*
G01X329577Y366318D02*
X328907Y366668D01*
Y367538D01*
X329577Y367888D01*
X329752D01*
X329751Y366318D01*
X329577D01*
G37*
G36*
G01X332956Y360449D02*
X332286Y360799D01*
Y361669D01*
X332956Y362019D01*
X333131D01*
Y360449D01*
X332956D01*
G37*
G36*
G01X331470Y364523D02*
X330832Y364118D01*
X330079Y364553D01*
X330110Y365308D01*
X330198Y365460D01*
X331557Y364674D01*
X331470Y364523D01*
G37*
G36*
G01X315125Y400467D02*
X314365Y400817D01*
Y401717D01*
X315125Y402067D01*
X315300D01*
Y400467D01*
X315125D01*
G37*
G36*
G01X295507Y383246D02*
X296145Y383651D01*
X296898Y383216D01*
X296866Y382461D01*
X296779Y382309D01*
X295419Y383095D01*
X295507Y383246D01*
G37*
G36*
G01X298881Y381300D02*
X299519Y381705D01*
X300272Y381270D01*
X300240Y380515D01*
X300153Y380363D01*
X298793Y381149D01*
X298881Y381300D01*
G37*
G36*
G01X309026Y375446D02*
X309664Y375851D01*
X310417Y375416D01*
X310385Y374661D01*
X310298Y374509D01*
X308938Y375295D01*
X309026Y375446D01*
G37*
G36*
G01X305641Y377400D02*
X306279Y377805D01*
X307032Y377370D01*
X307000Y376615D01*
X306913Y376463D01*
X305553Y377249D01*
X305641Y377400D01*
G37*
G36*
G01X302267Y379346D02*
X302905Y379751D01*
X303658Y379316D01*
X303626Y378561D01*
X303539Y378409D01*
X302179Y379195D01*
X302267Y379346D01*
G37*
G36*
G01X321129Y395908D02*
X321914Y396198D01*
X322550Y395561D01*
X322260Y394776D01*
X322136Y394653D01*
X321005Y395784D01*
X321129Y395908D01*
G37*
G36*
G01X337960Y358119D02*
X338630Y357769D01*
Y356899D01*
X337960Y356549D01*
X337785D01*
Y358119D01*
X337960D01*
G37*
G36*
G01Y354219D02*
X338630Y353869D01*
Y352999D01*
X337960Y352649D01*
X337785D01*
Y354219D01*
X337960D01*
G37*
G36*
G01Y350319D02*
X338630Y349969D01*
Y349099D01*
X337960Y348749D01*
X337785D01*
Y350319D01*
X337960D01*
G37*
G36*
G01X330123Y386053D02*
X330883Y385703D01*
Y384803D01*
X330123Y384453D01*
X329948D01*
Y386053D01*
X330123D01*
G37*
G36*
G01X326644Y390392D02*
X327429Y390682D01*
X328066Y390046D01*
X327776Y389261D01*
X327652Y389137D01*
X326521Y390268D01*
X326644Y390392D01*
G37*
G36*
G01X331285Y383197D02*
X332069Y383487D01*
X332706Y382850D01*
X332416Y382066D01*
X332292Y381942D01*
X331161Y383073D01*
X331285Y383197D01*
G37*
G36*
G01X334579Y379520D02*
X335249Y379170D01*
Y378300D01*
X334579Y377950D01*
X334404D01*
Y379520D01*
X334579D01*
G37*
G36*
G01X334580Y371769D02*
X335250Y371419D01*
Y370549D01*
X334580Y370199D01*
X334405D01*
Y371769D01*
X334580D01*
G37*
G36*
G01Y375620D02*
X335250Y375270D01*
Y374400D01*
X334580Y374050D01*
X334405D01*
Y375620D01*
X334580D01*
G37*
G36*
G01X336030Y367668D02*
X336668Y368073D01*
X337421Y367639D01*
X337390Y366884D01*
X337303Y366732D01*
X335943Y367517D01*
X336030Y367668D01*
G37*
G36*
G01X337960Y365893D02*
X338630Y365543D01*
X338631Y364674D01*
X337961Y364323D01*
X337786D01*
Y365893D01*
X337960D01*
G37*
G36*
G01Y362019D02*
X338630Y361669D01*
Y360799D01*
X337960Y360449D01*
X337785D01*
Y362019D01*
X337960D01*
G37*
G36*
G01X323887Y393150D02*
X324671Y393440D01*
X325308Y392803D01*
X325018Y392019D01*
X324894Y391895D01*
X323763Y393026D01*
X323887Y393150D01*
G37*
G36*
G01X319323Y400941D02*
X320083Y400591D01*
Y399691D01*
X319323Y399341D01*
X319148D01*
Y400941D01*
X319323D01*
G37*
G36*
G01X294490Y408957D02*
X293705Y408667D01*
X293068Y409303D01*
X293358Y410088D01*
X293482Y410212D01*
X294613Y409081D01*
X294490Y408957D01*
G37*
G36*
G01X296478Y404997D02*
X295718Y405347D01*
Y406247D01*
X296478Y406597D01*
X296653D01*
Y404997D01*
X296478D01*
G37*
G36*
G01X297576Y406097D02*
X298336Y405747D01*
Y404847D01*
X297576Y404497D01*
X297401D01*
Y406097D01*
X297576D01*
G37*
G36*
G01X295574Y409421D02*
X296359Y409711D01*
X296995Y409075D01*
X296705Y408290D01*
X296582Y408166D01*
X295450Y409297D01*
X295574Y409421D01*
G37*
G36*
G01X319355Y405213D02*
X318595Y405563D01*
Y406463D01*
X319355Y406813D01*
X319530D01*
Y405213D01*
X319355D01*
G37*
G36*
G01X320455Y406813D02*
X321215Y406463D01*
Y405563D01*
X320455Y405213D01*
X320280D01*
Y406813D01*
X320455D01*
G37*
G36*
G01X372715Y-9410D02*
X372667Y-9279D01*
G03X369968Y-9031I-1409J-521D01*
G02X369341Y-9109I-344J205D01*
G01X368548Y-8316D01*
X362804D01*
X360210Y-5722D01*
Y-5647D01*
X359272Y-4709D01*
Y-1928D01*
G03Y-1788I-1400J70D01*
G01Y16944D01*
G03Y17084I-1400J70D01*
G01Y23451D01*
X362708Y26887D01*
Y39808D01*
X364900Y42000D01*
X376980D01*
X381086Y37894D01*
Y29611D01*
G02X380709Y29212I-400J0D01*
G03X379949Y26692I83J-1400D01*
G02Y26053I-241J-320D01*
G03X381579Y23772I843J-1120D01*
G02X382203Y23441I224J-331D01*
G01Y-6549D01*
X379342Y-9410D01*
X372715D01*
G37*
G36*
G01X373500Y578400D02*
X367651Y584249D01*
G02X367702Y584857I283J282D01*
G03X365765Y586837I-812J1143D01*
G02X365183Y586774I-320J239D01*
G03X365000Y586908I-917J-1061D01*
G01X364979Y586921D01*
X364900Y587000D01*
Y591840D01*
G02X365302Y592240I400J0D01*
G03X366322Y592671I9J1402D01*
G02X366900I289J-277D01*
G03Y594613I1011J971D01*
G02X366322I-289J277D01*
G03X365302Y595044I-1011J-971D01*
G02X364900Y595444I-2J400D01*
G01Y603245D01*
X365033Y603292D01*
G03Y605936I-468J1322D01*
G01X364900Y605983D01*
Y610873D01*
X365033Y610920D01*
G03X365405Y611120I-470J1321D01*
G02X365983Y611012I239J-321D01*
G03X367550Y613108I1187J747D01*
G02X367376Y613776I109J385D01*
G01X367704Y614104D01*
X384496D01*
X384700Y613900D01*
Y611906D01*
X384694Y611882D01*
G03X384586Y611005I3493J-875D01*
G01Y606105D01*
G03X384694Y605228I3601J-2D01*
G01X384700Y605204D01*
Y593030D01*
X384694Y593006D01*
G03X384586Y592129I3493J-875D01*
G01Y587229D01*
G03X384694Y586352I3601J-2D01*
G01X384700Y586328D01*
Y583600D01*
X379500Y578400D01*
X377967D01*
G03X375817I-1075J-900D01*
G01X373500D01*
G37*
G36*
G01X426095Y195897D02*
X425335Y196247D01*
Y197147D01*
X426095Y197497D01*
X426270D01*
Y195897D01*
X426095D01*
G37*
G36*
G01Y199797D02*
X425335Y200147D01*
Y201047D01*
X426095Y201397D01*
X426270D01*
Y199797D01*
X426095D01*
G37*
G36*
G01X425587Y202792D02*
X424803Y202502D01*
X424166Y203139D01*
X424456Y203923D01*
X424580Y204047D01*
X425711Y202916D01*
X425587Y202792D01*
G37*
G36*
G01X425483Y189972D02*
X424723Y190322D01*
Y191222D01*
X425483Y191572D01*
X425658D01*
Y189972D01*
X425483D01*
G37*
G36*
G01X423472Y217337D02*
X422802Y217687D01*
Y218557D01*
X423472Y218907D01*
X423647D01*
Y217337D01*
X423472D01*
G37*
G36*
G01X423634Y209103D02*
X422874Y209453D01*
Y210353D01*
X423634Y210703D01*
X423809D01*
Y209103D01*
X423634D01*
G37*
G36*
G01Y213003D02*
X422874Y213353D01*
Y214253D01*
X423634Y214603D01*
X423809D01*
Y213003D01*
X423634D01*
G37*
G36*
G01X427195Y197497D02*
X427955Y197147D01*
Y196247D01*
X427195Y195897D01*
X427020D01*
Y197497D01*
X427195D01*
G37*
G36*
G01X425233Y204700D02*
X426017Y204990D01*
X426654Y204353D01*
X426364Y203569D01*
X426240Y203445D01*
X425109Y204576D01*
X425233Y204700D01*
G37*
G36*
G01X427195Y201397D02*
X427955Y201047D01*
Y200147D01*
X427195Y199797D01*
X427020D01*
Y201397D01*
X427195D01*
G37*
G36*
G01X426583Y191572D02*
X427343Y191222D01*
Y190322D01*
X426583Y189972D01*
X426408D01*
Y191572D01*
X426583D01*
G37*
G36*
G01X424734Y214603D02*
X425494Y214253D01*
Y213353D01*
X424734Y213003D01*
X424559D01*
Y214603D01*
X424734D01*
G37*
G36*
G01Y210703D02*
X425494Y210353D01*
Y209453D01*
X424734Y209103D01*
X424559D01*
Y210703D01*
X424734D01*
G37*
G36*
G01X439233Y195943D02*
X438473Y196293D01*
Y197193D01*
X439233Y197543D01*
X439408D01*
Y195943D01*
X439233D01*
G37*
G36*
G01Y199843D02*
X438473Y200193D01*
Y201093D01*
X439233Y201443D01*
X439408D01*
Y199843D01*
X439233D01*
G37*
G36*
G01Y203743D02*
X438473Y204093D01*
Y204993D01*
X439233Y205343D01*
X439408D01*
Y203743D01*
X439233D01*
G37*
G36*
G01X442212Y191447D02*
X441427Y191157D01*
X440791Y191793D01*
X441081Y192578D01*
X441204Y192702D01*
X442336Y191570D01*
X442212Y191447D01*
G37*
G36*
G01X436991Y217337D02*
X436321Y217687D01*
Y218557D01*
X436991Y218907D01*
X437166D01*
Y217337D01*
X436991D01*
G37*
G36*
G01Y213437D02*
X436321Y213787D01*
Y214657D01*
X436991Y215007D01*
X437166D01*
Y213437D01*
X436991D01*
G37*
G36*
G01X438831Y206625D02*
X438046Y206335D01*
X437410Y206971D01*
X437700Y207756D01*
X437823Y207880D01*
X438955Y206748D01*
X438831Y206625D01*
G37*
G36*
G01X436991Y209437D02*
X436321Y209787D01*
Y210657D01*
X436991Y211007D01*
X437166D01*
Y209437D01*
X436991D01*
G37*
G36*
G01X440333Y198543D02*
X441093Y198193D01*
Y197293D01*
X440333Y196943D01*
X440158D01*
Y198543D01*
X440333D01*
G37*
G36*
G01Y202443D02*
X441093Y202093D01*
Y201193D01*
X440333Y200843D01*
X440158D01*
Y202443D01*
X440333D01*
G37*
G36*
G01X441859Y193356D02*
X442644Y193646D01*
X443280Y193010D01*
X442990Y192225D01*
X442867Y192101D01*
X441735Y193233D01*
X441859Y193356D01*
G37*
G36*
G01X438679Y208335D02*
X439463Y208625D01*
X440100Y207988D01*
X439810Y207204D01*
X439686Y207080D01*
X438555Y208211D01*
X438679Y208335D01*
G37*
G36*
G01X438615Y213081D02*
X439285Y212731D01*
Y211861D01*
X438615Y211511D01*
X438440D01*
Y213081D01*
X438615D01*
G37*
G36*
G01Y217006D02*
X439285Y216656D01*
Y215786D01*
X438615Y215436D01*
X438440D01*
Y217006D01*
X438615D01*
G37*
G36*
G01X423075Y196800D02*
X422315Y197150D01*
Y198050D01*
X423075Y198400D01*
X423250D01*
Y196800D01*
X423075D01*
G37*
G36*
G01X421858Y202253D02*
X421073Y201963D01*
X420437Y202600D01*
X420727Y203385D01*
X420851Y203508D01*
X421982Y202377D01*
X421858Y202253D01*
G37*
G36*
G01X421654Y192745D02*
X421364Y193529D01*
X422001Y194166D01*
X422785Y193876D01*
X422909Y193752D01*
X421778Y192621D01*
X421654Y192745D01*
G37*
G36*
G01X420383Y208437D02*
X419623Y208787D01*
Y209687D01*
X420383Y210037D01*
X420558D01*
Y208437D01*
X420383D01*
G37*
G36*
G01X420092Y215436D02*
X419422Y215786D01*
Y216656D01*
X420092Y217006D01*
X420267D01*
Y215436D01*
X420092D01*
G37*
G36*
G01X420383Y204537D02*
X419623Y204887D01*
Y205787D01*
X420383Y206137D01*
X420558D01*
Y204537D01*
X420383D01*
G37*
G36*
G01X424175Y197000D02*
X424935Y196650D01*
Y195750D01*
X424175Y195400D01*
X424000D01*
Y197000D01*
X424175D01*
G37*
G36*
G01X422212Y203455D02*
X422996Y203745D01*
X423633Y203108D01*
X423343Y202324D01*
X423219Y202200D01*
X422088Y203331D01*
X422212Y203455D01*
G37*
G36*
G01X424175Y200900D02*
X424935Y200550D01*
Y199650D01*
X424175Y199300D01*
X424000D01*
Y200900D01*
X424175D01*
G37*
G36*
G01X423563Y193098D02*
X423853Y192313D01*
X423217Y191677D01*
X422432Y191967D01*
X422308Y192090D01*
X423440Y193222D01*
X423563Y193098D01*
G37*
G36*
G01X421716Y218907D02*
X422386Y218557D01*
Y217687D01*
X421716Y217337D01*
X421541D01*
Y218907D01*
X421716D01*
G37*
G36*
G01X421482Y210037D02*
X422242Y209687D01*
Y208787D01*
X421482Y208437D01*
X421307D01*
Y210037D01*
X421482D01*
G37*
G36*
G01Y206137D02*
X422242Y205787D01*
Y204887D01*
X421482Y204537D01*
X421307D01*
Y206137D01*
X421482D01*
G37*
G36*
G01X436383Y195988D02*
X435623Y196338D01*
Y197238D01*
X436383Y197588D01*
X436558D01*
Y195988D01*
X436383D01*
G37*
G36*
G01Y199888D02*
X435623Y200238D01*
Y201138D01*
X436383Y201488D01*
X436558D01*
Y199888D01*
X436383D01*
G37*
G36*
G01Y192088D02*
X435623Y192438D01*
Y193338D01*
X436383Y193688D01*
X436558D01*
Y192088D01*
X436383D01*
G37*
G36*
G01X433613Y208427D02*
X432853Y208777D01*
Y209677D01*
X433613Y210027D01*
X433788D01*
Y208427D01*
X433613D01*
G37*
G36*
G01X435635Y205552D02*
X434850Y205262D01*
X434214Y205898D01*
X434504Y206683D01*
X434627Y206807D01*
X435759Y205675D01*
X435635Y205552D01*
G37*
G36*
G01X433611Y215436D02*
X432941Y215786D01*
Y216656D01*
X433611Y217006D01*
X433786D01*
Y215436D01*
X433611D01*
G37*
G36*
G01X437481Y196188D02*
X438241Y195838D01*
Y194938D01*
X437481Y194588D01*
X437306D01*
Y196188D01*
X437481D01*
G37*
G36*
G01Y203988D02*
X438241Y203638D01*
Y202738D01*
X437481Y202388D01*
X437306D01*
Y203988D01*
X437481D01*
G37*
G36*
G01Y200088D02*
X438241Y199738D01*
Y198838D01*
X437481Y198488D01*
X437306D01*
Y200088D01*
X437481D01*
G37*
G36*
G01X435480Y207259D02*
X436265Y207549D01*
X436901Y206913D01*
X436611Y206128D01*
X436488Y206004D01*
X435356Y207136D01*
X435480Y207259D01*
G37*
G36*
G01X434713Y210927D02*
X435473Y210577D01*
Y209677D01*
X434713Y209327D01*
X434538D01*
Y210927D01*
X434713D01*
G37*
G36*
G01X435235Y215007D02*
X435905Y214657D01*
Y213787D01*
X435235Y213437D01*
X435060D01*
Y215007D01*
X435235D01*
G37*
G36*
G01Y218907D02*
X435905Y218557D01*
Y217687D01*
X435235Y217337D01*
X435060D01*
Y218907D01*
X435235D01*
G37*
G36*
G01X452763Y195497D02*
X452003Y195847D01*
Y196747D01*
X452763Y197097D01*
X452938D01*
Y195497D01*
X452763D01*
G37*
G36*
G01Y199397D02*
X452003Y199747D01*
Y200647D01*
X452763Y200997D01*
X452938D01*
Y199397D01*
X452763D01*
G37*
G36*
G01Y203297D02*
X452003Y203647D01*
Y204547D01*
X452763Y204897D01*
X452938D01*
Y203297D01*
X452763D01*
G37*
G36*
G01Y191597D02*
X452003Y191947D01*
Y192847D01*
X452763Y193197D01*
X452938D01*
Y191597D01*
X452763D01*
G37*
G36*
G01X453891Y215436D02*
X453221Y215786D01*
Y216656D01*
X453891Y217006D01*
X454066D01*
Y215436D01*
X453891D01*
G37*
G36*
G01X452763Y207197D02*
X452003Y207547D01*
Y208447D01*
X452763Y208797D01*
X452938D01*
Y207197D01*
X452763D01*
G37*
G36*
G01X453863Y197097D02*
X454623Y196747D01*
Y195847D01*
X453863Y195497D01*
X453688D01*
Y197097D01*
X453863D01*
G37*
G36*
G01Y200997D02*
X454623Y200647D01*
Y199747D01*
X453863Y199397D01*
X453688D01*
Y200997D01*
X453863D01*
G37*
G36*
G01Y204897D02*
X454623Y204547D01*
Y203647D01*
X453863Y203297D01*
X453688D01*
Y204897D01*
X453863D01*
G37*
G36*
G01Y193197D02*
X454623Y192847D01*
Y191947D01*
X453863Y191597D01*
X453688D01*
Y193197D01*
X453863D01*
G37*
G36*
G01X455515Y218907D02*
X456185Y218557D01*
Y217687D01*
X455515Y217337D01*
X455340D01*
Y218907D01*
X455515D01*
G37*
G36*
G01Y215007D02*
X456185Y214657D01*
Y213787D01*
X455515Y213437D01*
X455340D01*
Y215007D01*
X455515D01*
G37*
G36*
G01X453863Y208797D02*
X454623Y208447D01*
Y207547D01*
X453863Y207197D01*
X453688D01*
Y208797D01*
X453863D01*
G37*
G36*
G01X467985Y196333D02*
X467225Y196683D01*
Y197583D01*
X467985Y197933D01*
X468160D01*
Y196333D01*
X467985D01*
G37*
G36*
G01Y200233D02*
X467225Y200583D01*
Y201483D01*
X467985Y201833D01*
X468160D01*
Y200233D01*
X467985D01*
G37*
G36*
G01Y203833D02*
X467225Y204183D01*
Y205083D01*
X467985Y205433D01*
X468160D01*
Y203833D01*
X467985D01*
G37*
G36*
G01X471182Y190852D02*
X470397Y190562D01*
X469761Y191198D01*
X470051Y191983D01*
X470174Y192107D01*
X471306Y190975D01*
X471182Y190852D01*
G37*
G36*
G01X467413Y213424D02*
X466653Y213774D01*
Y214674D01*
X467413Y215024D01*
X467588D01*
Y213424D01*
X467413D01*
G37*
G36*
G01Y209524D02*
X466653Y209874D01*
Y210774D01*
X467413Y211124D01*
X467588D01*
Y209524D01*
X467413D01*
G37*
G36*
G01X469085Y197933D02*
X469845Y197583D01*
Y196683D01*
X469085Y196333D01*
X468910D01*
Y197933D01*
X469085D01*
G37*
G36*
G01Y201833D02*
X469845Y201483D01*
Y200583D01*
X469085Y200233D01*
X468910D01*
Y201833D01*
X469085D01*
G37*
G36*
G01X470829Y192761D02*
X471613Y193051D01*
X472250Y192414D01*
X471960Y191630D01*
X471836Y191506D01*
X470705Y192637D01*
X470829Y192761D01*
G37*
G36*
G01X468513Y215024D02*
X469273Y214674D01*
Y213774D01*
X468513Y213424D01*
X468338D01*
Y215024D01*
X468513D01*
G37*
G36*
G01X469035Y218907D02*
X469705Y218557D01*
Y217687D01*
X469035Y217337D01*
X468860D01*
Y218907D01*
X469035D01*
G37*
G36*
G01X468513Y211124D02*
X469273Y210774D01*
Y209874D01*
X468513Y209524D01*
X468338D01*
Y211124D01*
X468513D01*
G37*
G36*
G01X469085Y205733D02*
X469845Y205383D01*
Y204483D01*
X469085Y204133D01*
X468910D01*
Y205733D01*
X469085D01*
G37*
G36*
G01X449743Y197283D02*
X448983Y197633D01*
Y198533D01*
X449743Y198883D01*
X449918D01*
Y197283D01*
X449743D01*
G37*
G36*
G01Y201183D02*
X448983Y201533D01*
Y202433D01*
X449743Y202783D01*
X449918D01*
Y201183D01*
X449743D01*
G37*
G36*
G01Y189483D02*
X448983Y189833D01*
Y190733D01*
X449743Y191083D01*
X449918D01*
Y189483D01*
X449743D01*
G37*
G36*
G01Y193383D02*
X448983Y193733D01*
Y194633D01*
X449743Y194983D01*
X449918D01*
Y193383D01*
X449743D01*
G37*
G36*
G01X450511Y217337D02*
X449841Y217687D01*
Y218557D01*
X450511Y218907D01*
X450686D01*
Y217337D01*
X450511D01*
G37*
G36*
G01Y213437D02*
X449841Y213787D01*
Y214657D01*
X450511Y215007D01*
X450686D01*
Y213437D01*
X450511D01*
G37*
G36*
G01X449743Y205083D02*
X448983Y205433D01*
Y206333D01*
X449743Y206683D01*
X449918D01*
Y205083D01*
X449743D01*
G37*
G36*
G01X450843Y198883D02*
X451603Y198533D01*
Y197633D01*
X450843Y197283D01*
X450668D01*
Y198883D01*
X450843D01*
G37*
G36*
G01Y202783D02*
X451603Y202433D01*
Y201533D01*
X450843Y201183D01*
X450668D01*
Y202783D01*
X450843D01*
G37*
G36*
G01Y191083D02*
X451603Y190733D01*
Y189833D01*
X450843Y189483D01*
X450668D01*
Y191083D01*
X450843D01*
G37*
G36*
G01Y194983D02*
X451603Y194633D01*
Y193733D01*
X450843Y193383D01*
X450668D01*
Y194983D01*
X450843D01*
G37*
G36*
G01Y206683D02*
X451603Y206333D01*
Y205433D01*
X450843Y205083D01*
X450668D01*
Y206683D01*
X450843D01*
G37*
G36*
G01X452135Y217006D02*
X452805Y216656D01*
Y215786D01*
X452135Y215436D01*
X451960D01*
Y217006D01*
X452135D01*
G37*
G36*
G01X464959Y194359D02*
X464199Y194709D01*
Y195609D01*
X464959Y195959D01*
X465134D01*
Y194359D01*
X464959D01*
G37*
G36*
G01Y198259D02*
X464199Y198609D01*
Y199509D01*
X464959Y199859D01*
X465134D01*
Y198259D01*
X464959D01*
G37*
G36*
G01X463834Y203765D02*
X463074Y204115D01*
Y205015D01*
X463834Y205365D01*
X464009D01*
Y203765D01*
X463834D01*
G37*
G36*
G01X467129Y190631D02*
X466344Y190341D01*
X465707Y190977D01*
X465997Y191762D01*
X466121Y191886D01*
X467253Y190754D01*
X467129Y190631D01*
G37*
G36*
G01X464031Y217337D02*
X463361Y217687D01*
Y218557D01*
X464031Y218907D01*
X464206D01*
Y217337D01*
X464031D01*
G37*
G36*
G01X463834Y207665D02*
X463074Y208015D01*
Y208915D01*
X463834Y209265D01*
X464009D01*
Y207665D01*
X463834D01*
G37*
G36*
G01Y211565D02*
X463074Y211915D01*
Y212815D01*
X463834Y213165D01*
X464009D01*
Y211565D01*
X463834D01*
G37*
G36*
G01X466059Y195959D02*
X466819Y195609D01*
Y194709D01*
X466059Y194359D01*
X465884D01*
Y195959D01*
X466059D01*
G37*
G36*
G01X464934Y205365D02*
X465694Y205015D01*
Y204115D01*
X464934Y203765D01*
X464759D01*
Y205365D01*
X464934D01*
G37*
G36*
G01X466059Y199859D02*
X466819Y199509D01*
Y198609D01*
X466059Y198259D01*
X465884D01*
Y199859D01*
X466059D01*
G37*
G36*
G01X466729Y192587D02*
X467514Y192876D01*
X468150Y192240D01*
X467860Y191455D01*
X467737Y191331D01*
X466605Y192463D01*
X466729Y192587D01*
G37*
G36*
G01X464934Y209265D02*
X465694Y208915D01*
Y208015D01*
X464934Y207665D01*
X464759D01*
Y209265D01*
X464934D01*
G37*
G36*
G01Y213165D02*
X465694Y212815D01*
Y211915D01*
X464934Y211565D01*
X464759D01*
Y213165D01*
X464934D01*
G37*
G36*
G01X474170Y215436D02*
X473500Y215786D01*
Y216656D01*
X474170Y217006D01*
X474345D01*
Y215436D01*
X474170D01*
G37*
G36*
G01Y211536D02*
X473500Y211886D01*
Y212756D01*
X474170Y213106D01*
X474345D01*
Y211536D01*
X474170D01*
G37*
G36*
G01X474534Y208920D02*
X473774Y209270D01*
Y210170D01*
X474534Y210520D01*
X474709D01*
Y208920D01*
X474534D01*
G37*
G36*
G01X475794Y218907D02*
X476464Y218557D01*
Y217687D01*
X475794Y217337D01*
X475619D01*
Y218907D01*
X475794D01*
G37*
G36*
G01X475633Y209720D02*
X476393Y209370D01*
Y208470D01*
X475633Y208120D01*
X475458D01*
Y209720D01*
X475633D01*
G37*
G36*
G01X475794Y215007D02*
X476464Y214657D01*
Y213787D01*
X475794Y213437D01*
X475619D01*
Y215007D01*
X475794D01*
G37*
G36*
G01X476303Y194284D02*
X475519Y193994D01*
X474882Y194631D01*
X475172Y195415D01*
X475296Y195539D01*
X476427Y194408D01*
X476303Y194284D01*
G37*
G36*
G01X473546Y197042D02*
X472761Y196752D01*
X472124Y197388D01*
X472414Y198173D01*
X472538Y198297D01*
X473669Y197166D01*
X473546Y197042D01*
G37*
G36*
G01X471515Y202977D02*
X470755Y203327D01*
Y204227D01*
X471515Y204577D01*
X471690D01*
Y202977D01*
X471515D01*
G37*
G36*
G01X470790Y217326D02*
X470120Y217676D01*
Y218546D01*
X470790Y218896D01*
X470965D01*
Y217326D01*
X470790D01*
G37*
G36*
G01Y213419D02*
X470120Y213769D01*
Y214639D01*
X470790Y214989D01*
X470965D01*
Y213419D01*
X470790D01*
G37*
G36*
G01X471313Y209743D02*
X470643Y210093D01*
Y210963D01*
X471313Y211313D01*
X471488D01*
Y209743D01*
X471313D01*
G37*
G36*
G01X475950Y196193D02*
X476735Y196483D01*
X477371Y195847D01*
X477081Y195062D01*
X476958Y194938D01*
X475826Y196070D01*
X475950Y196193D01*
G37*
G36*
G01X473192Y198951D02*
X473977Y199241D01*
X474614Y198605D01*
X474324Y197820D01*
X474200Y197696D01*
X473069Y198827D01*
X473192Y198951D01*
G37*
G36*
G01X472615Y204577D02*
X473375Y204227D01*
Y203327D01*
X472615Y202977D01*
X472440D01*
Y204577D01*
X472615D01*
G37*
G36*
G01X472415Y217017D02*
X473085Y216667D01*
Y215797D01*
X472415Y215447D01*
X472240D01*
Y217017D01*
X472415D01*
G37*
G36*
G01X472416Y211726D02*
X473086Y211376D01*
Y210506D01*
X472416Y210156D01*
X472241D01*
Y211726D01*
X472416D01*
G37*
G36*
G01X430214Y203531D02*
X430974Y203181D01*
Y202281D01*
X430214Y201931D01*
X430039D01*
Y203531D01*
X430214D01*
G37*
G36*
G01Y199631D02*
X430974Y199281D01*
Y198381D01*
X430214Y198031D01*
X430039D01*
Y199631D01*
X430214D01*
G37*
G36*
G01Y195731D02*
X430974Y195381D01*
Y194481D01*
X430214Y194131D01*
X430039D01*
Y195731D01*
X430214D01*
G37*
G36*
G01Y191831D02*
X430974Y191481D01*
Y190581D01*
X430214Y190231D01*
X430039D01*
Y191831D01*
X430214D01*
G37*
G36*
G01X428476Y218907D02*
X429146Y218557D01*
Y217687D01*
X428476Y217337D01*
X428301D01*
Y218907D01*
X428476D01*
G37*
G36*
G01X428672Y207662D02*
X429432Y207312D01*
Y206412D01*
X428672Y206062D01*
X428497D01*
Y207662D01*
X428672D01*
G37*
G36*
G01X427878Y211162D02*
X428638Y210812D01*
Y209912D01*
X427878Y209562D01*
X427703D01*
Y211162D01*
X427878D01*
G37*
G36*
G01Y215062D02*
X428638Y214712D01*
Y213812D01*
X427878Y213462D01*
X427703D01*
Y215062D01*
X427878D01*
G37*
G36*
G01X457783Y197193D02*
X458453Y196843D01*
Y195973D01*
X457783Y195623D01*
X457608D01*
Y197193D01*
X457783D01*
G37*
G36*
G01X458894Y204685D02*
X459654Y204335D01*
Y203435D01*
X458894Y203085D01*
X458719D01*
Y204685D01*
X458894D01*
G37*
G36*
G01X461038Y186322D02*
X461798Y185972D01*
Y185072D01*
X461038Y184722D01*
X460863D01*
Y186322D01*
X461038D01*
G37*
G36*
G01X457783Y193293D02*
X458453Y192943D01*
Y192073D01*
X457783Y191723D01*
X457608D01*
Y193293D01*
X457783D01*
G37*
G36*
G01X458805Y189463D02*
X459526Y189689D01*
X460141Y189074D01*
X459915Y188353D01*
X459791Y188229D01*
X458681Y189339D01*
X458805Y189463D01*
G37*
G36*
G01X458895Y217006D02*
X459565Y216656D01*
Y215786D01*
X458895Y215436D01*
X458720D01*
Y217006D01*
X458895D01*
G37*
G36*
G01X458894Y208585D02*
X459654Y208235D01*
Y207335D01*
X458894Y206985D01*
X458719D01*
Y208585D01*
X458894D01*
G37*
G36*
G01Y212485D02*
X459654Y212135D01*
Y211235D01*
X458894Y210885D01*
X458719D01*
Y212485D01*
X458894D01*
G37*
G36*
G01X433235Y197957D02*
X433995Y197607D01*
Y196707D01*
X433235Y196357D01*
X433060D01*
Y197957D01*
X433235D01*
G37*
G36*
G01Y201857D02*
X433995Y201507D01*
Y200607D01*
X433235Y200257D01*
X433060D01*
Y201857D01*
X433235D01*
G37*
G36*
G01Y194057D02*
X433995Y193707D01*
Y192807D01*
X433235Y192457D01*
X433060D01*
Y194057D01*
X433235D01*
G37*
G36*
G01X431856Y217017D02*
X432526Y216667D01*
Y215797D01*
X431856Y215447D01*
X431681D01*
Y217017D01*
X431856D01*
G37*
G36*
G01X431855Y213045D02*
X432525Y212695D01*
Y211825D01*
X431855Y211475D01*
X431680D01*
Y213045D01*
X431855D01*
G37*
G36*
G01X460623Y197350D02*
X461293Y197000D01*
Y196129D01*
X460623Y195779D01*
X460448D01*
Y197350D01*
X460623D01*
G37*
G36*
G01X461914Y204357D02*
X462674Y204007D01*
Y203107D01*
X461914Y202757D01*
X461739D01*
Y204357D01*
X461914D01*
G37*
G36*
G01X461995Y193041D02*
X462779Y193331D01*
X463416Y192694D01*
X463126Y191910D01*
X463002Y191786D01*
X461871Y192917D01*
X461995Y193041D01*
G37*
G36*
G01X462275Y218907D02*
X462945Y218557D01*
Y217687D01*
X462275Y217337D01*
X462100D01*
Y218907D01*
X462275D01*
G37*
G36*
G01X461914Y208257D02*
X462674Y207907D01*
Y207007D01*
X461914Y206657D01*
X461739D01*
Y208257D01*
X461914D01*
G37*
G36*
G01Y212157D02*
X462674Y211807D01*
Y210907D01*
X461914Y210557D01*
X461739D01*
Y212157D01*
X461914D01*
G37*
G36*
G01X429115Y197531D02*
X428355Y197881D01*
Y198781D01*
X429115Y199131D01*
X429290D01*
Y197531D01*
X429115D01*
G37*
G36*
G01Y201431D02*
X428355Y201781D01*
Y202681D01*
X429115Y203031D01*
X429290D01*
Y201431D01*
X429115D01*
G37*
G36*
G01Y193631D02*
X428355Y193981D01*
Y194881D01*
X429115Y195231D01*
X429290D01*
Y193631D01*
X429115D01*
G37*
G36*
G01Y189731D02*
X428355Y190081D01*
Y190981D01*
X429115Y191331D01*
X429290D01*
Y189731D01*
X429115D01*
G37*
G36*
G01X426778Y209562D02*
X426018Y209912D01*
Y210812D01*
X426778Y211162D01*
X426953D01*
Y209562D01*
X426778D01*
G37*
G36*
G01Y213462D02*
X426018Y213812D01*
Y214712D01*
X426778Y215062D01*
X426953D01*
Y213462D01*
X426778D01*
G37*
G36*
G01X456683Y195623D02*
X456013Y195973D01*
Y196843D01*
X456683Y197193D01*
X456858D01*
Y195623D01*
X456683D01*
G37*
G36*
G01X456428Y201987D02*
X456138Y202772D01*
X456774Y203408D01*
X457559Y203118D01*
X457683Y202995D01*
X456551Y201863D01*
X456428Y201987D01*
G37*
G36*
G01X459938Y184522D02*
X459178Y184872D01*
Y185772D01*
X459938Y186122D01*
X460113D01*
Y184522D01*
X459938D01*
G37*
G36*
G01X456683Y191723D02*
X456013Y192073D01*
Y192943D01*
X456683Y193293D01*
X456858D01*
Y191723D01*
X456683D01*
G37*
G36*
G01X458917Y187795D02*
X458196Y187569D01*
X457581Y188184D01*
X457807Y188905D01*
X457931Y189029D01*
X459041Y187919D01*
X458917Y187795D01*
G37*
G36*
G01X457271Y217337D02*
X456601Y217687D01*
Y218557D01*
X457271Y218907D01*
X457446D01*
Y217337D01*
X457271D01*
G37*
G36*
G01Y213437D02*
X456601Y213787D01*
Y214657D01*
X457271Y215007D01*
X457446D01*
Y213437D01*
X457271D01*
G37*
G36*
G01X457794Y209485D02*
X457034Y209835D01*
Y210735D01*
X457794Y211085D01*
X457969D01*
Y209485D01*
X457794D01*
G37*
G36*
G01Y205585D02*
X457034Y205935D01*
Y206835D01*
X457794Y207185D01*
X457969D01*
Y205585D01*
X457794D01*
G37*
G36*
G01X479278Y203006D02*
X478493Y202716D01*
X477857Y203352D01*
X478146Y204137D01*
X478270Y204261D01*
X479402Y203129D01*
X479278Y203006D01*
G37*
G36*
G01X477550Y217337D02*
X476880Y217687D01*
Y218557D01*
X477550Y218907D01*
X477725D01*
Y217337D01*
X477550D01*
G37*
G36*
G01Y213437D02*
X476880Y213787D01*
Y214657D01*
X477550Y215007D01*
X477725D01*
Y213437D01*
X477550D01*
G37*
G36*
G01X477553Y209019D02*
X476883Y209369D01*
Y210239D01*
X477553Y210589D01*
X477728D01*
Y209019D01*
X477553D01*
G37*
G36*
G01Y205323D02*
X476793Y205673D01*
Y206573D01*
X477553Y206923D01*
X477728D01*
Y205323D01*
X477553D01*
G37*
G36*
G01X432135Y196357D02*
X431375Y196707D01*
Y197607D01*
X432135Y197957D01*
X432310D01*
Y196357D01*
X432135D01*
G37*
G36*
G01Y200257D02*
X431375Y200607D01*
Y201507D01*
X432135Y201857D01*
X432310D01*
Y200257D01*
X432135D01*
G37*
G36*
G01Y192457D02*
X431375Y192807D01*
Y193707D01*
X432135Y194057D01*
X432310D01*
Y192457D01*
X432135D01*
G37*
G36*
G01X430231Y217326D02*
X429561Y217676D01*
Y218546D01*
X430231Y218896D01*
X430406D01*
Y217326D01*
X430231D01*
G37*
G36*
G01Y213437D02*
X429561Y213787D01*
Y214657D01*
X430231Y215007D01*
X430406D01*
Y213437D01*
X430231D01*
G37*
G36*
G01Y209593D02*
X429561Y209943D01*
Y210813D01*
X430231Y211163D01*
X430406D01*
Y209593D01*
X430231D01*
G37*
G36*
G01X459523Y195779D02*
X458853Y196129D01*
Y197000D01*
X459523Y197350D01*
X459698D01*
Y195779D01*
X459523D01*
G37*
G36*
G01X460814Y202757D02*
X460054Y203107D01*
Y204007D01*
X460814Y204357D01*
X460989D01*
Y202757D01*
X460814D01*
G37*
G36*
G01X462348Y191132D02*
X461563Y190842D01*
X460927Y191478D01*
X461217Y192263D01*
X461340Y192387D01*
X462472Y191255D01*
X462348Y191132D01*
G37*
G36*
G01X460651Y215436D02*
X459981Y215786D01*
Y216656D01*
X460651Y217006D01*
X460826D01*
Y215436D01*
X460651D01*
G37*
G36*
G01X460814Y210557D02*
X460054Y210907D01*
Y211807D01*
X460814Y212157D01*
X460989D01*
Y210557D01*
X460814D01*
G37*
G36*
G01Y206657D02*
X460054Y207007D01*
Y207907D01*
X460814Y208257D01*
X460989D01*
Y206657D01*
X460814D01*
G37*
G36*
G01X431299Y249981D02*
Y247967D01*
X427732Y244400D01*
X423666D01*
G03X421522I-1072J-904D01*
G01X420896D01*
G02X420523Y244944I0J400D01*
G03X418970Y246828I-1309J503D01*
G02X418500Y247221I-70J394D01*
G01Y250500D01*
X420200Y252200D01*
Y253916D01*
G02X420792Y254267I400J0D01*
G03Y256727I672J1230D01*
G02X420200Y257078I-192J351D01*
G01Y259000D01*
X424318Y263118D01*
X425732D01*
X425742Y263117D01*
G03X426080I169J1593D01*
G01X426090Y263118D01*
X426864D01*
X427663Y263917D01*
Y266263D01*
X428800Y267400D01*
X432900D01*
X434100Y266200D01*
Y258300D01*
X433580Y257780D01*
G02X432921Y257926I-283J283D01*
G03X431601Y256044I-1317J-480D01*
G02X432000Y255644I-1J-400D01*
G01Y250682D01*
X431299Y249981D01*
G37*
G36*
G01X423472Y225137D02*
X422802Y225487D01*
Y226357D01*
X423472Y226707D01*
X423647D01*
Y225137D01*
X423472D01*
G37*
G36*
G01Y221237D02*
X422802Y221587D01*
Y222457D01*
X423472Y222807D01*
X423647D01*
Y221237D01*
X423472D01*
G37*
G36*
G01X423471Y229061D02*
X422801Y229411D01*
Y230281D01*
X423471Y230631D01*
X423646D01*
Y229061D01*
X423471D01*
G37*
G36*
G01X425096Y224806D02*
X425766Y224456D01*
Y223586D01*
X425096Y223236D01*
X424921D01*
Y224806D01*
X425096D01*
G37*
G36*
G01X425095Y228706D02*
X425765Y228356D01*
Y227486D01*
X425095Y227136D01*
X424920D01*
Y228706D01*
X425095D01*
G37*
G36*
G01X425096Y220906D02*
X425766Y220556D01*
Y219686D01*
X425096Y219336D01*
X424921D01*
Y220906D01*
X425096D01*
G37*
G36*
G01X426357Y235887D02*
X427079Y236113D01*
X427694Y235499D01*
X427467Y234777D01*
X427344Y234653D01*
X426234Y235764D01*
X426357Y235887D01*
G37*
G36*
G01X424587Y238866D02*
X424111Y239454D01*
X424454Y240252D01*
X425209Y240308D01*
X425369Y240239D01*
X424746Y238797D01*
X424587Y238866D01*
G37*
G36*
G01X436991Y225137D02*
X436321Y225487D01*
Y226357D01*
X436991Y226707D01*
X437166D01*
Y225137D01*
X436991D01*
G37*
G36*
G01Y221237D02*
X436321Y221587D01*
Y222457D01*
X436991Y222807D01*
X437166D01*
Y221237D01*
X436991D01*
G37*
G36*
G01Y229062D02*
X436321Y229412D01*
Y230282D01*
X436991Y230632D01*
X437166D01*
Y229062D01*
X436991D01*
G37*
G36*
G01X438615Y220906D02*
X439285Y220556D01*
Y219686D01*
X438615Y219336D01*
X438440D01*
Y220906D01*
X438615D01*
G37*
G36*
G01Y224806D02*
X439285Y224456D01*
Y223586D01*
X438615Y223236D01*
X438440D01*
Y224806D01*
X438615D01*
G37*
G36*
G01Y228706D02*
X439285Y228356D01*
Y227486D01*
X438615Y227136D01*
X438440D01*
Y228706D01*
X438615D01*
G37*
G36*
G01Y232557D02*
X439285Y232207D01*
Y231337D01*
X438615Y230987D01*
X438440D01*
Y232557D01*
X438615D01*
G37*
G36*
G01Y236481D02*
X439285Y236131D01*
Y235261D01*
X438615Y234911D01*
X438440D01*
Y236481D01*
X438615D01*
G37*
G36*
G01X420092Y227136D02*
X419422Y227486D01*
Y228356D01*
X420092Y228706D01*
X420267D01*
Y227136D01*
X420092D01*
G37*
G36*
G01Y223236D02*
X419422Y223586D01*
Y224456D01*
X420092Y224806D01*
X420267D01*
Y223236D01*
X420092D01*
G37*
G36*
G01Y219336D02*
X419422Y219686D01*
Y220556D01*
X420092Y220906D01*
X420267D01*
Y219336D01*
X420092D01*
G37*
G36*
G01X420091Y231011D02*
X419421Y231361D01*
Y232231D01*
X420091Y232581D01*
X420266D01*
Y231011D01*
X420091D01*
G37*
G36*
G01X421716Y222807D02*
X422386Y222457D01*
Y221587D01*
X421716Y221237D01*
X421541D01*
Y222807D01*
X421716D01*
G37*
G36*
G01Y226707D02*
X422386Y226357D01*
Y225487D01*
X421716Y225137D01*
X421541D01*
Y226707D01*
X421716D01*
G37*
G36*
G01Y230631D02*
X422386Y230281D01*
Y229411D01*
X421716Y229061D01*
X421541D01*
Y230631D01*
X421716D01*
G37*
G36*
G01X423928Y234449D02*
X423983Y233695D01*
X423243Y233237D01*
X422593Y233623D01*
X422500Y233771D01*
X423836Y234598D01*
X423928Y234449D01*
G37*
G36*
G01X433612Y227136D02*
X432942Y227486D01*
Y228356D01*
X433612Y228706D01*
X433787D01*
Y227136D01*
X433612D01*
G37*
G36*
G01X433611Y223236D02*
X432941Y223586D01*
Y224456D01*
X433611Y224806D01*
X433786D01*
Y223236D01*
X433611D01*
G37*
G36*
G01Y219336D02*
X432941Y219686D01*
Y220556D01*
X433611Y220906D01*
X433786D01*
Y219336D01*
X433611D01*
G37*
G36*
G01X433612Y231036D02*
X432942Y231386D01*
Y232256D01*
X433612Y232606D01*
X433787D01*
Y231036D01*
X433612D01*
G37*
G36*
G01X435235Y222807D02*
X435905Y222457D01*
Y221587D01*
X435235Y221237D01*
X435060D01*
Y222807D01*
X435235D01*
G37*
G36*
G01Y226707D02*
X435905Y226357D01*
Y225487D01*
X435235Y225137D01*
X435060D01*
Y226707D01*
X435235D01*
G37*
G36*
G01Y230631D02*
X435905Y230281D01*
Y229411D01*
X435235Y229061D01*
X435060D01*
Y230631D01*
X435235D01*
G37*
G36*
G01X434270Y235300D02*
X433549Y235528D01*
X433398Y236385D01*
X433997Y236846D01*
X434170Y236876D01*
X434442Y235330D01*
X434270Y235300D01*
G37*
G36*
G01X453891Y223236D02*
X453221Y223586D01*
Y224456D01*
X453891Y224806D01*
X454066D01*
Y223236D01*
X453891D01*
G37*
G36*
G01Y227136D02*
X453221Y227486D01*
Y228356D01*
X453891Y228706D01*
X454066D01*
Y227136D01*
X453891D01*
G37*
G36*
G01Y219336D02*
X453221Y219686D01*
Y220556D01*
X453891Y220906D01*
X454066D01*
Y219336D01*
X453891D01*
G37*
G36*
G01Y230987D02*
X453221Y231337D01*
Y232207D01*
X453891Y232557D01*
X454066D01*
Y230987D01*
X453891D01*
G37*
G36*
G01Y238836D02*
X453221Y239186D01*
Y240056D01*
X453891Y240406D01*
X454066D01*
Y238836D01*
X453891D01*
G37*
G36*
G01Y234911D02*
X453221Y235261D01*
Y236131D01*
X453891Y236481D01*
X454066D01*
Y234911D01*
X453891D01*
G37*
G36*
G01Y242736D02*
X453221Y243086D01*
Y243956D01*
X453891Y244306D01*
X454066D01*
Y242736D01*
X453891D01*
G37*
G36*
G01X455515Y222807D02*
X456185Y222457D01*
Y221587D01*
X455515Y221237D01*
X455340D01*
Y222807D01*
X455515D01*
G37*
G36*
G01Y226707D02*
X456185Y226357D01*
Y225487D01*
X455515Y225137D01*
X455340D01*
Y226707D01*
X455515D01*
G37*
G36*
G01Y230632D02*
X456185Y230282D01*
Y229412D01*
X455515Y229062D01*
X455340D01*
Y230632D01*
X455515D01*
G37*
G36*
G01Y234556D02*
X456185Y234206D01*
Y233336D01*
X455515Y232986D01*
X455340D01*
Y234556D01*
X455515D01*
G37*
G36*
G01Y238407D02*
X456185Y238057D01*
Y237187D01*
X455515Y236837D01*
X455340D01*
Y238407D01*
X455515D01*
G37*
G36*
G01Y242307D02*
X456185Y241957D01*
Y241087D01*
X455515Y240737D01*
X455340D01*
Y242307D01*
X455515D01*
G37*
G36*
G01X456534Y249616D02*
X457231Y249907D01*
X457900Y249350D01*
X457740Y248611D01*
X457628Y248477D01*
X456422Y249482D01*
X456534Y249616D01*
G37*
G36*
G01X467411Y219336D02*
X466741Y219686D01*
Y220556D01*
X467411Y220906D01*
X467586D01*
Y219336D01*
X467411D01*
G37*
G36*
G01Y223236D02*
X466741Y223586D01*
Y224456D01*
X467411Y224806D01*
X467586D01*
Y223236D01*
X467411D01*
G37*
G36*
G01Y227136D02*
X466741Y227486D01*
Y228356D01*
X467411Y228706D01*
X467586D01*
Y227136D01*
X467411D01*
G37*
G36*
G01Y230987D02*
X466741Y231337D01*
Y232207D01*
X467411Y232557D01*
X467586D01*
Y230987D01*
X467411D01*
G37*
G36*
G01Y234911D02*
X466741Y235261D01*
Y236131D01*
X467411Y236481D01*
X467586D01*
Y234911D01*
X467411D01*
G37*
G36*
G01Y238836D02*
X466741Y239186D01*
Y240056D01*
X467411Y240406D01*
X467586D01*
Y238836D01*
X467411D01*
G37*
G36*
G01Y246636D02*
X466741Y246986D01*
Y247856D01*
X467411Y248206D01*
X467586D01*
Y246636D01*
X467411D01*
G37*
G36*
G01Y242736D02*
X466741Y243086D01*
Y243956D01*
X467411Y244306D01*
X467586D01*
Y242736D01*
X467411D01*
G37*
G36*
G01X469035Y222807D02*
X469705Y222457D01*
Y221587D01*
X469035Y221237D01*
X468860D01*
Y222807D01*
X469035D01*
G37*
G36*
G01Y226707D02*
X469705Y226357D01*
Y225487D01*
X469035Y225137D01*
X468860D01*
Y226707D01*
X469035D01*
G37*
G36*
G01Y230632D02*
X469705Y230282D01*
Y229412D01*
X469035Y229062D01*
X468860D01*
Y230632D01*
X469035D01*
G37*
G36*
G01Y234556D02*
X469705Y234206D01*
Y233336D01*
X469035Y232986D01*
X468860D01*
Y234556D01*
X469035D01*
G37*
G36*
G01Y242307D02*
X469705Y241957D01*
Y241087D01*
X469035Y240737D01*
X468860D01*
Y242307D01*
X469035D01*
G37*
G36*
G01Y238407D02*
X469705Y238057D01*
Y237187D01*
X469035Y236837D01*
X468860D01*
Y238407D01*
X469035D01*
G37*
G36*
G01Y250107D02*
X469705Y249757D01*
Y248887D01*
X469035Y248537D01*
X468860D01*
Y250107D01*
X469035D01*
G37*
G36*
G01Y246207D02*
X469705Y245857D01*
Y244987D01*
X469035Y244637D01*
X468860D01*
Y246207D01*
X469035D01*
G37*
G36*
G01X450511Y225137D02*
X449841Y225487D01*
Y226357D01*
X450511Y226707D01*
X450686D01*
Y225137D01*
X450511D01*
G37*
G36*
G01Y221237D02*
X449841Y221587D01*
Y222457D01*
X450511Y222807D01*
X450686D01*
Y221237D01*
X450511D01*
G37*
G36*
G01Y229062D02*
X449841Y229412D01*
Y230282D01*
X450511Y230632D01*
X450686D01*
Y229062D01*
X450511D01*
G37*
G36*
G01Y232986D02*
X449841Y233336D01*
Y234206D01*
X450511Y234556D01*
X450686D01*
Y232986D01*
X450511D01*
G37*
G36*
G01Y240737D02*
X449841Y241087D01*
Y241957D01*
X450511Y242307D01*
X450686D01*
Y240737D01*
X450511D01*
G37*
G36*
G01Y236837D02*
X449841Y237187D01*
Y238057D01*
X450511Y238407D01*
X450686D01*
Y236837D01*
X450511D01*
G37*
G36*
G01Y244637D02*
X449841Y244987D01*
Y245857D01*
X450511Y246207D01*
X450686D01*
Y244637D01*
X450511D01*
G37*
G36*
G01X452135Y220906D02*
X452805Y220556D01*
Y219686D01*
X452135Y219336D01*
X451960D01*
Y220906D01*
X452135D01*
G37*
G36*
G01Y224806D02*
X452805Y224456D01*
Y223586D01*
X452135Y223236D01*
X451960D01*
Y224806D01*
X452135D01*
G37*
G36*
G01Y228706D02*
X452805Y228356D01*
Y227486D01*
X452135Y227136D01*
X451960D01*
Y228706D01*
X452135D01*
G37*
G36*
G01Y232557D02*
X452805Y232207D01*
Y231337D01*
X452135Y230987D01*
X451960D01*
Y232557D01*
X452135D01*
G37*
G36*
G01Y236481D02*
X452805Y236131D01*
Y235261D01*
X452135Y234911D01*
X451960D01*
Y236481D01*
X452135D01*
G37*
G36*
G01Y240406D02*
X452805Y240056D01*
Y239186D01*
X452135Y238836D01*
X451960D01*
Y240406D01*
X452135D01*
G37*
G36*
G01Y244306D02*
X452805Y243956D01*
Y243086D01*
X452135Y242736D01*
X451960D01*
Y244306D01*
X452135D01*
G37*
G36*
G01X454298Y248084D02*
X454412Y247337D01*
X453710Y246823D01*
X453032Y247157D01*
X452928Y247298D01*
X454195Y248225D01*
X454298Y248084D01*
G37*
G36*
G01X464031Y225162D02*
X463361Y225512D01*
Y226382D01*
X464031Y226732D01*
X464206D01*
Y225162D01*
X464031D01*
G37*
G36*
G01Y221260D02*
X463361Y221610D01*
Y222480D01*
X464031Y222830D01*
X464206D01*
Y221260D01*
X464031D01*
G37*
G36*
G01Y229087D02*
X463361Y229437D01*
Y230307D01*
X464031Y230657D01*
X464206D01*
Y229087D01*
X464031D01*
G37*
G36*
G01Y232987D02*
X463361Y233337D01*
Y234207D01*
X464031Y234557D01*
X464206D01*
Y232987D01*
X464031D01*
G37*
G36*
G01Y236887D02*
X463361Y237237D01*
Y238107D01*
X464031Y238457D01*
X464206D01*
Y236887D01*
X464031D01*
G37*
G36*
G01X464032Y240787D02*
X463362Y241137D01*
Y242007D01*
X464032Y242357D01*
X464207D01*
Y240787D01*
X464032D01*
G37*
G36*
G01Y244687D02*
X463362Y245037D01*
Y245907D01*
X464032Y246257D01*
X464207D01*
Y244687D01*
X464032D01*
G37*
G36*
G01X465655Y228658D02*
X466325Y228308D01*
Y227438D01*
X465655Y227088D01*
X465480D01*
Y228658D01*
X465655D01*
G37*
G36*
G01Y224781D02*
X466325Y224431D01*
Y223561D01*
X465655Y223211D01*
X465480D01*
Y224781D01*
X465655D01*
G37*
G36*
G01Y220879D02*
X466325Y220529D01*
Y219659D01*
X465655Y219309D01*
X465480D01*
Y220879D01*
X465655D01*
G37*
G36*
G01Y232558D02*
X466325Y232208D01*
Y231338D01*
X465655Y230988D01*
X465480D01*
Y232558D01*
X465655D01*
G37*
G36*
G01Y240358D02*
X466325Y240008D01*
Y239138D01*
X465655Y238788D01*
X465480D01*
Y240358D01*
X465655D01*
G37*
G36*
G01Y236458D02*
X466325Y236108D01*
Y235238D01*
X465655Y234888D01*
X465480D01*
Y236458D01*
X465655D01*
G37*
G36*
G01Y248182D02*
X466325Y247832D01*
Y246962D01*
X465655Y246612D01*
X465480D01*
Y248182D01*
X465655D01*
G37*
G36*
G01Y244282D02*
X466325Y243932D01*
Y243062D01*
X465655Y242712D01*
X465480D01*
Y244282D01*
X465655D01*
G37*
G36*
G01X464824Y252077D02*
X465508Y251756D01*
X465545Y250887D01*
X464890Y250509D01*
X464715Y250501D01*
X464649Y252070D01*
X464824Y252077D01*
G37*
G36*
G01X474170Y227136D02*
X473500Y227486D01*
Y228356D01*
X474170Y228706D01*
X474345D01*
Y227136D01*
X474170D01*
G37*
G36*
G01Y223236D02*
X473500Y223586D01*
Y224456D01*
X474170Y224806D01*
X474345D01*
Y223236D01*
X474170D01*
G37*
G36*
G01Y219336D02*
X473500Y219686D01*
Y220556D01*
X474170Y220906D01*
X474345D01*
Y219336D01*
X474170D01*
G37*
G36*
G01Y230987D02*
X473500Y231337D01*
Y232207D01*
X474170Y232557D01*
X474345D01*
Y230987D01*
X474170D01*
G37*
G36*
G01Y238836D02*
X473500Y239186D01*
Y240056D01*
X474170Y240406D01*
X474345D01*
Y238836D01*
X474170D01*
G37*
G36*
G01Y234911D02*
X473500Y235261D01*
Y236131D01*
X474170Y236481D01*
X474345D01*
Y234911D01*
X474170D01*
G37*
G36*
G01X474868Y245440D02*
X474525Y246114D01*
X475029Y246823D01*
X475778Y246720D01*
X475920Y246619D01*
X475011Y245339D01*
X474868Y245440D01*
G37*
G36*
G01X474170Y242712D02*
X473500Y243062D01*
Y243932D01*
X474170Y244282D01*
X474345D01*
Y242712D01*
X474170D01*
G37*
G36*
G01X475794Y230632D02*
X476464Y230282D01*
Y229412D01*
X475794Y229062D01*
X475619D01*
Y230632D01*
X475794D01*
G37*
G36*
G01Y234556D02*
X476464Y234206D01*
Y233336D01*
X475794Y232986D01*
X475619D01*
Y234556D01*
X475794D01*
G37*
G36*
G01Y226707D02*
X476464Y226357D01*
Y225487D01*
X475794Y225137D01*
X475619D01*
Y226707D01*
X475794D01*
G37*
G36*
G01Y222807D02*
X476464Y222457D01*
Y221587D01*
X475794Y221237D01*
X475619D01*
Y222807D01*
X475794D01*
G37*
G36*
G01X475316Y252552D02*
X474847Y253144D01*
X475201Y253939D01*
X475955Y253986D01*
X476115Y253915D01*
X475476Y252481D01*
X475316Y252552D01*
G37*
G36*
G01X475793Y242332D02*
X476463Y241982D01*
Y241112D01*
X475793Y240762D01*
X475618D01*
Y242332D01*
X475793D01*
G37*
G36*
G01X475794Y238407D02*
X476464Y238057D01*
Y237187D01*
X475794Y236837D01*
X475619D01*
Y238407D01*
X475794D01*
G37*
G36*
G01X476768Y249755D02*
X477467Y250043D01*
X478133Y249484D01*
X477971Y248745D01*
X477858Y248611D01*
X476656Y249621D01*
X476768Y249755D01*
G37*
G36*
G01X470790Y225126D02*
X470120Y225476D01*
Y226346D01*
X470790Y226696D01*
X470965D01*
Y225126D01*
X470790D01*
G37*
G36*
G01Y221226D02*
X470120Y221576D01*
Y222446D01*
X470790Y222796D01*
X470965D01*
Y221226D01*
X470790D01*
G37*
G36*
G01Y229037D02*
X470120Y229387D01*
Y230257D01*
X470790Y230607D01*
X470965D01*
Y229037D01*
X470790D01*
G37*
G36*
G01Y232986D02*
X470120Y233336D01*
Y234206D01*
X470790Y234556D01*
X470965D01*
Y232986D01*
X470790D01*
G37*
G36*
G01Y240762D02*
X470120Y241112D01*
Y241982D01*
X470790Y242332D01*
X470965D01*
Y240762D01*
X470790D01*
G37*
G36*
G01Y236826D02*
X470120Y237176D01*
Y238046D01*
X470790Y238396D01*
X470965D01*
Y236826D01*
X470790D01*
G37*
G36*
G01Y244662D02*
X470120Y245012D01*
Y245882D01*
X470790Y246232D01*
X470965D01*
Y244662D01*
X470790D01*
G37*
G36*
G01X472415Y220917D02*
X473085Y220567D01*
Y219697D01*
X472415Y219347D01*
X472240D01*
Y220917D01*
X472415D01*
G37*
G36*
G01Y224817D02*
X473085Y224467D01*
Y223597D01*
X472415Y223247D01*
X472240D01*
Y224817D01*
X472415D01*
G37*
G36*
G01Y228717D02*
X473085Y228367D01*
Y227497D01*
X472415Y227147D01*
X472240D01*
Y228717D01*
X472415D01*
G37*
G36*
G01Y232557D02*
X473085Y232207D01*
Y231337D01*
X472415Y230987D01*
X472240D01*
Y232557D01*
X472415D01*
G37*
G36*
G01Y236506D02*
X473085Y236156D01*
Y235286D01*
X472415Y234936D01*
X472240D01*
Y236506D01*
X472415D01*
G37*
G36*
G01Y240417D02*
X473085Y240067D01*
Y239197D01*
X472415Y238847D01*
X472240D01*
Y240417D01*
X472415D01*
G37*
G36*
G01X474649Y248093D02*
X474734Y247342D01*
X474013Y246855D01*
X473348Y247214D01*
X473250Y247359D01*
X474551Y248238D01*
X474649Y248093D01*
G37*
G36*
G01X472415Y244282D02*
X473085Y243932D01*
Y243062D01*
X472415Y242712D01*
X472240D01*
Y244282D01*
X472415D01*
G37*
G36*
G01X428476Y222831D02*
X429146Y222481D01*
Y221611D01*
X428476Y221261D01*
X428301D01*
Y222831D01*
X428476D01*
G37*
G36*
G01Y226756D02*
X429146Y226406D01*
Y225536D01*
X428476Y225186D01*
X428301D01*
Y226756D01*
X428476D01*
G37*
G36*
G01X458895Y220906D02*
X459565Y220556D01*
Y219686D01*
X458895Y219336D01*
X458720D01*
Y220906D01*
X458895D01*
G37*
G36*
G01Y224806D02*
X459565Y224456D01*
Y223586D01*
X458895Y223236D01*
X458720D01*
Y224806D01*
X458895D01*
G37*
G36*
G01Y228706D02*
X459565Y228356D01*
Y227486D01*
X458895Y227136D01*
X458720D01*
Y228706D01*
X458895D01*
G37*
G36*
G01Y232557D02*
X459565Y232207D01*
Y231337D01*
X458895Y230987D01*
X458720D01*
Y232557D01*
X458895D01*
G37*
G36*
G01Y236481D02*
X459565Y236131D01*
Y235261D01*
X458895Y234911D01*
X458720D01*
Y236481D01*
X458895D01*
G37*
G36*
G01Y240406D02*
X459565Y240056D01*
Y239186D01*
X458895Y238836D01*
X458720D01*
Y240406D01*
X458895D01*
G37*
G36*
G01X431856Y228717D02*
X432526Y228367D01*
Y227497D01*
X431856Y227147D01*
X431681D01*
Y228717D01*
X431856D01*
G37*
G36*
G01Y224817D02*
X432526Y224467D01*
Y223597D01*
X431856Y223247D01*
X431681D01*
Y224817D01*
X431856D01*
G37*
G36*
G01Y220917D02*
X432526Y220567D01*
Y219697D01*
X431856Y219347D01*
X431681D01*
Y220917D01*
X431856D01*
G37*
G36*
G01Y232557D02*
X432526Y232207D01*
Y231337D01*
X431856Y230987D01*
X431681D01*
Y232557D01*
X431856D01*
G37*
G36*
G01Y236506D02*
X432526Y236156D01*
Y235286D01*
X431856Y234936D01*
X431681D01*
Y236506D01*
X431856D01*
G37*
G36*
G01X431854Y240338D02*
X432524Y239988D01*
Y239118D01*
X431854Y238768D01*
X431678D01*
X431680Y240338D01*
X431854D01*
G37*
G36*
G01X462275Y226707D02*
X462945Y226357D01*
Y225487D01*
X462275Y225137D01*
X462100D01*
Y226707D01*
X462275D01*
G37*
G36*
G01Y222807D02*
X462945Y222457D01*
Y221587D01*
X462275Y221237D01*
X462100D01*
Y222807D01*
X462275D01*
G37*
G36*
G01Y230632D02*
X462945Y230282D01*
Y229412D01*
X462275Y229062D01*
X462100D01*
Y230632D01*
X462275D01*
G37*
G36*
G01Y234556D02*
X462945Y234206D01*
Y233336D01*
X462275Y232986D01*
X462100D01*
Y234556D01*
X462275D01*
G37*
G36*
G01Y250107D02*
X462945Y249757D01*
Y248887D01*
X462275Y248537D01*
X462100D01*
Y250107D01*
X462275D01*
G37*
G36*
G01Y246207D02*
X462945Y245857D01*
Y244987D01*
X462275Y244637D01*
X462100D01*
Y246207D01*
X462275D01*
G37*
G36*
G01Y242307D02*
X462945Y241957D01*
Y241087D01*
X462275Y240737D01*
X462100D01*
Y242307D01*
X462275D01*
G37*
G36*
G01Y238407D02*
X462945Y238057D01*
Y237187D01*
X462275Y236837D01*
X462100D01*
Y238407D01*
X462275D01*
G37*
G36*
G01X462273Y254076D02*
X462943Y253726D01*
X462944Y252856D01*
X462273Y252507D01*
X462099D01*
X462098Y254076D01*
X462273D01*
G37*
G36*
G01X426852Y227087D02*
X426182Y227437D01*
Y228307D01*
X426852Y228657D01*
X427027D01*
Y227087D01*
X426852D01*
G37*
G36*
G01Y223187D02*
X426182Y223537D01*
Y224407D01*
X426852Y224757D01*
X427027D01*
Y223187D01*
X426852D01*
G37*
G36*
G01Y219287D02*
X426182Y219637D01*
Y220507D01*
X426852Y220857D01*
X427027D01*
Y219287D01*
X426852D01*
G37*
G36*
G01X457271Y225137D02*
X456601Y225487D01*
Y226357D01*
X457271Y226707D01*
X457446D01*
Y225137D01*
X457271D01*
G37*
G36*
G01Y221237D02*
X456601Y221587D01*
Y222457D01*
X457271Y222807D01*
X457446D01*
Y221237D01*
X457271D01*
G37*
G36*
G01Y229062D02*
X456601Y229412D01*
Y230282D01*
X457271Y230632D01*
X457446D01*
Y229062D01*
X457271D01*
G37*
G36*
G01Y232937D02*
X456601Y233287D01*
Y234157D01*
X457271Y234507D01*
X457446D01*
Y232937D01*
X457271D01*
G37*
G36*
G01Y240762D02*
X456601Y241112D01*
Y241982D01*
X457271Y242332D01*
X457446D01*
Y240762D01*
X457271D01*
G37*
G36*
G01Y236837D02*
X456601Y237187D01*
Y238057D01*
X457271Y238407D01*
X457446D01*
Y236837D01*
X457271D01*
G37*
G36*
G01X477550Y229062D02*
X476880Y229412D01*
Y230282D01*
X477550Y230632D01*
X477725D01*
Y229062D01*
X477550D01*
G37*
G36*
G01Y232986D02*
X476880Y233336D01*
Y234206D01*
X477550Y234556D01*
X477725D01*
Y232986D01*
X477550D01*
G37*
G36*
G01Y221237D02*
X476880Y221587D01*
Y222457D01*
X477550Y222807D01*
X477725D01*
Y221237D01*
X477550D01*
G37*
G36*
G01Y225137D02*
X476880Y225487D01*
Y226357D01*
X477550Y226707D01*
X477725D01*
Y225137D01*
X477550D01*
G37*
G36*
G01Y236837D02*
X476880Y237187D01*
Y238057D01*
X477550Y238407D01*
X477725D01*
Y236837D01*
X477550D01*
G37*
G36*
G01Y240762D02*
X476880Y241112D01*
Y241982D01*
X477550Y242332D01*
X477725D01*
Y240762D01*
X477550D01*
G37*
G36*
G01X430231Y225126D02*
X429561Y225476D01*
Y226346D01*
X430231Y226696D01*
X430406D01*
Y225126D01*
X430231D01*
G37*
G36*
G01Y221226D02*
X429561Y221576D01*
Y222446D01*
X430231Y222796D01*
X430406D01*
Y221226D01*
X430231D01*
G37*
G36*
G01Y229037D02*
X429561Y229387D01*
Y230257D01*
X430231Y230607D01*
X430406D01*
Y229037D01*
X430231D01*
G37*
G36*
G01Y232986D02*
X429561Y233336D01*
Y234206D01*
X430231Y234556D01*
X430406D01*
Y232986D01*
X430231D01*
G37*
G36*
G01Y236826D02*
X429561Y237176D01*
Y238046D01*
X430231Y238396D01*
X430406D01*
Y236826D01*
X430231D01*
G37*
G36*
G01X460651Y227136D02*
X459981Y227486D01*
Y228356D01*
X460651Y228706D01*
X460826D01*
Y227136D01*
X460651D01*
G37*
G36*
G01Y223236D02*
X459981Y223586D01*
Y224456D01*
X460651Y224806D01*
X460826D01*
Y223236D01*
X460651D01*
G37*
G36*
G01Y219336D02*
X459981Y219686D01*
Y220556D01*
X460651Y220906D01*
X460826D01*
Y219336D01*
X460651D01*
G37*
G36*
G01Y230987D02*
X459981Y231337D01*
Y232207D01*
X460651Y232557D01*
X460826D01*
Y230987D01*
X460651D01*
G37*
G36*
G01Y250536D02*
X459981Y250886D01*
Y251756D01*
X460651Y252106D01*
X460826D01*
Y250536D01*
X460651D01*
G37*
G36*
G01Y246636D02*
X459981Y246986D01*
Y247856D01*
X460651Y248206D01*
X460826D01*
Y246636D01*
X460651D01*
G37*
G36*
G01Y242736D02*
X459981Y243086D01*
Y243956D01*
X460651Y244306D01*
X460826D01*
Y242736D01*
X460651D01*
G37*
G36*
G01Y238836D02*
X459981Y239186D01*
Y240056D01*
X460651Y240406D01*
X460826D01*
Y238836D01*
X460651D01*
G37*
G36*
G01Y234911D02*
X459981Y235261D01*
Y236131D01*
X460651Y236481D01*
X460826D01*
Y234911D01*
X460651D01*
G37*
G36*
G01X474200Y273000D02*
X468200Y279000D01*
Y282700D01*
X468500Y283000D01*
Y283964D01*
X472028D01*
X472064Y284000D01*
X475000D01*
X476346Y285346D01*
X477825D01*
G02X478571Y284896I-33J-899D01*
G03X479785Y283733I2601J1500D01*
G02X479949Y283182I-184J-355D01*
G03X482474Y283017I1223J-686D01*
G02X482799Y283562I371J148D01*
G01X483406Y283633D01*
X483475Y283550D01*
G03X485668Y285295I1077J897D01*
G02X486033Y285934I319J242D01*
G01X486630Y285865D01*
X486678Y285768D01*
G03X486855Y287294I1254J628D01*
G01X486786Y287211D01*
X484733Y287450D01*
X484507D01*
G02X483774Y287898I45J897D01*
G03X482559Y289061I-2602J-1502D01*
G02X482395Y289611I185J355D01*
G03X479967Y291012I-1223J685D01*
G02X479408Y290879I-344J204D01*
G03X477882Y291349I-1615J-2532D01*
G03X477862Y291350I-44J-676D01*
G01X474591D01*
X473742Y290500D01*
X473000D01*
X471178Y288678D01*
X467379D01*
X467126Y288424D01*
X467020Y288446D01*
G03X465947Y288234I-286J-1372D01*
G01X465896Y288200D01*
X465361D01*
G02X465015Y288800I0J400D01*
G03X463178Y290756I-1215J700D01*
G02X462600Y291115I-178J358D01*
G01Y293001D01*
G02X463222Y293334I400J0D01*
G03X464221Y293116I778J1166D01*
G02X464680Y292661I63J-395D01*
G03X465845Y293836I1386J-209D01*
G02X465386Y294291I-63J395D01*
G03X463222Y295666I-1386J209D01*
G02X462600Y295999I-222J333D01*
G01Y310945D01*
G02X462966Y311344I400J0D01*
G03X463891Y313677I-118J1397D01*
G02X463914Y314235I298J267D01*
G03X463508Y316536I-966J1016D01*
G02X463386Y317186I160J367D01*
G01X464372Y318172D01*
G03X464885Y318685I-701J1214D01*
G01X467050Y320850D01*
Y331550D01*
X469300Y333800D01*
X476400D01*
X477134Y333066D01*
G02X477060Y332443I-283J-282D01*
G03X478746Y330219I733J-1195D01*
G02X479301Y330209I272J-293D01*
G01X479822Y329688D01*
X479800Y329582D01*
G03X480584Y328023I1372J-287D01*
G01X480700Y327970D01*
Y326722D01*
X480584Y326669D01*
G03X482048Y324301I589J-1273D01*
G01X482187Y324413D01*
X483148Y323452D01*
X483152Y323375D01*
G03X485544Y322456I1400J71D01*
G01X486528Y321472D01*
X486533Y321397D01*
G03X489094Y320712I1399J99D01*
G01X489154Y320800D01*
X489400D01*
X490043Y320157D01*
X489998Y320037D01*
G03X491802Y318233I1314J-490D01*
G01X491922Y318278D01*
X494487Y315713D01*
G02X494312Y315046I-283J-282D01*
G03X496042Y313316I380J-1350D01*
G02X496709Y313491I385J-108D01*
G01X496992Y313208D01*
G02X497011Y312664I-283J-282D01*
G03X498989Y310686I1061J-917D01*
G02X499533Y310667I262J-302D01*
G01X500083Y310117D01*
X500067Y310016D01*
G03X501373Y308397I1385J-219D01*
G02X501750Y307998I-23J-399D01*
G01Y307695D01*
G02X501373Y307296I-400J0D01*
G03Y304496I79J-1400D01*
G02X501750Y304097I-23J-399D01*
G01Y303795D01*
G02X501373Y303396I-400J0D01*
G03Y300596I79J-1400D01*
G02X501750Y300197I-23J-399D01*
G01Y299895D01*
G02X501373Y299496I-400J0D01*
G03Y296696I79J-1400D01*
G02X501750Y296297I-23J-399D01*
G01Y295995D01*
G02X501373Y295596I-400J0D01*
G03Y292796I79J-1400D01*
G02X501750Y292397I-23J-399D01*
G01Y292095D01*
G02X501373Y291696I-400J0D01*
G03X500811Y289049I79J-1400D01*
G02X500911Y288411I-183J-356D01*
G01X498329Y285829D01*
X498233Y285840D01*
G03X496679Y284286I-161J-1393D01*
G01X496690Y284190D01*
X495977Y283477D01*
G02X495693Y283478I-142J141D01*
G03X493710Y281495I-1001J-982D01*
G01X493711D01*
X493853Y281353D01*
X493312Y280812D01*
G02X492648Y280973I-283J282D01*
G03X490886Y279211I-1336J-426D01*
G02X491047Y278547I-121J-381D01*
G01X488489Y275989D01*
X488372Y276027D01*
G03X486601Y274256I-440J-1331D01*
G01X486639Y274139D01*
X486172Y273672D01*
G02X485592Y273687I-283J283D01*
G03X483207Y273143I-1040J-940D01*
G01X483165Y273000D01*
X482424D01*
G02X482146Y273688I0J400D01*
G03X480198I-974J1008D01*
G02X479920Y273000I-278J-288D01*
G01X479179D01*
X479137Y273143D01*
G03X476447I-1345J-396D01*
G01X476405Y273000D01*
X474200D01*
G37*
G36*
G01X421212Y385037D02*
X420542Y385387D01*
Y386257D01*
X421212Y386607D01*
X421387D01*
Y385037D01*
X421212D01*
G37*
G36*
G01Y373386D02*
X420542Y373736D01*
Y374606D01*
X421212Y374956D01*
X421387D01*
Y373386D01*
X421212D01*
G37*
G36*
G01Y377237D02*
X420542Y377587D01*
Y378457D01*
X421212Y378807D01*
X421387D01*
Y377237D01*
X421212D01*
G37*
G36*
G01Y381137D02*
X420542Y381487D01*
Y382357D01*
X421212Y382707D01*
X421387D01*
Y381137D01*
X421212D01*
G37*
G36*
G01X423929Y368244D02*
X424567Y368649D01*
X425320Y368214D01*
X425288Y367459D01*
X425201Y367307D01*
X423841Y368093D01*
X423929Y368244D01*
G37*
G36*
G01X421212Y369486D02*
X420542Y369836D01*
Y370706D01*
X421212Y371056D01*
X421387D01*
Y369486D01*
X421212D01*
G37*
G36*
G01Y388937D02*
X420542Y389287D01*
Y390157D01*
X421212Y390507D01*
X421387D01*
Y388937D01*
X421212D01*
G37*
G36*
G01X425115Y402511D02*
X424355Y402861D01*
Y403761D01*
X425115Y404111D01*
X425290D01*
Y402511D01*
X425115D01*
G37*
G36*
G01Y398611D02*
X424355Y398961D01*
Y399861D01*
X425115Y400211D01*
X425290D01*
Y398611D01*
X425115D01*
G37*
G36*
G01X421778Y395418D02*
X421747Y396173D01*
X422500Y396608D01*
X423138Y396203D01*
X423225Y396052D01*
X421866Y395266D01*
X421778Y395418D01*
G37*
G36*
G01X421212Y392837D02*
X420542Y393187D01*
Y394057D01*
X421212Y394407D01*
X421387D01*
Y392837D01*
X421212D01*
G37*
G36*
G01X422836Y384706D02*
X423506Y384356D01*
Y383486D01*
X422836Y383136D01*
X422661D01*
Y384706D01*
X422836D01*
G37*
G36*
G01Y388606D02*
X423506Y388256D01*
Y387386D01*
X422836Y387036D01*
X422661D01*
Y388606D01*
X422836D01*
G37*
G36*
G01Y372957D02*
X423506Y372607D01*
Y371737D01*
X422836Y371387D01*
X422661D01*
Y372957D01*
X422836D01*
G37*
G36*
G01Y376881D02*
X423506Y376531D01*
Y375661D01*
X422836Y375311D01*
X422661D01*
Y376881D01*
X422836D01*
G37*
G36*
G01Y380806D02*
X423506Y380456D01*
Y379586D01*
X422836Y379236D01*
X422661D01*
Y380806D01*
X422836D01*
G37*
G36*
G01X426217Y403611D02*
X426977Y403261D01*
Y402361D01*
X426217Y402011D01*
X426042D01*
Y403611D01*
X426217D01*
G37*
G36*
G01Y399711D02*
X426977Y399361D01*
Y398461D01*
X426217Y398111D01*
X426042D01*
Y399711D01*
X426217D01*
G37*
G36*
G01X425645Y395772D02*
X425676Y395017D01*
X424923Y394583D01*
X424285Y394988D01*
X424198Y395139D01*
X425558Y395924D01*
X425645Y395772D01*
G37*
G36*
G01X422836Y392506D02*
X423506Y392156D01*
Y391286D01*
X422836Y390936D01*
X422661D01*
Y392506D01*
X422836D01*
G37*
G36*
G01X434731Y385026D02*
X434061Y385376D01*
Y386246D01*
X434731Y386596D01*
X434906D01*
Y385026D01*
X434731D01*
G37*
G36*
G01Y377226D02*
X434061Y377576D01*
Y378446D01*
X434731Y378796D01*
X434906D01*
Y377226D01*
X434731D01*
G37*
G36*
G01Y373386D02*
X434061Y373736D01*
Y374606D01*
X434731Y374956D01*
X434906D01*
Y373386D01*
X434731D01*
G37*
G36*
G01Y381126D02*
X434061Y381476D01*
Y382346D01*
X434731Y382696D01*
X434906D01*
Y381126D01*
X434731D01*
G37*
G36*
G01X436624Y367685D02*
X435953Y367337D01*
X435240Y367836D01*
X435338Y368585D01*
X435438Y368728D01*
X436724Y367829D01*
X436624Y367685D01*
G37*
G36*
G01X434731Y369486D02*
X434061Y369836D01*
Y370706D01*
X434731Y371056D01*
X434906D01*
Y369486D01*
X434731D01*
G37*
G36*
G01X435272Y387603D02*
X435240Y388358D01*
X435994Y388792D01*
X436631Y388387D01*
X436720Y388236D01*
X435359Y387451D01*
X435272Y387603D01*
G37*
G36*
G01X438646Y389548D02*
X438614Y390303D01*
X439367Y390738D01*
X440005Y390333D01*
X440093Y390181D01*
X438733Y389397D01*
X438646Y389548D01*
G37*
G36*
G01X444871Y402651D02*
X444201Y403001D01*
Y403871D01*
X444871Y404221D01*
X445046D01*
Y402651D01*
X444871D01*
G37*
G36*
G01Y398709D02*
X444201Y399059D01*
Y399929D01*
X444871Y400279D01*
X445046D01*
Y398709D01*
X444871D01*
G37*
G36*
G01Y394785D02*
X444201Y395135D01*
Y396005D01*
X444871Y396355D01*
X445046D01*
Y394785D01*
X444871D01*
G37*
G36*
G01X442060Y391495D02*
X442028Y392250D01*
X442781Y392685D01*
X443419Y392280D01*
X443507Y392129D01*
X442147Y391343D01*
X442060Y391495D01*
G37*
G36*
G01X436356Y384717D02*
X437026Y384367D01*
Y383497D01*
X436356Y383147D01*
X436181D01*
Y384717D01*
X436356D01*
G37*
G36*
G01X439200Y387995D02*
X439232Y387240D01*
X438479Y386805D01*
X437841Y387210D01*
X437753Y387361D01*
X439113Y388147D01*
X439200Y387995D01*
G37*
G36*
G01X436356Y372957D02*
X437026Y372607D01*
Y371737D01*
X436356Y371387D01*
X436181D01*
Y372957D01*
X436356D01*
G37*
G36*
G01Y376906D02*
X437026Y376556D01*
Y375686D01*
X436356Y375336D01*
X436181D01*
Y376906D01*
X436356D01*
G37*
G36*
G01Y380817D02*
X437026Y380467D01*
Y379597D01*
X436356Y379247D01*
X436181D01*
Y380817D01*
X436356D01*
G37*
G36*
G01X442574Y389941D02*
X442606Y389186D01*
X441853Y388751D01*
X441215Y389156D01*
X441127Y389307D01*
X442487Y390093D01*
X442574Y389941D01*
G37*
G36*
G01X445954Y391891D02*
X445986Y391136D01*
X445233Y390701D01*
X444595Y391106D01*
X444507Y391257D01*
X445867Y392043D01*
X445954Y391891D01*
G37*
G36*
G01X446495Y402205D02*
X447165Y401855D01*
Y400985D01*
X446495Y400635D01*
X446320D01*
Y402205D01*
X446495D01*
G37*
G36*
G01Y398354D02*
X447165Y398004D01*
Y397134D01*
X446495Y396784D01*
X446320D01*
Y398354D01*
X446495D01*
G37*
G36*
G01Y394454D02*
X447165Y394104D01*
Y393234D01*
X446495Y392884D01*
X446320D01*
Y394454D01*
X446495D01*
G37*
G36*
G01X417832Y383136D02*
X417162Y383486D01*
Y384356D01*
X417832Y384706D01*
X418007D01*
Y383136D01*
X417832D01*
G37*
G36*
G01Y387036D02*
X417162Y387386D01*
Y388256D01*
X417832Y388606D01*
X418007D01*
Y387036D01*
X417832D01*
G37*
G36*
G01Y371387D02*
X417162Y371737D01*
Y372607D01*
X417832Y372957D01*
X418007D01*
Y371387D01*
X417832D01*
G37*
G36*
G01Y375311D02*
X417162Y375661D01*
Y376531D01*
X417832Y376881D01*
X418007D01*
Y375311D01*
X417832D01*
G37*
G36*
G01Y379236D02*
X417162Y379586D01*
Y380456D01*
X417832Y380806D01*
X418007D01*
Y379236D01*
X417832D01*
G37*
G36*
G01X418539Y366404D02*
X417784Y366372D01*
X417349Y367125D01*
X417754Y367763D01*
X417906Y367851D01*
X418690Y366491D01*
X418539Y366404D01*
G37*
G36*
G01X421811Y360611D02*
X421056Y360645D01*
X420688Y361433D01*
X421148Y362033D01*
X421306Y362107D01*
X421970Y360685D01*
X421811Y360611D01*
G37*
G36*
G01X421197Y402759D02*
X420437Y403109D01*
Y404009D01*
X421197Y404359D01*
X421372D01*
Y402759D01*
X421197D01*
G37*
G36*
G01Y398859D02*
X420437Y399209D01*
Y400109D01*
X421197Y400459D01*
X421372D01*
Y398859D01*
X421197D01*
G37*
G36*
G01X419090Y396465D02*
X418800Y397249D01*
X419437Y397886D01*
X420221Y397596D01*
X420345Y397472D01*
X419214Y396341D01*
X419090Y396465D01*
G37*
G36*
G01X417832Y390936D02*
X417162Y391286D01*
Y392156D01*
X417832Y392506D01*
X418007D01*
Y390936D01*
X417832D01*
G37*
G36*
G01X419456Y386607D02*
X420126Y386257D01*
Y385387D01*
X419456Y385037D01*
X419281D01*
Y386607D01*
X419456D01*
G37*
G36*
G01Y378807D02*
X420126Y378457D01*
Y377587D01*
X419456Y377237D01*
X419281D01*
Y378807D01*
X419456D01*
G37*
G36*
G01Y374956D02*
X420126Y374606D01*
Y373736D01*
X419456Y373386D01*
X419281D01*
Y374956D01*
X419456D01*
G37*
G36*
G01Y382707D02*
X420126Y382357D01*
Y381487D01*
X419456Y381137D01*
X419281D01*
Y382707D01*
X419456D01*
G37*
G36*
G01X420245Y366941D02*
X420652Y367578D01*
X421519Y367502D01*
X421809Y366804D01*
X421794Y366630D01*
X420230Y366766D01*
X420245Y366941D01*
G37*
G36*
G01X419456Y371032D02*
X420126Y370682D01*
Y369812D01*
X419456Y369462D01*
X419281D01*
Y371032D01*
X419456D01*
G37*
G36*
G01Y390507D02*
X420126Y390157D01*
Y389287D01*
X419456Y388937D01*
X419281D01*
Y390507D01*
X419456D01*
G37*
G36*
G01X422314Y404359D02*
X423074Y404009D01*
Y403109D01*
X422314Y402759D01*
X422139D01*
Y404359D01*
X422314D01*
G37*
G36*
G01Y400459D02*
X423074Y400109D01*
Y399209D01*
X422314Y398859D01*
X422139D01*
Y400459D01*
X422314D01*
G37*
G36*
G01X420999Y396818D02*
X421289Y396033D01*
X420653Y395397D01*
X419868Y395687D01*
X419744Y395810D01*
X420876Y396942D01*
X420999Y396818D01*
G37*
G36*
G01X431352Y383136D02*
X430682Y383486D01*
Y384356D01*
X431352Y384706D01*
X431527D01*
Y383136D01*
X431352D01*
G37*
G36*
G01Y387036D02*
X430682Y387386D01*
Y388256D01*
X431352Y388606D01*
X431527D01*
Y387036D01*
X431352D01*
G37*
G36*
G01Y375311D02*
X430682Y375661D01*
Y376531D01*
X431352Y376881D01*
X431527D01*
Y375311D01*
X431352D01*
G37*
G36*
G01Y379236D02*
X430682Y379586D01*
Y380456D01*
X431352Y380806D01*
X431527D01*
Y379236D01*
X431352D01*
G37*
G36*
G01Y367536D02*
X430682Y367886D01*
Y368756D01*
X431352Y369106D01*
X431527D01*
Y367536D01*
X431352D01*
G37*
G36*
G01X432225Y371012D02*
X432895Y370662D01*
Y369792D01*
X432225Y369442D01*
X432050D01*
Y371012D01*
X432225D01*
G37*
G36*
G01X431908Y389562D02*
X431876Y390317D01*
X432630Y390751D01*
X433267Y390346D01*
X433356Y390195D01*
X431996Y389409D01*
X431908Y389562D01*
G37*
G36*
G01X435272Y391502D02*
X435240Y392257D01*
X435993Y392692D01*
X436631Y392287D01*
X436719Y392135D01*
X435359Y391351D01*
X435272Y391502D01*
G37*
G36*
G01X441491Y400660D02*
X440821Y401010D01*
Y401880D01*
X441491Y402230D01*
X441666D01*
Y400660D01*
X441491D01*
G37*
G36*
G01Y396784D02*
X440821Y397134D01*
Y398004D01*
X441491Y398354D01*
X441666D01*
Y396784D01*
X441491D01*
G37*
G36*
G01X438646Y393448D02*
X438614Y394203D01*
X439367Y394638D01*
X440005Y394233D01*
X440093Y394081D01*
X438733Y393297D01*
X438646Y393448D01*
G37*
G36*
G01X432976Y386607D02*
X433646Y386257D01*
Y385387D01*
X432976Y385037D01*
X432801D01*
Y386607D01*
X432976D01*
G37*
G36*
G01Y374956D02*
X433646Y374606D01*
Y373736D01*
X432976Y373386D01*
X432801D01*
Y374956D01*
X432976D01*
G37*
G36*
G01Y378807D02*
X433646Y378457D01*
Y377587D01*
X432976Y377237D01*
X432801D01*
Y378807D01*
X432976D01*
G37*
G36*
G01Y382707D02*
X433646Y382357D01*
Y381487D01*
X432976Y381137D01*
X432801D01*
Y382707D01*
X432976D01*
G37*
G36*
G01X435815Y389941D02*
X435847Y389186D01*
X435094Y388751D01*
X434456Y389156D01*
X434368Y389307D01*
X435728Y390093D01*
X435815Y389941D01*
G37*
G36*
G01X443115Y404205D02*
X443785Y403855D01*
Y402985D01*
X443115Y402635D01*
X442940D01*
Y404205D01*
X443115D01*
G37*
G36*
G01Y396380D02*
X443785Y396030D01*
Y395160D01*
X443115Y394810D01*
X442940D01*
Y396380D01*
X443115D01*
G37*
G36*
G01Y400280D02*
X443785Y399930D01*
Y399060D01*
X443115Y398710D01*
X442940D01*
Y400280D01*
X443115D01*
G37*
G36*
G01X442580Y393845D02*
X442612Y393090D01*
X441859Y392655D01*
X441221Y393060D01*
X441133Y393211D01*
X442493Y393997D01*
X442580Y393845D01*
G37*
G36*
G01X439200Y391895D02*
X439232Y391140D01*
X438479Y390705D01*
X437841Y391110D01*
X437753Y391261D01*
X439113Y392047D01*
X439200Y391895D01*
G37*
G36*
G01X441491Y357737D02*
X440821Y358087D01*
Y358957D01*
X441491Y359307D01*
X441666D01*
Y357737D01*
X441491D01*
G37*
G36*
G01X442033Y383704D02*
X442001Y384459D01*
X442754Y384893D01*
X443392Y384488D01*
X443480Y384337D01*
X442119Y383552D01*
X442033Y383704D01*
G37*
G36*
G01X441491Y381137D02*
X440821Y381487D01*
Y382357D01*
X441491Y382707D01*
X441666D01*
Y381137D01*
X441491D01*
G37*
G36*
G01Y373386D02*
X440821Y373736D01*
Y374606D01*
X441491Y374956D01*
X441666D01*
Y373386D01*
X441491D01*
G37*
G36*
G01Y377237D02*
X440821Y377587D01*
Y378457D01*
X441491Y378807D01*
X441666D01*
Y377237D01*
X441491D01*
G37*
G36*
G01Y361637D02*
X440821Y361987D01*
Y362857D01*
X441491Y363207D01*
X441666D01*
Y361637D01*
X441491D01*
G37*
G36*
G01Y365537D02*
X440821Y365887D01*
Y366757D01*
X441491Y367107D01*
X441666D01*
Y365537D01*
X441491D01*
G37*
G36*
G01Y369462D02*
X440821Y369812D01*
Y370682D01*
X441491Y371032D01*
X441666D01*
Y369462D01*
X441491D01*
G37*
G36*
G01X445406Y385648D02*
X445374Y386403D01*
X446127Y386838D01*
X446765Y386433D01*
X446853Y386281D01*
X445493Y385497D01*
X445406Y385648D01*
G37*
G36*
G01X448792Y387602D02*
X448760Y388357D01*
X449513Y388792D01*
X450151Y388387D01*
X450239Y388235D01*
X448879Y387451D01*
X448792Y387602D01*
G37*
G36*
G01X452166Y389548D02*
X452134Y390303D01*
X452887Y390738D01*
X453525Y390333D01*
X453613Y390181D01*
X452253Y389397D01*
X452166Y389548D01*
G37*
G36*
G01X458391Y402646D02*
X457721Y402996D01*
Y403866D01*
X458391Y404216D01*
X458566D01*
Y402646D01*
X458391D01*
G37*
G36*
G01Y394846D02*
X457721Y395196D01*
Y396066D01*
X458391Y396416D01*
X458566D01*
Y394846D01*
X458391D01*
G37*
G36*
G01Y398746D02*
X457721Y399096D01*
Y399966D01*
X458391Y400316D01*
X458566D01*
Y398746D01*
X458391D01*
G37*
G36*
G01X455552Y391502D02*
X455520Y392257D01*
X456273Y392692D01*
X456911Y392287D01*
X456999Y392135D01*
X455639Y391351D01*
X455552Y391502D01*
G37*
G36*
G01X445960Y384095D02*
X445992Y383340D01*
X445239Y382905D01*
X444601Y383310D01*
X444513Y383461D01*
X445873Y384247D01*
X445960Y384095D01*
G37*
G36*
G01X443115Y376881D02*
X443785Y376531D01*
Y375661D01*
X443115Y375311D01*
X442940D01*
Y376881D01*
X443115D01*
G37*
G36*
G01Y372957D02*
X443785Y372607D01*
Y371737D01*
X443115Y371387D01*
X442940D01*
Y372957D01*
X443115D01*
G37*
G36*
G01Y380806D02*
X443785Y380456D01*
Y379586D01*
X443115Y379236D01*
X442940D01*
Y380806D01*
X443115D01*
G37*
G36*
G01Y369106D02*
X443785Y368756D01*
Y367886D01*
X443115Y367536D01*
X442940D01*
Y369106D01*
X443115D01*
G37*
G36*
G01X449334Y386041D02*
X449366Y385286D01*
X448613Y384851D01*
X447975Y385256D01*
X447887Y385407D01*
X449247Y386193D01*
X449334Y386041D01*
G37*
G36*
G01X452720Y387995D02*
X452752Y387240D01*
X451999Y386805D01*
X451361Y387210D01*
X451273Y387361D01*
X452633Y388147D01*
X452720Y387995D01*
G37*
G36*
G01X456094Y389941D02*
X456126Y389186D01*
X455373Y388751D01*
X454735Y389156D01*
X454647Y389307D01*
X456007Y390093D01*
X456094Y389941D01*
G37*
G36*
G01X459459Y391881D02*
X459491Y391126D01*
X458737Y390692D01*
X458100Y391097D01*
X458011Y391248D01*
X459372Y392033D01*
X459459Y391881D01*
G37*
G36*
G01X460015Y402196D02*
X460685Y401846D01*
Y400976D01*
X460015Y400626D01*
X459840D01*
Y402196D01*
X460015D01*
G37*
G36*
G01Y398296D02*
X460685Y397946D01*
Y397076D01*
X460015Y396726D01*
X459840D01*
Y398296D01*
X460015D01*
G37*
G36*
G01Y394396D02*
X460685Y394046D01*
Y393176D01*
X460015Y392826D01*
X459840D01*
Y394396D01*
X460015D01*
G37*
G36*
G01X455011Y373362D02*
X454341Y373712D01*
Y374582D01*
X455011Y374932D01*
X455186D01*
Y373362D01*
X455011D01*
G37*
G36*
G01X455581Y375921D02*
X455550Y376676D01*
X456303Y377110D01*
X456941Y376705D01*
X457029Y376554D01*
X455668Y375769D01*
X455581Y375921D01*
G37*
G36*
G01X452220Y359543D02*
X451551Y359894D01*
X451552Y360763D01*
X452223Y361113D01*
X452398Y361112D01*
X452395Y359543D01*
X452220D01*
G37*
G36*
G01X452769Y361788D02*
X452547Y362510D01*
X453166Y363122D01*
X453886Y362891D01*
X454009Y362767D01*
X452892Y361663D01*
X452769Y361788D01*
G37*
G36*
G01X455011Y369462D02*
X454341Y369812D01*
Y370682D01*
X455011Y371032D01*
X455186D01*
Y369462D01*
X455011D01*
G37*
G36*
G01Y365537D02*
X454341Y365887D01*
Y366757D01*
X455011Y367107D01*
X455186D01*
Y365537D01*
X455011D01*
G37*
G36*
G01X458926Y377848D02*
X458894Y378603D01*
X459647Y379038D01*
X460285Y378633D01*
X460373Y378481D01*
X459013Y377697D01*
X458926Y377848D01*
G37*
G36*
G01X465686Y381748D02*
X465654Y382503D01*
X466407Y382938D01*
X467045Y382533D01*
X467133Y382381D01*
X465773Y381597D01*
X465686Y381748D01*
G37*
G36*
G01X462312Y379802D02*
X462280Y380557D01*
X463033Y380992D01*
X463671Y380587D01*
X463759Y380435D01*
X462399Y379651D01*
X462312Y379802D01*
G37*
G36*
G01X469072Y383702D02*
X469040Y384457D01*
X469793Y384892D01*
X470431Y384487D01*
X470519Y384335D01*
X469159Y383551D01*
X469072Y383702D01*
G37*
G36*
G01X471911Y387036D02*
X471241Y387386D01*
Y388256D01*
X471911Y388606D01*
X472086D01*
Y387036D01*
X471911D01*
G37*
G36*
G01Y402636D02*
X471241Y402986D01*
Y403856D01*
X471911Y404206D01*
X472086D01*
Y402636D01*
X471911D01*
G37*
G36*
G01Y398736D02*
X471241Y399086D01*
Y399956D01*
X471911Y400306D01*
X472086D01*
Y398736D01*
X471911D01*
G37*
G36*
G01Y394836D02*
X471241Y395186D01*
Y396056D01*
X471911Y396406D01*
X472086D01*
Y394836D01*
X471911D01*
G37*
G36*
G01Y390936D02*
X471241Y391286D01*
Y392156D01*
X471911Y392506D01*
X472086D01*
Y390936D01*
X471911D01*
G37*
G36*
G01X456635Y372957D02*
X457305Y372607D01*
Y371737D01*
X456635Y371387D01*
X456460D01*
Y372957D01*
X456635D01*
G37*
G36*
G01Y369106D02*
X457305Y368756D01*
Y367886D01*
X456635Y367536D01*
X456460D01*
Y369106D01*
X456635D01*
G37*
G36*
G01Y365206D02*
X457305Y364856D01*
Y363986D01*
X456635Y363636D01*
X456460D01*
Y365206D01*
X456635D01*
G37*
G36*
G01X462854Y378241D02*
X462886Y377486D01*
X462133Y377051D01*
X461495Y377456D01*
X461407Y377607D01*
X462767Y378393D01*
X462854Y378241D01*
G37*
G36*
G01X459465Y376286D02*
X459497Y375531D01*
X458744Y375096D01*
X458106Y375501D01*
X458018Y375653D01*
X459378Y376437D01*
X459465Y376286D01*
G37*
G36*
G01X466240Y380195D02*
X466272Y379440D01*
X465519Y379005D01*
X464881Y379410D01*
X464793Y379561D01*
X466153Y380347D01*
X466240Y380195D01*
G37*
G36*
G01X469614Y382141D02*
X469646Y381386D01*
X468893Y380951D01*
X468255Y381356D01*
X468167Y381507D01*
X469527Y382293D01*
X469614Y382141D01*
G37*
G36*
G01X473535Y386607D02*
X474205Y386257D01*
Y385387D01*
X473535Y385037D01*
X473360D01*
Y386607D01*
X473535D01*
G37*
G36*
G01X472979Y384081D02*
X473011Y383326D01*
X472257Y382892D01*
X471620Y383297D01*
X471531Y383448D01*
X472892Y384233D01*
X472979Y384081D01*
G37*
G36*
G01X473535Y390507D02*
X474205Y390157D01*
Y389287D01*
X473535Y388937D01*
X473360D01*
Y390507D01*
X473535D01*
G37*
G36*
G01Y402207D02*
X474205Y401857D01*
Y400987D01*
X473535Y400637D01*
X473360D01*
Y402207D01*
X473535D01*
G37*
G36*
G01Y398307D02*
X474205Y397957D01*
Y397087D01*
X473535Y396737D01*
X473360D01*
Y398307D01*
X473535D01*
G37*
G36*
G01Y394407D02*
X474205Y394057D01*
Y393187D01*
X473535Y392837D01*
X473360D01*
Y394407D01*
X473535D01*
G37*
G36*
G01X438667Y385662D02*
X438635Y386417D01*
X439389Y386851D01*
X440026Y386446D01*
X440115Y386295D01*
X438754Y385510D01*
X438667Y385662D01*
G37*
G36*
G01X438111Y383136D02*
X437441Y383486D01*
Y384356D01*
X438111Y384706D01*
X438286D01*
Y383136D01*
X438111D01*
G37*
G36*
G01Y375311D02*
X437441Y375661D01*
Y376531D01*
X438111Y376881D01*
X438286D01*
Y375311D01*
X438111D01*
G37*
G36*
G01Y371387D02*
X437441Y371737D01*
Y372607D01*
X438111Y372957D01*
X438286D01*
Y371387D01*
X438111D01*
G37*
G36*
G01Y379236D02*
X437441Y379586D01*
Y380456D01*
X438111Y380806D01*
X438286D01*
Y379236D01*
X438111D01*
G37*
G36*
G01Y359736D02*
X437441Y360086D01*
Y360956D01*
X438111Y361306D01*
X438286D01*
Y359736D01*
X438111D01*
G37*
G36*
G01Y363636D02*
X437441Y363986D01*
Y364856D01*
X438111Y365206D01*
X438286D01*
Y363636D01*
X438111D01*
G37*
G36*
G01X442032Y387602D02*
X442000Y388357D01*
X442753Y388792D01*
X443391Y388387D01*
X443479Y388235D01*
X442119Y387451D01*
X442032Y387602D01*
G37*
G36*
G01X445406Y389548D02*
X445374Y390303D01*
X446127Y390738D01*
X446765Y390333D01*
X446853Y390181D01*
X445493Y389397D01*
X445406Y389548D01*
G37*
G36*
G01X455011Y400637D02*
X454341Y400987D01*
Y401857D01*
X455011Y402207D01*
X455186D01*
Y400637D01*
X455011D01*
G37*
G36*
G01Y396737D02*
X454341Y397087D01*
Y397957D01*
X455011Y398307D01*
X455186D01*
Y396737D01*
X455011D01*
G37*
G36*
G01X452166Y393448D02*
X452134Y394203D01*
X452887Y394638D01*
X453525Y394233D01*
X453613Y394081D01*
X452253Y393297D01*
X452166Y393448D01*
G37*
G36*
G01X448792Y391502D02*
X448760Y392257D01*
X449513Y392692D01*
X450151Y392287D01*
X450239Y392135D01*
X448879Y391351D01*
X448792Y391502D01*
G37*
G36*
G01X442574Y386041D02*
X442606Y385286D01*
X441853Y384851D01*
X441215Y385256D01*
X441127Y385407D01*
X442487Y386193D01*
X442574Y386041D01*
G37*
G36*
G01X445960Y387995D02*
X445992Y387240D01*
X445239Y386805D01*
X444601Y387210D01*
X444513Y387361D01*
X445873Y388147D01*
X445960Y387995D01*
G37*
G36*
G01X439735Y378807D02*
X440405Y378457D01*
Y377587D01*
X439735Y377237D01*
X439560D01*
Y378807D01*
X439735D01*
G37*
G36*
G01Y374956D02*
X440405Y374606D01*
Y373736D01*
X439735Y373386D01*
X439560D01*
Y374956D01*
X439735D01*
G37*
G36*
G01Y382707D02*
X440405Y382357D01*
Y381487D01*
X439735Y381137D01*
X439560D01*
Y382707D01*
X439735D01*
G37*
G36*
G01Y371032D02*
X440405Y370682D01*
Y369812D01*
X439735Y369462D01*
X439560D01*
Y371032D01*
X439735D01*
G37*
G36*
G01Y367107D02*
X440405Y366757D01*
Y365887D01*
X439735Y365537D01*
X439560D01*
Y367107D01*
X439735D01*
G37*
G36*
G01X449334Y389941D02*
X449366Y389186D01*
X448613Y388751D01*
X447975Y389156D01*
X447887Y389307D01*
X449247Y390093D01*
X449334Y389941D01*
G37*
G36*
G01X456635Y404206D02*
X457305Y403856D01*
Y402986D01*
X456635Y402636D01*
X456460D01*
Y404206D01*
X456635D01*
G37*
G36*
G01Y396406D02*
X457305Y396056D01*
Y395186D01*
X456635Y394836D01*
X456460D01*
Y396406D01*
X456635D01*
G37*
G36*
G01Y400306D02*
X457305Y399956D01*
Y399086D01*
X456635Y398736D01*
X456460D01*
Y400306D01*
X456635D01*
G37*
G36*
G01X452720Y391895D02*
X452752Y391140D01*
X451999Y390705D01*
X451361Y391110D01*
X451273Y391261D01*
X452633Y392047D01*
X452720Y391895D01*
G37*
G36*
G01X456093Y393839D02*
X456125Y393084D01*
X455372Y392650D01*
X454734Y393055D01*
X454646Y393206D01*
X456007Y393991D01*
X456093Y393839D01*
G37*
G36*
G01X449002Y357742D02*
X448332Y358092D01*
Y358962D01*
X449002Y359312D01*
X449177D01*
Y357742D01*
X449002D01*
G37*
G36*
G01X451631Y375287D02*
X450961Y375637D01*
Y376507D01*
X451631Y376857D01*
X451806D01*
Y375287D01*
X451631D01*
G37*
G36*
G01Y371387D02*
X450961Y371737D01*
Y372607D01*
X451631Y372957D01*
X451806D01*
Y371387D01*
X451631D01*
G37*
G36*
G01X452166Y377848D02*
X452134Y378603D01*
X452887Y379038D01*
X453525Y378633D01*
X453613Y378482D01*
X452252Y377697D01*
X452166Y377848D01*
G37*
G36*
G01X455552Y379802D02*
X455520Y380557D01*
X456273Y380992D01*
X456911Y380587D01*
X456999Y380435D01*
X455639Y379651D01*
X455552Y379802D01*
G37*
G36*
G01X449875Y361306D02*
X450545Y360956D01*
Y360086D01*
X449875Y359736D01*
X449700D01*
Y361306D01*
X449875D01*
G37*
G36*
G01X451631Y367536D02*
X450961Y367886D01*
Y368756D01*
X451631Y369106D01*
X451806D01*
Y367536D01*
X451631D01*
G37*
G36*
G01X458926Y381748D02*
X458894Y382503D01*
X459647Y382938D01*
X460285Y382533D01*
X460373Y382381D01*
X459013Y381597D01*
X458926Y381748D01*
G37*
G36*
G01X462312Y383702D02*
X462280Y384457D01*
X463033Y384892D01*
X463671Y384487D01*
X463759Y384335D01*
X462399Y383551D01*
X462312Y383702D01*
G37*
G36*
G01X465686Y385648D02*
X465654Y386403D01*
X466407Y386838D01*
X467045Y386433D01*
X467133Y386281D01*
X465773Y385497D01*
X465686Y385648D01*
G37*
G36*
G01X468531Y388937D02*
X467861Y389287D01*
Y390157D01*
X468531Y390507D01*
X468706D01*
Y388937D01*
X468531D01*
G37*
G36*
G01Y396737D02*
X467861Y397087D01*
Y397957D01*
X468531Y398307D01*
X468706D01*
Y396737D01*
X468531D01*
G37*
G36*
G01Y400637D02*
X467861Y400987D01*
Y401857D01*
X468531Y402207D01*
X468706D01*
Y400637D01*
X468531D01*
G37*
G36*
G01Y392837D02*
X467861Y393187D01*
Y394057D01*
X468531Y394407D01*
X468706D01*
Y392837D01*
X468531D01*
G37*
G36*
G01X453255Y374956D02*
X453925Y374606D01*
Y373736D01*
X453255Y373386D01*
X453080D01*
Y374956D01*
X453255D01*
G37*
G36*
G01X456094Y378241D02*
X456126Y377486D01*
X455373Y377051D01*
X454735Y377456D01*
X454647Y377607D01*
X456007Y378393D01*
X456094Y378241D01*
G37*
G36*
G01X453255Y367107D02*
X453925Y366757D01*
Y365887D01*
X453255Y365537D01*
X453080D01*
Y367107D01*
X453255D01*
G37*
G36*
G01Y371032D02*
X453925Y370682D01*
Y369812D01*
X453255Y369462D01*
X453080D01*
Y371032D01*
X453255D01*
G37*
G36*
G01X462854Y382141D02*
X462886Y381386D01*
X462133Y380951D01*
X461495Y381356D01*
X461407Y381507D01*
X462767Y382293D01*
X462854Y382141D01*
G37*
G36*
G01X466240Y384095D02*
X466272Y383340D01*
X465519Y382905D01*
X464881Y383310D01*
X464793Y383461D01*
X466153Y384247D01*
X466240Y384095D01*
G37*
G36*
G01X459480Y380195D02*
X459512Y379440D01*
X458759Y379005D01*
X458121Y379410D01*
X458033Y379561D01*
X459393Y380347D01*
X459480Y380195D01*
G37*
G36*
G01X469613Y386039D02*
X469645Y385284D01*
X468892Y384850D01*
X468254Y385255D01*
X468166Y385406D01*
X469527Y386191D01*
X469613Y386039D01*
G37*
G36*
G01X470155Y388606D02*
X470825Y388256D01*
Y387386D01*
X470155Y387036D01*
X469980D01*
Y388606D01*
X470155D01*
G37*
G36*
G01Y404206D02*
X470825Y403856D01*
Y402986D01*
X470155Y402636D01*
X469980D01*
Y404206D01*
X470155D01*
G37*
G36*
G01Y396406D02*
X470825Y396056D01*
Y395186D01*
X470155Y394836D01*
X469980D01*
Y396406D01*
X470155D01*
G37*
G36*
G01Y400306D02*
X470825Y399956D01*
Y399086D01*
X470155Y398736D01*
X469980D01*
Y400306D01*
X470155D01*
G37*
G36*
G01Y392506D02*
X470825Y392156D01*
Y391286D01*
X470155Y390936D01*
X469980D01*
Y392506D01*
X470155D01*
G37*
G36*
G01X461771Y369437D02*
X461101Y369787D01*
Y370657D01*
X461771Y371007D01*
X461946D01*
Y369437D01*
X461771D01*
G37*
G36*
G01Y361637D02*
X461101Y361987D01*
Y362857D01*
X461771Y363207D01*
X461946D01*
Y361637D01*
X461771D01*
G37*
G36*
G01Y365537D02*
X461101Y365887D01*
Y366757D01*
X461771Y367107D01*
X461946D01*
Y365537D01*
X461771D01*
G37*
G36*
G01X462306Y371999D02*
X462274Y372754D01*
X463027Y373189D01*
X463665Y372784D01*
X463753Y372633D01*
X462392Y371848D01*
X462306Y371999D01*
G37*
G36*
G01X465692Y373952D02*
X465660Y374707D01*
X466413Y375142D01*
X467051Y374737D01*
X467139Y374585D01*
X465779Y373801D01*
X465692Y373952D01*
G37*
G36*
G01X469081Y375907D02*
X469049Y376662D01*
X469802Y377097D01*
X470440Y376692D01*
X470528Y376541D01*
X469168Y375755D01*
X469081Y375907D01*
G37*
G36*
G01X472446Y377848D02*
X472414Y378603D01*
X473167Y379038D01*
X473805Y378633D01*
X473893Y378481D01*
X472533Y377697D01*
X472446Y377848D01*
G37*
G36*
G01X475831Y379802D02*
X475799Y380557D01*
X476552Y380992D01*
X477190Y380587D01*
X477278Y380435D01*
X475918Y379651D01*
X475831Y379802D01*
G37*
G36*
G01X466234Y372391D02*
X466266Y371636D01*
X465513Y371201D01*
X464875Y371606D01*
X464787Y371757D01*
X466147Y372543D01*
X466234Y372391D01*
G37*
G36*
G01X463395Y369106D02*
X464065Y368756D01*
Y367886D01*
X463395Y367536D01*
X463220D01*
Y369106D01*
X463395D01*
G37*
G36*
G01X469620Y374344D02*
X469652Y373589D01*
X468899Y373154D01*
X468261Y373559D01*
X468173Y373711D01*
X469533Y374495D01*
X469620Y374344D01*
G37*
G36*
G01X476374Y378241D02*
X476406Y377486D01*
X475653Y377051D01*
X475015Y377456D01*
X474927Y377607D01*
X476287Y378393D01*
X476374Y378241D01*
G37*
G36*
G01X472985Y376286D02*
X473017Y375531D01*
X472264Y375096D01*
X471626Y375501D01*
X471538Y375653D01*
X472898Y376437D01*
X472985Y376286D01*
G37*
G36*
G01X471911Y359675D02*
X471241Y360025D01*
Y360894D01*
X471911Y361244D01*
X472087D01*
X472086Y359675D01*
X471911D01*
G37*
G36*
G01X472451Y362252D02*
X472419Y363007D01*
X473172Y363442D01*
X473810Y363037D01*
X473898Y362885D01*
X472538Y362101D01*
X472451Y362252D01*
G37*
G36*
G01X475831Y364202D02*
X475799Y364957D01*
X476552Y365392D01*
X477190Y364987D01*
X477278Y364835D01*
X475918Y364051D01*
X475831Y364202D01*
G37*
G36*
G01X476213Y362491D02*
X476542Y361810D01*
X476023Y361112D01*
X475276Y361231D01*
X475136Y361335D01*
X476073Y362596D01*
X476213Y362491D01*
G37*
G36*
G01X458391Y359736D02*
X457721Y360086D01*
Y360956D01*
X458391Y361306D01*
X458566D01*
Y359736D01*
X458391D01*
G37*
G36*
G01Y363636D02*
X457721Y363986D01*
Y364856D01*
X458391Y365206D01*
X458566D01*
Y363636D01*
X458391D01*
G37*
G36*
G01Y367536D02*
X457721Y367886D01*
Y368756D01*
X458391Y369106D01*
X458566D01*
Y367536D01*
X458391D01*
G37*
G36*
G01X458933Y373954D02*
X458901Y374709D01*
X459654Y375143D01*
X460292Y374738D01*
X460380Y374587D01*
X459019Y373802D01*
X458933Y373954D01*
G37*
G36*
G01X462321Y375907D02*
X462289Y376662D01*
X463042Y377097D01*
X463680Y376692D01*
X463768Y376541D01*
X462408Y375755D01*
X462321Y375907D01*
G37*
G36*
G01X465686Y377848D02*
X465654Y378603D01*
X466407Y379038D01*
X467045Y378633D01*
X467133Y378481D01*
X465773Y377697D01*
X465686Y377848D01*
G37*
G36*
G01X458391Y371436D02*
X457721Y371786D01*
Y372656D01*
X458391Y373006D01*
X458566D01*
Y371436D01*
X458391D01*
G37*
G36*
G01X469072Y379802D02*
X469040Y380557D01*
X469793Y380992D01*
X470431Y380587D01*
X470519Y380435D01*
X469159Y379651D01*
X469072Y379802D01*
G37*
G36*
G01X472446Y381748D02*
X472414Y382503D01*
X473167Y382938D01*
X473805Y382533D01*
X473893Y382381D01*
X472533Y381597D01*
X472446Y381748D01*
G37*
G36*
G01X475831Y383702D02*
X475799Y384457D01*
X476552Y384892D01*
X477190Y384487D01*
X477278Y384335D01*
X475918Y383551D01*
X475831Y383702D01*
G37*
G36*
G01X460015Y371032D02*
X460685Y370682D01*
Y369812D01*
X460015Y369462D01*
X459840D01*
Y371032D01*
X460015D01*
G37*
G36*
G01Y367107D02*
X460685Y366757D01*
Y365887D01*
X460015Y365537D01*
X459840D01*
Y367107D01*
X460015D01*
G37*
G36*
G01X466225Y376286D02*
X466257Y375531D01*
X465504Y375096D01*
X464866Y375501D01*
X464778Y375653D01*
X466138Y376437D01*
X466225Y376286D01*
G37*
G36*
G01X462860Y374344D02*
X462892Y373589D01*
X462139Y373154D01*
X461501Y373559D01*
X461413Y373711D01*
X462773Y374495D01*
X462860Y374344D01*
G37*
G36*
G01X469614Y378241D02*
X469646Y377486D01*
X468893Y377051D01*
X468255Y377456D01*
X468167Y377607D01*
X469527Y378393D01*
X469614Y378241D01*
G37*
G36*
G01X476374Y382141D02*
X476406Y381386D01*
X475653Y380951D01*
X475015Y381356D01*
X474927Y381507D01*
X476287Y382293D01*
X476374Y382141D01*
G37*
G36*
G01X473000Y380195D02*
X473032Y379440D01*
X472279Y379005D01*
X471641Y379410D01*
X471553Y379561D01*
X472913Y380347D01*
X473000Y380195D01*
G37*
G36*
G01X469282Y357742D02*
X468612Y358092D01*
Y358962D01*
X469282Y359312D01*
X469457D01*
Y357742D01*
X469282D01*
G37*
G36*
G01X470155Y361306D02*
X470825Y360956D01*
Y360086D01*
X470155Y359736D01*
X469980D01*
Y361306D01*
X470155D01*
G37*
G36*
G01X472446Y366148D02*
X472414Y366903D01*
X473167Y367338D01*
X473805Y366933D01*
X473893Y366781D01*
X472533Y365997D01*
X472446Y366148D01*
G37*
G36*
G01X475831Y368102D02*
X475799Y368857D01*
X476552Y369292D01*
X477190Y368887D01*
X477278Y368735D01*
X475918Y367951D01*
X475831Y368102D01*
G37*
G36*
G01X476374Y366541D02*
X476406Y365786D01*
X475653Y365351D01*
X475015Y365756D01*
X474927Y365907D01*
X476287Y366693D01*
X476374Y366541D01*
G37*
G36*
G01X426216Y386607D02*
X426886Y386257D01*
Y385387D01*
X426216Y385037D01*
X426041D01*
Y386607D01*
X426216D01*
G37*
G36*
G01Y378807D02*
X426886Y378457D01*
Y377587D01*
X426216Y377237D01*
X426041D01*
Y378807D01*
X426216D01*
G37*
G36*
G01Y374956D02*
X426886Y374606D01*
Y373736D01*
X426216Y373386D01*
X426041D01*
Y374956D01*
X426216D01*
G37*
G36*
G01Y382707D02*
X426886Y382357D01*
Y381487D01*
X426216Y381137D01*
X426041D01*
Y382707D01*
X426216D01*
G37*
G36*
G01X429595Y369080D02*
X430265Y368731D01*
Y367861D01*
X429596Y367511D01*
X429421Y367510D01*
X429420Y369081D01*
X429595Y369080D01*
G37*
G36*
G01X427665Y370854D02*
X428303Y371260D01*
X429056Y370825D01*
X429025Y370070D01*
X428938Y369918D01*
X427577Y370703D01*
X427665Y370854D01*
G37*
G36*
G01X426216Y390507D02*
X426886Y390157D01*
Y389287D01*
X426216Y388937D01*
X426041D01*
Y390507D01*
X426216D01*
G37*
G36*
G01X432597Y401130D02*
X433357Y400780D01*
Y399880D01*
X432597Y399530D01*
X432422D01*
Y401130D01*
X432597D01*
G37*
G36*
G01X431632Y397181D02*
X431922Y396396D01*
X431285Y395759D01*
X430500Y396049D01*
X430377Y396173D01*
X431508Y397305D01*
X431632Y397181D01*
G37*
G36*
G01X429046Y393837D02*
X429078Y393082D01*
X428325Y392647D01*
X427687Y393052D01*
X427599Y393203D01*
X428959Y393989D01*
X429046Y393837D01*
G37*
G36*
G01X446495Y359307D02*
X447165Y358957D01*
Y358087D01*
X446495Y357737D01*
X446320D01*
Y359307D01*
X446495D01*
G37*
G36*
G01X452720Y384095D02*
X452752Y383340D01*
X451999Y382905D01*
X451361Y383310D01*
X451273Y383461D01*
X452633Y384247D01*
X452720Y384095D01*
G37*
G36*
G01X456094Y386041D02*
X456126Y385286D01*
X455373Y384851D01*
X454735Y385256D01*
X454647Y385407D01*
X456007Y386193D01*
X456094Y386041D01*
G37*
G36*
G01X459480Y387995D02*
X459512Y387240D01*
X458759Y386805D01*
X458121Y387210D01*
X458033Y387361D01*
X459393Y388147D01*
X459480Y387995D01*
G37*
G36*
G01X446495Y378807D02*
X447165Y378457D01*
Y377587D01*
X446495Y377237D01*
X446320D01*
Y378807D01*
X446495D01*
G37*
G36*
G01Y374956D02*
X447165Y374606D01*
Y373736D01*
X446495Y373386D01*
X446320D01*
Y374956D01*
X446495D01*
G37*
G36*
G01X449334Y382141D02*
X449366Y381386D01*
X448613Y380951D01*
X447975Y381356D01*
X447887Y381507D01*
X449247Y382293D01*
X449334Y382141D01*
G37*
G36*
G01X446495Y371032D02*
X447165Y370682D01*
Y369812D01*
X446495Y369462D01*
X446320D01*
Y371032D01*
X446495D01*
G37*
G36*
G01Y367107D02*
X447165Y366757D01*
Y365887D01*
X446495Y365537D01*
X446320D01*
Y367107D01*
X446495D01*
G37*
G36*
G01Y363207D02*
X447165Y362857D01*
Y361987D01*
X446495Y361637D01*
X446320D01*
Y363207D01*
X446495D01*
G37*
G36*
G01X462853Y389940D02*
X462884Y389185D01*
X462131Y388750D01*
X461493Y389156D01*
X461406Y389306D01*
X462766Y390092D01*
X462853Y389940D01*
G37*
G36*
G01X463395Y404205D02*
X464065Y403855D01*
Y402985D01*
X463395Y402635D01*
X463220D01*
Y404205D01*
X463395D01*
G37*
G36*
G01Y400280D02*
X464065Y399930D01*
Y399060D01*
X463395Y398710D01*
X463220D01*
Y400280D01*
X463395D01*
G37*
G36*
G01Y396355D02*
X464065Y396005D01*
Y395135D01*
X463395Y394785D01*
X463220D01*
Y396355D01*
X463395D01*
G37*
G36*
G01Y392455D02*
X464065Y392105D01*
Y391235D01*
X463395Y390885D01*
X463220D01*
Y392455D01*
X463395D01*
G37*
G36*
G01X466775Y359307D02*
X467445Y358957D01*
Y358087D01*
X466775Y357737D01*
X466600D01*
Y359307D01*
X466775D01*
G37*
G36*
G01Y363207D02*
X467445Y362857D01*
Y361987D01*
X466775Y361637D01*
X466600D01*
Y363207D01*
X466775D01*
G37*
G36*
G01Y367107D02*
X467445Y366757D01*
Y365887D01*
X466775Y365537D01*
X466600D01*
Y367107D01*
X466775D01*
G37*
G36*
G01X469605Y370436D02*
X469637Y369681D01*
X468884Y369246D01*
X468246Y369651D01*
X468158Y369803D01*
X469518Y370587D01*
X469605Y370436D01*
G37*
G36*
G01X472994Y372391D02*
X473026Y371636D01*
X472273Y371201D01*
X471635Y371606D01*
X471547Y371757D01*
X472907Y372543D01*
X472994Y372391D01*
G37*
G36*
G01X476380Y374344D02*
X476412Y373589D01*
X475659Y373154D01*
X475021Y373559D01*
X474933Y373711D01*
X476293Y374495D01*
X476380Y374344D01*
G37*
G36*
G01X427972Y385037D02*
X427302Y385387D01*
Y386257D01*
X427972Y386607D01*
X428147D01*
Y385037D01*
X427972D01*
G37*
G36*
G01X427973Y373381D02*
X427303Y373731D01*
Y374601D01*
X427973Y374951D01*
X428148D01*
Y373381D01*
X427973D01*
G37*
G36*
G01X427972Y377237D02*
X427302Y377587D01*
Y378457D01*
X427972Y378807D01*
X428147D01*
Y377237D01*
X427972D01*
G37*
G36*
G01Y381137D02*
X427302Y381487D01*
Y382357D01*
X427972Y382707D01*
X428147D01*
Y381137D01*
X427972D01*
G37*
G36*
G01Y388937D02*
X427302Y389287D01*
Y390157D01*
X427972Y390507D01*
X428147D01*
Y388937D01*
X427972D01*
G37*
G36*
G01X435247Y401414D02*
X434487Y401764D01*
Y402664D01*
X435247Y403014D01*
X435422D01*
Y401414D01*
X435247D01*
G37*
G36*
G01X433287Y395062D02*
X432997Y395846D01*
X433634Y396483D01*
X434418Y396193D01*
X434542Y396069D01*
X433411Y394938D01*
X433287Y395062D01*
G37*
G36*
G01X435247Y397514D02*
X434487Y397864D01*
Y398764D01*
X435247Y399114D01*
X435422D01*
Y397514D01*
X435247D01*
G37*
G36*
G01X428514Y391504D02*
X428482Y392259D01*
X429235Y392693D01*
X429873Y392288D01*
X429960Y392137D01*
X428601Y391351D01*
X428514Y391504D01*
G37*
G36*
G01X458926Y385648D02*
X458894Y386403D01*
X459647Y386838D01*
X460285Y386433D01*
X460373Y386281D01*
X459013Y385497D01*
X458926Y385648D01*
G37*
G36*
G01X455552Y383702D02*
X455520Y384457D01*
X456273Y384892D01*
X456911Y384487D01*
X456999Y384335D01*
X455639Y383551D01*
X455552Y383702D01*
G37*
G36*
G01X448251Y377286D02*
X447581Y377636D01*
Y378506D01*
X448251Y378856D01*
X448426D01*
Y377286D01*
X448251D01*
G37*
G36*
G01Y373386D02*
X447581Y373736D01*
Y374606D01*
X448251Y374956D01*
X448426D01*
Y373386D01*
X448251D01*
G37*
G36*
G01X448793Y379804D02*
X448761Y380559D01*
X449514Y380993D01*
X450152Y380588D01*
X450240Y380437D01*
X448879Y379652D01*
X448793Y379804D01*
G37*
G36*
G01X452166Y381748D02*
X452134Y382503D01*
X452887Y382938D01*
X453525Y382533D01*
X453613Y382381D01*
X452253Y381597D01*
X452166Y381748D01*
G37*
G36*
G01X448252Y369462D02*
X447582Y369812D01*
Y370682D01*
X448252Y371032D01*
X448427D01*
Y369462D01*
X448252D01*
G37*
G36*
G01X462312Y387602D02*
X462280Y388357D01*
X463033Y388792D01*
X463671Y388387D01*
X463759Y388235D01*
X462399Y387451D01*
X462312Y387602D01*
G37*
G36*
G01X465151Y398675D02*
X464481Y399025D01*
Y399895D01*
X465151Y400245D01*
X465326D01*
Y398675D01*
X465151D01*
G37*
G36*
G01Y402611D02*
X464481Y402961D01*
Y403831D01*
X465151Y404181D01*
X465326D01*
Y402611D01*
X465151D01*
G37*
G36*
G01X465152Y394786D02*
X464482Y395136D01*
Y396006D01*
X465152Y396356D01*
X465327D01*
Y394786D01*
X465152D01*
G37*
G36*
G01Y390911D02*
X464482Y391261D01*
Y392131D01*
X465152Y392481D01*
X465327D01*
Y390911D01*
X465152D01*
G37*
G36*
G01X469081Y368107D02*
X469049Y368862D01*
X469802Y369297D01*
X470440Y368892D01*
X470528Y368741D01*
X469168Y367955D01*
X469081Y368107D01*
G37*
G36*
G01X472461Y370057D02*
X472429Y370812D01*
X473182Y371247D01*
X473820Y370842D01*
X473908Y370691D01*
X472548Y369905D01*
X472461Y370057D01*
G37*
G36*
G01X475825Y371999D02*
X475793Y372754D01*
X476546Y373189D01*
X477184Y372784D01*
X477272Y372633D01*
X475912Y371847D01*
X475825Y371999D01*
G37*
G36*
G01X424592Y383136D02*
X423922Y383486D01*
Y384356D01*
X424592Y384706D01*
X424767D01*
Y383136D01*
X424592D01*
G37*
G36*
G01Y387036D02*
X423922Y387386D01*
Y388256D01*
X424592Y388606D01*
X424767D01*
Y387036D01*
X424592D01*
G37*
G36*
G01Y371411D02*
X423922Y371761D01*
Y372631D01*
X424592Y372981D01*
X424767D01*
Y371411D01*
X424592D01*
G37*
G36*
G01Y375311D02*
X423922Y375661D01*
Y376531D01*
X424592Y376881D01*
X424767D01*
Y375311D01*
X424592D01*
G37*
G36*
G01Y379236D02*
X423922Y379586D01*
Y380456D01*
X424592Y380806D01*
X424767D01*
Y379236D01*
X424592D01*
G37*
G36*
G01X427973Y365533D02*
X427303Y365883D01*
Y366753D01*
X427973Y367103D01*
X428148D01*
Y365533D01*
X427973D01*
G37*
G36*
G01X426522Y369638D02*
X425884Y369233D01*
X425131Y369667D01*
X425162Y370422D01*
X425250Y370575D01*
X426610Y369789D01*
X426522Y369638D01*
G37*
G36*
G01X431497Y399530D02*
X430737Y399880D01*
Y400780D01*
X431497Y401130D01*
X431672D01*
Y399530D01*
X431497D01*
G37*
G36*
G01X425163Y393470D02*
X425132Y394225D01*
X425885Y394660D01*
X426523Y394254D01*
X426611Y394103D01*
X425250Y393318D01*
X425163Y393470D01*
G37*
G36*
G01X424592Y390936D02*
X423922Y391286D01*
Y392156D01*
X424592Y392506D01*
X424767D01*
Y390936D01*
X424592D01*
G37*
G36*
G01X444871Y355836D02*
X444201Y356186D01*
Y357056D01*
X444871Y357406D01*
X445046D01*
Y355836D01*
X444871D01*
G37*
G36*
G01Y371387D02*
X444201Y371737D01*
Y372607D01*
X444871Y372957D01*
X445046D01*
Y371387D01*
X444871D01*
G37*
G36*
G01Y375311D02*
X444201Y375661D01*
Y376531D01*
X444871Y376881D01*
X445046D01*
Y375311D01*
X444871D01*
G37*
G36*
G01Y379211D02*
X444201Y379561D01*
Y380431D01*
X444871Y380781D01*
X445046D01*
Y379211D01*
X444871D01*
G37*
G36*
G01Y359736D02*
X444201Y360086D01*
Y360956D01*
X444871Y361306D01*
X445046D01*
Y359736D01*
X444871D01*
G37*
G36*
G01Y363636D02*
X444201Y363986D01*
Y364856D01*
X444871Y365206D01*
X445046D01*
Y363636D01*
X444871D01*
G37*
G36*
G01Y367536D02*
X444201Y367886D01*
Y368756D01*
X444871Y369106D01*
X445046D01*
Y367536D01*
X444871D01*
G37*
G36*
G01X448792Y383702D02*
X448760Y384457D01*
X449513Y384892D01*
X450151Y384487D01*
X450239Y384335D01*
X448879Y383551D01*
X448792Y383702D01*
G37*
G36*
G01X452166Y385648D02*
X452134Y386403D01*
X452887Y386838D01*
X453525Y386433D01*
X453613Y386281D01*
X452253Y385497D01*
X452166Y385648D01*
G37*
G36*
G01X445427Y381762D02*
X445395Y382517D01*
X446149Y382951D01*
X446786Y382546D01*
X446875Y382395D01*
X445514Y381610D01*
X445427Y381762D01*
G37*
G36*
G01X458926Y389548D02*
X458894Y390303D01*
X459647Y390738D01*
X460285Y390333D01*
X460373Y390181D01*
X459013Y389397D01*
X458926Y389548D01*
G37*
G36*
G01X455552Y387602D02*
X455520Y388357D01*
X456273Y388792D01*
X456911Y388387D01*
X456999Y388235D01*
X455639Y387451D01*
X455552Y387602D01*
G37*
G36*
G01X461771Y400660D02*
X461101Y401010D01*
Y401880D01*
X461771Y402230D01*
X461946D01*
Y400660D01*
X461771D01*
G37*
G36*
G01Y396784D02*
X461101Y397134D01*
Y398004D01*
X461771Y398354D01*
X461946D01*
Y396784D01*
X461771D01*
G37*
G36*
G01Y392885D02*
X461101Y393235D01*
Y394105D01*
X461771Y394455D01*
X461946D01*
Y392885D01*
X461771D01*
G37*
G36*
G01X465151Y355836D02*
X464481Y356186D01*
Y357056D01*
X465151Y357406D01*
X465326D01*
Y355836D01*
X465151D01*
G37*
G36*
G01Y367536D02*
X464481Y367886D01*
Y368756D01*
X465151Y369106D01*
X465326D01*
Y367536D01*
X465151D01*
G37*
G36*
G01X465722Y370070D02*
X465691Y370825D01*
X466444Y371260D01*
X467082Y370854D01*
X467169Y370704D01*
X465809Y369918D01*
X465722Y370070D01*
G37*
G36*
G01X465151Y363636D02*
X464481Y363986D01*
Y364856D01*
X465151Y365206D01*
X465326D01*
Y363636D01*
X465151D01*
G37*
G36*
G01Y359736D02*
X464481Y360086D01*
Y360956D01*
X465151Y361306D01*
X465326D01*
Y359736D01*
X465151D01*
G37*
G36*
G01X469066Y371999D02*
X469034Y372754D01*
X469787Y373189D01*
X470425Y372784D01*
X470513Y372633D01*
X469153Y371847D01*
X469066Y371999D01*
G37*
G36*
G01X472452Y373952D02*
X472420Y374707D01*
X473173Y375142D01*
X473811Y374737D01*
X473899Y374585D01*
X472539Y373801D01*
X472452Y373952D01*
G37*
G36*
G01X475840Y375907D02*
X475808Y376662D01*
X476561Y377097D01*
X477199Y376692D01*
X477287Y376541D01*
X475927Y375755D01*
X475840Y375907D01*
G37*
G36*
G01X429596Y384706D02*
X430266Y384356D01*
Y383486D01*
X429596Y383136D01*
X429421D01*
Y384706D01*
X429596D01*
G37*
G36*
G01Y388606D02*
X430266Y388256D01*
Y387386D01*
X429596Y387036D01*
X429421D01*
Y388606D01*
X429596D01*
G37*
G36*
G01Y376881D02*
X430266Y376531D01*
Y375661D01*
X429596Y375311D01*
X429421D01*
Y376881D01*
X429596D01*
G37*
G36*
G01Y380806D02*
X430266Y380456D01*
Y379586D01*
X429596Y379236D01*
X429421D01*
Y380806D01*
X429596D01*
G37*
G36*
G01X436347Y403014D02*
X437107Y402664D01*
Y401764D01*
X436347Y401414D01*
X436172D01*
Y403014D01*
X436347D01*
G37*
G36*
G01X435197Y395414D02*
X435487Y394630D01*
X434850Y393993D01*
X434066Y394283D01*
X433942Y394407D01*
X435073Y395538D01*
X435197Y395414D01*
G37*
G36*
G01X436347Y399114D02*
X437107Y398764D01*
Y397864D01*
X436347Y397514D01*
X436172D01*
Y399114D01*
X436347D01*
G37*
G36*
G01X432441Y391895D02*
X432473Y391140D01*
X431720Y390705D01*
X431082Y391110D01*
X430994Y391261D01*
X432354Y392047D01*
X432441Y391895D01*
G37*
G36*
G01X459480Y384095D02*
X459512Y383340D01*
X458759Y382905D01*
X458121Y383310D01*
X458033Y383461D01*
X459393Y384247D01*
X459480Y384095D01*
G37*
G36*
G01X449875Y376881D02*
X450545Y376531D01*
Y375661D01*
X449875Y375311D01*
X449700D01*
Y376881D01*
X449875D01*
G37*
G36*
G01Y372957D02*
X450545Y372607D01*
Y371737D01*
X449875Y371387D01*
X449700D01*
Y372957D01*
X449875D01*
G37*
G36*
G01X452720Y380195D02*
X452752Y379440D01*
X451999Y379005D01*
X451361Y379410D01*
X451273Y379561D01*
X452633Y380347D01*
X452720Y380195D01*
G37*
G36*
G01X456094Y382141D02*
X456126Y381386D01*
X455373Y380951D01*
X454735Y381356D01*
X454647Y381507D01*
X456007Y382293D01*
X456094Y382141D01*
G37*
G36*
G01X449875Y369057D02*
X450545Y368707D01*
Y367837D01*
X449875Y367487D01*
X449700D01*
Y369057D01*
X449875D01*
G37*
G36*
G01X462854Y386041D02*
X462886Y385286D01*
X462133Y384851D01*
X461495Y385256D01*
X461407Y385407D01*
X462767Y386193D01*
X462854Y386041D01*
G37*
G36*
G01X466219Y387981D02*
X466251Y387226D01*
X465497Y386792D01*
X464860Y387197D01*
X464771Y387348D01*
X466132Y388133D01*
X466219Y387981D01*
G37*
G36*
G01X466775Y390555D02*
X467445Y390205D01*
Y389335D01*
X466775Y388985D01*
X466600D01*
Y390555D01*
X466775D01*
G37*
G36*
G01Y402255D02*
X467445Y401905D01*
Y401035D01*
X466775Y400685D01*
X466600D01*
Y402255D01*
X466775D01*
G37*
G36*
G01Y398354D02*
X467445Y398004D01*
Y397134D01*
X466775Y396784D01*
X466600D01*
Y398354D01*
X466775D01*
G37*
G36*
G01Y394455D02*
X467445Y394105D01*
Y393235D01*
X466775Y392885D01*
X466600D01*
Y394455D01*
X466775D01*
G37*
G36*
G01X473000Y368495D02*
X473032Y367740D01*
X472279Y367305D01*
X471641Y367710D01*
X471553Y367861D01*
X472913Y368647D01*
X473000Y368495D01*
G37*
G36*
G01X476365Y370436D02*
X476397Y369681D01*
X475644Y369246D01*
X475006Y369651D01*
X474918Y369803D01*
X476278Y370587D01*
X476365Y370436D01*
G37*
G36*
G01X425115Y406411D02*
X424355Y406761D01*
Y407661D01*
X425115Y408011D01*
X425290D01*
Y406411D01*
X425115D01*
G37*
G36*
G01X426217Y407511D02*
X426977Y407161D01*
Y406261D01*
X426217Y405911D01*
X426042D01*
Y407511D01*
X426217D01*
G37*
G36*
G01X421197Y406659D02*
X420437Y407009D01*
Y407909D01*
X421197Y408259D01*
X421372D01*
Y406659D01*
X421197D01*
G37*
G36*
G01X422314Y408259D02*
X423074Y407909D01*
Y407009D01*
X422314Y406659D01*
X422139D01*
Y408259D01*
X422314D01*
G37*
G36*
G01X458391Y406546D02*
X457721Y406896D01*
Y407766D01*
X458391Y408116D01*
X458566D01*
Y406546D01*
X458391D01*
G37*
G36*
G01Y410446D02*
X457721Y410796D01*
Y411666D01*
X458391Y412016D01*
X458566D01*
Y410446D01*
X458391D01*
G37*
G36*
G01Y414346D02*
X457721Y414696D01*
Y415566D01*
X458391Y415916D01*
X458566D01*
Y414346D01*
X458391D01*
G37*
G36*
G01X460015Y409996D02*
X460685Y409646D01*
Y408776D01*
X460015Y408426D01*
X459840D01*
Y409996D01*
X460015D01*
G37*
G36*
G01Y406096D02*
X460685Y405746D01*
Y404876D01*
X460015Y404526D01*
X459840D01*
Y406096D01*
X460015D01*
G37*
G36*
G01Y413896D02*
X460685Y413546D01*
Y412676D01*
X460015Y412326D01*
X459840D01*
Y413896D01*
X460015D01*
G37*
G36*
G01Y417796D02*
X460685Y417446D01*
Y416576D01*
X460015Y416226D01*
X459840D01*
Y417796D01*
X460015D01*
G37*
G36*
G01X471911Y410436D02*
X471241Y410786D01*
Y411656D01*
X471911Y412006D01*
X472086D01*
Y410436D01*
X471911D01*
G37*
G36*
G01Y406536D02*
X471241Y406886D01*
Y407756D01*
X471911Y408106D01*
X472086D01*
Y406536D01*
X471911D01*
G37*
G36*
G01Y414336D02*
X471241Y414686D01*
Y415556D01*
X471911Y415906D01*
X472086D01*
Y414336D01*
X471911D01*
G37*
G36*
G01X473535Y410007D02*
X474205Y409657D01*
Y408787D01*
X473535Y408437D01*
X473360D01*
Y410007D01*
X473535D01*
G37*
G36*
G01Y406107D02*
X474205Y405757D01*
Y404887D01*
X473535Y404537D01*
X473360D01*
Y406107D01*
X473535D01*
G37*
G36*
G01Y413907D02*
X474205Y413557D01*
Y412687D01*
X473535Y412337D01*
X473360D01*
Y413907D01*
X473535D01*
G37*
G36*
G01X455011Y408437D02*
X454341Y408787D01*
Y409657D01*
X455011Y410007D01*
X455186D01*
Y408437D01*
X455011D01*
G37*
G36*
G01Y404537D02*
X454341Y404887D01*
Y405757D01*
X455011Y406107D01*
X455186D01*
Y404537D01*
X455011D01*
G37*
G36*
G01X454518Y414523D02*
X453734Y414233D01*
X453097Y414870D01*
X453387Y415654D01*
X453511Y415778D01*
X454642Y414647D01*
X454518Y414523D01*
G37*
G36*
G01X456635Y412006D02*
X457305Y411656D01*
Y410786D01*
X456635Y410436D01*
X456460D01*
Y412006D01*
X456635D01*
G37*
G36*
G01Y408106D02*
X457305Y407756D01*
Y406886D01*
X456635Y406536D01*
X456460D01*
Y408106D01*
X456635D01*
G37*
G36*
G01X454166Y416433D02*
X454951Y416723D01*
X455587Y416087D01*
X455297Y415302D01*
X455174Y415178D01*
X454042Y416310D01*
X454166Y416433D01*
G37*
G36*
G01X468531Y408437D02*
X467861Y408787D01*
Y409657D01*
X468531Y410007D01*
X468706D01*
Y408437D01*
X468531D01*
G37*
G36*
G01Y412337D02*
X467861Y412687D01*
Y413557D01*
X468531Y413907D01*
X468706D01*
Y412337D01*
X468531D01*
G37*
G36*
G01Y404537D02*
X467861Y404887D01*
Y405757D01*
X468531Y406107D01*
X468706D01*
Y404537D01*
X468531D01*
G37*
G36*
G01Y416237D02*
X467861Y416587D01*
Y417457D01*
X468531Y417807D01*
X468706D01*
Y416237D01*
X468531D01*
G37*
G36*
G01X470155Y408106D02*
X470825Y407756D01*
Y406886D01*
X470155Y406536D01*
X469980D01*
Y408106D01*
X470155D01*
G37*
G36*
G01Y412006D02*
X470825Y411656D01*
Y410786D01*
X470155Y410436D01*
X469980D01*
Y412006D01*
X470155D01*
G37*
G36*
G01Y415906D02*
X470825Y415556D01*
Y414686D01*
X470155Y414336D01*
X469980D01*
Y415906D01*
X470155D01*
G37*
G36*
G01X432597Y405030D02*
X433357Y404680D01*
Y403780D01*
X432597Y403430D01*
X432422D01*
Y405030D01*
X432597D01*
G37*
G36*
G01Y408930D02*
X433357Y408580D01*
Y407680D01*
X432597Y407330D01*
X432422D01*
Y408930D01*
X432597D01*
G37*
G36*
G01X463395Y412016D02*
X464065Y411666D01*
Y410796D01*
X463395Y410446D01*
X463220D01*
Y412016D01*
X463395D01*
G37*
G36*
G01Y408116D02*
X464065Y407766D01*
Y406896D01*
X463395Y406546D01*
X463220D01*
Y408116D01*
X463395D01*
G37*
G36*
G01Y415916D02*
X464065Y415566D01*
Y414696D01*
X463395Y414346D01*
X463220D01*
Y415916D01*
X463395D01*
G37*
G36*
G01X435247Y405314D02*
X434487Y405664D01*
Y406564D01*
X435247Y406914D01*
X435422D01*
Y405314D01*
X435247D01*
G37*
G36*
G01Y409214D02*
X434487Y409564D01*
Y410464D01*
X435247Y410814D01*
X435422D01*
Y409214D01*
X435247D01*
G37*
G36*
G01X465151Y406536D02*
X464481Y406886D01*
Y407756D01*
X465151Y408106D01*
X465326D01*
Y406536D01*
X465151D01*
G37*
G36*
G01Y410436D02*
X464481Y410786D01*
Y411656D01*
X465151Y412006D01*
X465326D01*
Y410436D01*
X465151D01*
G37*
G36*
G01Y414336D02*
X464481Y414686D01*
Y415556D01*
X465151Y415906D01*
X465326D01*
Y414336D01*
X465151D01*
G37*
G36*
G01X465373Y418729D02*
X464613Y419079D01*
Y419979D01*
X465373Y420329D01*
X465548D01*
Y418729D01*
X465373D01*
G37*
G36*
G01X431497Y403430D02*
X430737Y403780D01*
Y404680D01*
X431497Y405030D01*
X431672D01*
Y403430D01*
X431497D01*
G37*
G36*
G01Y407330D02*
X430737Y407680D01*
Y408580D01*
X431497Y408930D01*
X431672D01*
Y407330D01*
X431497D01*
G37*
G36*
G01X461771Y404526D02*
X461101Y404876D01*
Y405746D01*
X461771Y406096D01*
X461946D01*
Y404526D01*
X461771D01*
G37*
G36*
G01Y408426D02*
X461101Y408776D01*
Y409646D01*
X461771Y409996D01*
X461946D01*
Y408426D01*
X461771D01*
G37*
G36*
G01Y412326D02*
X461101Y412676D01*
Y413546D01*
X461771Y413896D01*
X461946D01*
Y412326D01*
X461771D01*
G37*
G36*
G01X436347Y406914D02*
X437107Y406564D01*
Y405664D01*
X436347Y405314D01*
X436172D01*
Y406914D01*
X436347D01*
G37*
G36*
G01Y410814D02*
X437107Y410464D01*
Y409564D01*
X436347Y409214D01*
X436172D01*
Y410814D01*
X436347D01*
G37*
G36*
G01X466775Y410007D02*
X467445Y409657D01*
Y408787D01*
X466775Y408437D01*
X466600D01*
Y410007D01*
X466775D01*
G37*
G36*
G01Y406107D02*
X467445Y405757D01*
Y404887D01*
X466775Y404537D01*
X466600D01*
Y406107D01*
X466775D01*
G37*
G36*
G01Y413907D02*
X467445Y413557D01*
Y412687D01*
X466775Y412337D01*
X466600D01*
Y413907D01*
X466775D01*
G37*
G36*
G01Y417807D02*
X467445Y417457D01*
Y416587D01*
X466775Y416237D01*
X466600D01*
Y417807D01*
X466775D01*
G37*
G36*
G01X466473Y420329D02*
X467233Y419979D01*
Y419079D01*
X466473Y418729D01*
X466298D01*
Y420329D01*
X466473D01*
G37*
G36*
G01X480016Y194943D02*
X479232Y194653D01*
X478595Y195290D01*
X478885Y196074D01*
X479009Y196198D01*
X480140Y195067D01*
X480016Y194943D01*
G37*
G36*
G01X479665Y196854D02*
X480450Y197144D01*
X481086Y196508D01*
X480796Y195723D01*
X480673Y195599D01*
X479541Y196731D01*
X479665Y196854D01*
G37*
G36*
G01X487690Y211536D02*
X487020Y211886D01*
Y212756D01*
X487690Y213106D01*
X487865D01*
Y211536D01*
X487690D01*
G37*
G36*
G01X491697Y206963D02*
X490912Y206673D01*
X490276Y207309D01*
X490566Y208094D01*
X490689Y208218D01*
X491821Y207086D01*
X491697Y206963D01*
G37*
G36*
G01X487690Y215436D02*
X487020Y215786D01*
Y216656D01*
X487690Y217006D01*
X487865D01*
Y215436D01*
X487690D01*
G37*
G36*
G01X489314Y215007D02*
X489984Y214657D01*
Y213787D01*
X489314Y213437D01*
X489139D01*
Y215007D01*
X489314D01*
G37*
G36*
G01X491344Y208872D02*
X492128Y209162D01*
X492765Y208525D01*
X492475Y207741D01*
X492351Y207617D01*
X491220Y208748D01*
X491344Y208872D01*
G37*
G36*
G01X489314Y218907D02*
X489984Y218557D01*
Y217687D01*
X489314Y217337D01*
X489139D01*
Y218907D01*
X489314D01*
G37*
G36*
G01X488541Y203462D02*
X487757Y203172D01*
X487120Y203809D01*
X487410Y204593D01*
X487534Y204717D01*
X488665Y203586D01*
X488541Y203462D01*
G37*
G36*
G01X484311Y209581D02*
X483641Y209931D01*
Y210801D01*
X484311Y211151D01*
X484486D01*
Y209581D01*
X484311D01*
G37*
G36*
G01X484310Y213437D02*
X483640Y213787D01*
Y214657D01*
X484310Y215007D01*
X484485D01*
Y213437D01*
X484310D01*
G37*
G36*
G01Y217337D02*
X483640Y217687D01*
Y218557D01*
X484310Y218907D01*
X484485D01*
Y217337D01*
X484310D01*
G37*
G36*
G01X485934Y213081D02*
X486604Y212731D01*
Y211861D01*
X485934Y211511D01*
X485759D01*
Y213081D01*
X485934D01*
G37*
G36*
G01X488286Y205282D02*
X489070Y205572D01*
X489707Y204935D01*
X489417Y204151D01*
X489293Y204027D01*
X488162Y205158D01*
X488286Y205282D01*
G37*
G36*
G01X485934Y217006D02*
X486604Y216656D01*
Y215786D01*
X485934Y215436D01*
X485759D01*
Y217006D01*
X485934D01*
G37*
G36*
G01X481164Y200135D02*
X481949Y200425D01*
X482585Y199789D01*
X482296Y199004D01*
X482172Y198880D01*
X481040Y200012D01*
X481164Y200135D01*
G37*
G36*
G01X484670Y197851D02*
X485455Y198141D01*
X486091Y197505D01*
X485802Y196720D01*
X485678Y196596D01*
X484546Y197728D01*
X484670Y197851D01*
G37*
G36*
G01X479173Y213037D02*
X479843Y212687D01*
Y211817D01*
X479173Y211467D01*
X478998D01*
Y213037D01*
X479173D01*
G37*
G36*
G01X479174Y217006D02*
X479844Y216656D01*
Y215786D01*
X479174Y215436D01*
X478999D01*
Y217006D01*
X479174D01*
G37*
G36*
G01X478653Y209193D02*
X479323Y208843D01*
Y207973D01*
X478653Y207623D01*
X478478D01*
Y209193D01*
X478653D01*
G37*
G36*
G01X482554Y215007D02*
X483224Y214657D01*
Y213787D01*
X482554Y213437D01*
X482379D01*
Y215007D01*
X482554D01*
G37*
G36*
G01X482822Y209772D02*
X483582Y209422D01*
Y208522D01*
X482822Y208172D01*
X482647D01*
Y209772D01*
X482822D01*
G37*
G36*
G01Y205872D02*
X483582Y205522D01*
Y204622D01*
X482822Y204272D01*
X482647D01*
Y205872D01*
X482822D01*
G37*
G36*
G01X482554Y218907D02*
X483224Y218557D01*
Y217687D01*
X482554Y217337D01*
X482379D01*
Y218907D01*
X482554D01*
G37*
G36*
G01X481450Y198294D02*
X480665Y198004D01*
X480029Y198640D01*
X480318Y199425D01*
X480442Y199549D01*
X481574Y198417D01*
X481450Y198294D01*
G37*
G36*
G01X481722Y203772D02*
X480962Y204122D01*
Y205022D01*
X481722Y205372D01*
X481897D01*
Y203772D01*
X481722D01*
G37*
G36*
G01X480930Y215436D02*
X480260Y215786D01*
Y216656D01*
X480930Y217006D01*
X481105D01*
Y215436D01*
X480930D01*
G37*
G36*
G01Y211511D02*
X480260Y211861D01*
Y212731D01*
X480930Y213081D01*
X481105D01*
Y211511D01*
X480930D01*
G37*
G36*
G01X481722Y207672D02*
X480962Y208022D01*
Y208922D01*
X481722Y209272D01*
X481897D01*
Y207672D01*
X481722D01*
G37*
G36*
G01X546398Y201603D02*
Y201403D01*
G03X548352Y200111I1402J-3D01*
G01X548476Y200165D01*
X611006Y137635D01*
X615184Y127549D01*
Y119627D01*
G03X614958Y119336I985J-998D01*
G02X614388Y119208I-345J203D01*
G03X614522Y116989I-786J-1161D01*
G02X615184Y116687I262J-302D01*
G01Y110607D01*
G02X614522Y110305I-400J0D01*
G03X614260Y108009I-920J-1058D01*
G02X614818Y107807I188J-353D01*
G03X615184Y107291I1297J532D01*
G01Y93960D01*
X615055Y93911D01*
G03Y91287I494J-1312D01*
G01X615184Y91238D01*
Y90905D01*
X613672Y89393D01*
X608324D01*
X606929Y90788D01*
Y91000D01*
X606416Y91513D01*
X606545Y91654D01*
G03X604565Y93634I-1035J945D01*
G01X604424Y93505D01*
X604000Y93929D01*
Y102846D01*
G03Y105096I-837J1125D01*
G01Y108493D01*
G02X604528Y108872I400J0D01*
G03Y111528I449J1328D01*
G02X604000Y111907I-128J379D01*
G01Y117311D01*
G02X604539Y117686I400J0D01*
G03X603873Y119795I489J1314D01*
G02X603261Y119739I-329J227D01*
G01X524063Y198937D01*
Y204749D01*
X524423Y205109D01*
X524691D01*
X524719Y205101D01*
G03X525503I392J1346D01*
G01X525531Y205109D01*
X527613D01*
X527638Y205103D01*
G03X529344I853J3294D01*
G01X529369Y205109D01*
X531451D01*
X531479Y205101D01*
G03X532263I392J1346D01*
G01X532291Y205109D01*
X533462D01*
G02X533859Y204662I0J-400D01*
G03X536350Y203625I1392J-166D01*
G01X539323D01*
X541345Y201603D01*
X546398D01*
G37*
G36*
G01X487690Y219336D02*
X487020Y219686D01*
Y220556D01*
X487690Y220906D01*
X487865D01*
Y219336D01*
X487690D01*
G37*
G36*
G01Y223236D02*
X487020Y223586D01*
Y224456D01*
X487690Y224806D01*
X487865D01*
Y223236D01*
X487690D01*
G37*
G36*
G01Y227136D02*
X487020Y227486D01*
Y228356D01*
X487690Y228706D01*
X487865D01*
Y227136D01*
X487690D01*
G37*
G36*
G01Y230987D02*
X487020Y231337D01*
Y232207D01*
X487690Y232557D01*
X487865D01*
Y230987D01*
X487690D01*
G37*
G36*
G01Y234911D02*
X487020Y235261D01*
Y236131D01*
X487690Y236481D01*
X487865D01*
Y234911D01*
X487690D01*
G37*
G36*
G01X487709Y238836D02*
X487039Y239186D01*
Y240056D01*
X487709Y240406D01*
X487884D01*
Y238836D01*
X487709D01*
G37*
G36*
G01X487705Y242710D02*
X487035Y243060D01*
Y243930D01*
X487705Y244280D01*
X487880D01*
Y242710D01*
X487705D01*
G37*
G36*
G01Y246610D02*
X487035Y246960D01*
Y247830D01*
X487705Y248180D01*
X487880D01*
Y246610D01*
X487705D01*
G37*
G36*
G01X489314Y226707D02*
X489984Y226357D01*
Y225487D01*
X489314Y225137D01*
X489139D01*
Y226707D01*
X489314D01*
G37*
G36*
G01Y222807D02*
X489984Y222457D01*
Y221587D01*
X489314Y221237D01*
X489139D01*
Y222807D01*
X489314D01*
G37*
G36*
G01Y230632D02*
X489984Y230282D01*
Y229412D01*
X489314Y229062D01*
X489139D01*
Y230632D01*
X489314D01*
G37*
G36*
G01Y234556D02*
X489984Y234206D01*
Y233336D01*
X489314Y232986D01*
X489139D01*
Y234556D01*
X489314D01*
G37*
G36*
G01X489400Y242283D02*
X490070Y241933D01*
Y241063D01*
X489400Y240713D01*
X489225D01*
Y242283D01*
X489400D01*
G37*
G36*
G01X489314Y238407D02*
X489984Y238057D01*
Y237187D01*
X489314Y236837D01*
X489139D01*
Y238407D01*
X489314D01*
G37*
G36*
G01X489354Y246243D02*
X490024Y245893D01*
Y245023D01*
X489354Y244673D01*
X489179D01*
Y246243D01*
X489354D01*
G37*
G36*
G01Y250143D02*
X490024Y249793D01*
Y248923D01*
X489354Y248573D01*
X489179D01*
Y250143D01*
X489354D01*
G37*
G36*
G01X484310Y221237D02*
X483640Y221587D01*
Y222457D01*
X484310Y222807D01*
X484485D01*
Y221237D01*
X484310D01*
G37*
G36*
G01Y225137D02*
X483640Y225487D01*
Y226357D01*
X484310Y226707D01*
X484485D01*
Y225137D01*
X484310D01*
G37*
G36*
G01Y229062D02*
X483640Y229412D01*
Y230282D01*
X484310Y230632D01*
X484485D01*
Y229062D01*
X484310D01*
G37*
G36*
G01Y232986D02*
X483640Y233336D01*
Y234206D01*
X484310Y234556D01*
X484485D01*
Y232986D01*
X484310D01*
G37*
G36*
G01Y236837D02*
X483640Y237187D01*
Y238057D01*
X484310Y238407D01*
X484485D01*
Y236837D01*
X484310D01*
G37*
G36*
G01X484311Y240762D02*
X483641Y241112D01*
Y241982D01*
X484311Y242332D01*
X484486D01*
Y240762D01*
X484311D01*
G37*
G36*
G01Y244662D02*
X483641Y245012D01*
Y245882D01*
X484311Y246232D01*
X484486D01*
Y244662D01*
X484311D01*
G37*
G36*
G01X485934Y220906D02*
X486604Y220556D01*
Y219686D01*
X485934Y219336D01*
X485759D01*
Y220906D01*
X485934D01*
G37*
G36*
G01Y224806D02*
X486604Y224456D01*
Y223586D01*
X485934Y223236D01*
X485759D01*
Y224806D01*
X485934D01*
G37*
G36*
G01Y228706D02*
X486604Y228356D01*
Y227486D01*
X485934Y227136D01*
X485759D01*
Y228706D01*
X485934D01*
G37*
G36*
G01Y232557D02*
X486604Y232207D01*
Y231337D01*
X485934Y230987D01*
X485759D01*
Y232557D01*
X485934D01*
G37*
G36*
G01Y236481D02*
X486604Y236131D01*
Y235261D01*
X485934Y234911D01*
X485759D01*
Y236481D01*
X485934D01*
G37*
G36*
G01Y240406D02*
X486604Y240056D01*
Y239186D01*
X485934Y238836D01*
X485759D01*
Y240406D01*
X485934D01*
G37*
G36*
G01Y244282D02*
X486604Y243932D01*
Y243062D01*
X485934Y242712D01*
X485759D01*
Y244282D01*
X485934D01*
G37*
G36*
G01Y248182D02*
X486604Y247832D01*
Y246962D01*
X485934Y246612D01*
X485759D01*
Y248182D01*
X485934D01*
G37*
G36*
G01X479174Y232557D02*
X479844Y232207D01*
Y231337D01*
X479174Y230987D01*
X478999D01*
Y232557D01*
X479174D01*
G37*
G36*
G01Y224806D02*
X479844Y224456D01*
Y223586D01*
X479174Y223236D01*
X478999D01*
Y224806D01*
X479174D01*
G37*
G36*
G01Y220906D02*
X479844Y220556D01*
Y219686D01*
X479174Y219336D01*
X478999D01*
Y220906D01*
X479174D01*
G37*
G36*
G01Y228706D02*
X479844Y228356D01*
Y227486D01*
X479174Y227136D01*
X478999D01*
Y228706D01*
X479174D01*
G37*
G36*
G01Y240406D02*
X479844Y240056D01*
Y239186D01*
X479174Y238836D01*
X478999D01*
Y240406D01*
X479174D01*
G37*
G36*
G01Y236481D02*
X479844Y236131D01*
Y235261D01*
X479174Y234911D01*
X478999D01*
Y236481D01*
X479174D01*
G37*
G36*
G01X482554Y226707D02*
X483224Y226357D01*
Y225487D01*
X482554Y225137D01*
X482379D01*
Y226707D01*
X482554D01*
G37*
G36*
G01Y222807D02*
X483224Y222457D01*
Y221587D01*
X482554Y221237D01*
X482379D01*
Y222807D01*
X482554D01*
G37*
G36*
G01Y230632D02*
X483224Y230282D01*
Y229412D01*
X482554Y229062D01*
X482379D01*
Y230632D01*
X482554D01*
G37*
G36*
G01Y234556D02*
X483224Y234206D01*
Y233336D01*
X482554Y232986D01*
X482379D01*
Y234556D01*
X482554D01*
G37*
G36*
G01Y246207D02*
X483224Y245857D01*
Y244987D01*
X482554Y244637D01*
X482379D01*
Y246207D01*
X482554D01*
G37*
G36*
G01Y242307D02*
X483224Y241957D01*
Y241087D01*
X482554Y240737D01*
X482379D01*
Y242307D01*
X482554D01*
G37*
G36*
G01Y238407D02*
X483224Y238057D01*
Y237187D01*
X482554Y236837D01*
X482379D01*
Y238407D01*
X482554D01*
G37*
G36*
G01X482552Y254056D02*
X483222Y253706D01*
X483223Y252836D01*
X482552Y252487D01*
X482378D01*
X482377Y254056D01*
X482552D01*
G37*
G36*
G01X482554Y250107D02*
X483224Y249757D01*
Y248887D01*
X482554Y248537D01*
X482379D01*
Y250107D01*
X482554D01*
G37*
G36*
G01X480930Y230987D02*
X480260Y231337D01*
Y232207D01*
X480930Y232557D01*
X481105D01*
Y230987D01*
X480930D01*
G37*
G36*
G01Y223236D02*
X480260Y223586D01*
Y224456D01*
X480930Y224806D01*
X481105D01*
Y223236D01*
X480930D01*
G37*
G36*
G01Y219336D02*
X480260Y219686D01*
Y220556D01*
X480930Y220906D01*
X481105D01*
Y219336D01*
X480930D01*
G37*
G36*
G01Y227136D02*
X480260Y227486D01*
Y228356D01*
X480930Y228706D01*
X481105D01*
Y227136D01*
X480930D01*
G37*
G36*
G01Y250536D02*
X480260Y250886D01*
Y251756D01*
X480930Y252106D01*
X481105D01*
Y250536D01*
X480930D01*
G37*
G36*
G01Y246636D02*
X480260Y246986D01*
Y247856D01*
X480930Y248206D01*
X481105D01*
Y246636D01*
X480930D01*
G37*
G36*
G01Y242736D02*
X480260Y243086D01*
Y243956D01*
X480930Y244306D01*
X481105D01*
Y242736D01*
X480930D01*
G37*
G36*
G01Y238836D02*
X480260Y239186D01*
Y240056D01*
X480930Y240406D01*
X481105D01*
Y238836D01*
X480930D01*
G37*
G36*
G01Y234911D02*
X480260Y235261D01*
Y236131D01*
X480930Y236481D01*
X481105D01*
Y234911D01*
X480930D01*
G37*
G36*
G01X503400Y298800D02*
X502800Y299400D01*
Y301610D01*
X502807Y301635D01*
G03Y302357I-1355J361D01*
G01X502800Y302382D01*
Y305510D01*
X502807Y305535D01*
G03Y306257I-1355J361D01*
G01X502800Y306282D01*
Y309411D01*
X502807Y309436D01*
G03Y310158I-1355J361D01*
G01X502800Y310183D01*
Y312800D01*
X503400Y313400D01*
X506400D01*
X507000Y312800D01*
Y310504D01*
X506976Y310459D01*
G03Y309135I1236J-662D01*
G01X507000Y309090D01*
Y308900D01*
X507400Y308500D01*
X507678D01*
X507713Y308487D01*
G03X508711I499J1310D01*
G01X508746Y308500D01*
X509808D01*
G02X510204Y308044I0J-400D01*
G03X512070Y309165I1388J-197D01*
G02X511924Y309824I137J376D01*
G01X513800Y311700D01*
Y315700D01*
X514407Y316307D01*
X514524Y316267D01*
G03X516301Y318044I448J1329D01*
G01X516261Y318161D01*
X516727Y318627D01*
G02X517308Y318611I283J-283D01*
G03X519740Y319353I1044J936D01*
G01X519765Y319525D01*
X522963D01*
X523041Y319603D01*
G02X523720Y319370I282J-283D01*
G03X525288Y320938I1391J177D01*
G02X525055Y321617I50J397D01*
G01X525553Y322115D01*
X525594Y322130D01*
G03X526427Y322963I-483J1316D01*
G01X526442Y323004D01*
X526631Y323193D01*
X527240D01*
G02X527518Y322505I0J-400D01*
G03X529464I973J-1009D01*
G02X529742Y323193I278J288D01*
G01X530484D01*
X530526Y323050D01*
G03X533216I1345J396D01*
G01X533258Y323193D01*
X534000D01*
G02X534278Y322505I0J-400D01*
G03X535913Y322732I973J-1009D01*
G02X535819Y323367I189J352D01*
G01X538411Y325959D01*
X538504Y325951D01*
G03X539831Y326622I127J1396D01*
G01X540410D01*
G02X540765Y326039I-1J-400D01*
G03X543257I1246J-643D01*
G02X543612Y326622I356J183D01*
G01X544191D01*
G03X546591I1200J725D01*
G01X547170D01*
G02X547525Y326039I-1J-400D01*
G03X549817Y326329I1246J-643D01*
G02X549833Y326879I298J267D01*
G01X550125Y327171D01*
G02X550795Y326990I283J-282D01*
G03X551339Y328490I1356J357D01*
G02X550708Y328816I-231J326D01*
G01Y329778D01*
G02X551339Y330104I400J0D01*
G03X552911Y332425I812J1143D01*
G02X552844Y333044I216J337D01*
G01X553455Y333655D01*
G02X554136Y333333I283J-283D01*
G03X555394Y334591I1395J-137D01*
G02X555072Y335272I-39J398D01*
G01X555492Y335692D01*
X555572Y335695D01*
G03X556932Y337055I-41J1401D01*
G01X556935Y337135D01*
X557880Y338080D01*
X558020Y337965D01*
G03X559993Y339938I891J1082D01*
G01X559878Y340078D01*
X560300Y340500D01*
Y342756D01*
X560302Y342769D01*
G03Y343125I-1391J178D01*
G01X560300Y343138D01*
Y348900D01*
X562696Y351296D01*
X562764Y351305D01*
G03X563860Y352100I-173J1391D01*
G01X571900D01*
X578200Y358400D01*
Y389700D01*
X615200Y426700D01*
X629400D01*
X632400Y423700D01*
Y375100D01*
X556586Y299286D01*
X556457Y299350D01*
G03X554619Y298800I-626J-1254D01*
G01X553741D01*
G02X553388Y299388I0J400D01*
G03X550914I-1237J659D01*
G02X550561Y298800I-353J-188D01*
G01X549983D01*
G03X547559I-1212J-704D01*
G01X546981D01*
G02X546628Y299388I0J400D01*
G03X544154I-1237J659D01*
G02X543801Y298800I-353J-188D01*
G01X543223D01*
G03X540799I-1212J-704D01*
G01X540221D01*
G02X539868Y299388I0J400D01*
G03X537394I-1237J659D01*
G02X537041Y298800I-353J-188D01*
G01X536463D01*
G03X534039I-1212J-704D01*
G01X533461D01*
G02X533108Y299388I0J400D01*
G03X530634I-1237J659D01*
G02X530281Y298800I-353J-188D01*
G01X529703D01*
G03X527279I-1212J-704D01*
G01X526701D01*
G02X526348Y299388I0J400D01*
G03X523874I-1237J659D01*
G02X523521Y298800I-353J-188D01*
G01X522943D01*
G03X520519I-1212J-704D01*
G01X519942D01*
G02X519589Y299388I0J400D01*
G03X517115I-1237J659D01*
G02X516762Y298800I-353J-188D01*
G01X516184D01*
G03X513760I-1212J-704D01*
G01X513182D01*
G02X512829Y299388I0J400D01*
G03X510355I-1237J659D01*
G02X510002Y298800I-353J-188D01*
G01X509424D01*
G03X507000I-1212J-704D01*
G01X503400D01*
G37*
G36*
G01X482050Y385063D02*
X481380Y385413D01*
Y386283D01*
X482050Y386633D01*
X482225D01*
Y385063D01*
X482050D01*
G37*
G36*
G01X479205Y381748D02*
X479173Y382503D01*
X479926Y382938D01*
X480564Y382533D01*
X480652Y382381D01*
X479292Y381597D01*
X479205Y381748D01*
G37*
G36*
G01X482050Y388937D02*
X481380Y389287D01*
Y390157D01*
X482050Y390507D01*
X482225D01*
Y388937D01*
X482050D01*
G37*
G36*
G01Y400637D02*
X481380Y400987D01*
Y401857D01*
X482050Y402207D01*
X482225D01*
Y400637D01*
X482050D01*
G37*
G36*
G01Y396737D02*
X481380Y397087D01*
Y397957D01*
X482050Y398307D01*
X482225D01*
Y396737D01*
X482050D01*
G37*
G36*
G01Y392837D02*
X481380Y393187D01*
Y394057D01*
X482050Y394407D01*
X482225D01*
Y392837D01*
X482050D01*
G37*
G36*
G01X483132Y382139D02*
X483164Y381384D01*
X482411Y380950D01*
X481773Y381355D01*
X481686Y381506D01*
X483046Y382291D01*
X483132Y382139D01*
G37*
G36*
G01X479759Y380195D02*
X479791Y379440D01*
X479038Y379005D01*
X478400Y379410D01*
X478312Y379561D01*
X479672Y380347D01*
X479759Y380195D01*
G37*
G36*
G01X483673Y384682D02*
X484343Y384332D01*
Y383462D01*
X483673Y383112D01*
X483498D01*
Y384682D01*
X483673D01*
G37*
G36*
G01Y388582D02*
X484343Y388232D01*
Y387362D01*
X483673Y387012D01*
X483498D01*
Y388582D01*
X483673D01*
G37*
G36*
G01X483674Y392506D02*
X484344Y392156D01*
Y391286D01*
X483674Y390936D01*
X483499D01*
Y392506D01*
X483674D01*
G37*
G36*
G01Y404206D02*
X484344Y403856D01*
Y402986D01*
X483674Y402636D01*
X483499D01*
Y404206D01*
X483674D01*
G37*
G36*
G01Y396406D02*
X484344Y396056D01*
Y395186D01*
X483674Y394836D01*
X483499D01*
Y396406D01*
X483674D01*
G37*
G36*
G01Y400306D02*
X484344Y399956D01*
Y399086D01*
X483674Y398736D01*
X483499D01*
Y400306D01*
X483674D01*
G37*
G36*
G01X479205Y366148D02*
X479173Y366903D01*
X479926Y367338D01*
X480564Y366933D01*
X480652Y366781D01*
X479292Y365997D01*
X479205Y366148D01*
G37*
G36*
G01X482591Y368102D02*
X482559Y368857D01*
X483312Y369292D01*
X483950Y368887D01*
X484038Y368735D01*
X482678Y367951D01*
X482591Y368102D01*
G37*
G36*
G01X485980Y370057D02*
X485948Y370812D01*
X486701Y371247D01*
X487339Y370842D01*
X487427Y370691D01*
X486067Y369905D01*
X485980Y370057D01*
G37*
G36*
G01X492731Y373952D02*
X492699Y374707D01*
X493452Y375142D01*
X494090Y374737D01*
X494178Y374585D01*
X492818Y373801D01*
X492731Y373952D01*
G37*
G36*
G01X495570Y377237D02*
X494900Y377587D01*
Y378457D01*
X495570Y378807D01*
X495745D01*
Y377237D01*
X495570D01*
G37*
G36*
G01Y381164D02*
X494900Y381514D01*
Y382384D01*
X495570Y382734D01*
X495745D01*
Y381164D01*
X495570D01*
G37*
G36*
G01Y385064D02*
X494900Y385414D01*
Y386284D01*
X495570Y386634D01*
X495745D01*
Y385064D01*
X495570D01*
G37*
G36*
G01X489345Y371999D02*
X489313Y372754D01*
X490066Y373189D01*
X490704Y372784D01*
X490792Y372633D01*
X489432Y371847D01*
X489345Y371999D01*
G37*
G36*
G01X495571Y388982D02*
X494901Y389332D01*
Y390202D01*
X495571Y390552D01*
X495746D01*
Y388982D01*
X495571D01*
G37*
G36*
G01X499506Y401262D02*
X499474Y402017D01*
X500228Y402451D01*
X500865Y402046D01*
X500953Y401895D01*
X499594Y401109D01*
X499506Y401262D01*
G37*
G36*
G01X495570Y396762D02*
X494900Y397112D01*
Y397982D01*
X495570Y398332D01*
X495745D01*
Y396762D01*
X495570D01*
G37*
G36*
G01X496126Y399312D02*
X496094Y400067D01*
X496848Y400501D01*
X497485Y400096D01*
X497573Y399945D01*
X496214Y399159D01*
X496126Y399312D01*
G37*
G36*
G01X495570Y392862D02*
X494900Y393212D01*
Y394082D01*
X495570Y394432D01*
X495745D01*
Y392862D01*
X495570D01*
G37*
G36*
G01X479759Y364595D02*
X479791Y363840D01*
X479038Y363405D01*
X478400Y363810D01*
X478312Y363961D01*
X479672Y364747D01*
X479759Y364595D01*
G37*
G36*
G01X486519Y368495D02*
X486551Y367740D01*
X485798Y367305D01*
X485160Y367710D01*
X485072Y367861D01*
X486432Y368647D01*
X486519Y368495D01*
G37*
G36*
G01X483133Y366541D02*
X483165Y365786D01*
X482412Y365351D01*
X481774Y365756D01*
X481686Y365907D01*
X483046Y366693D01*
X483133Y366541D01*
G37*
G36*
G01X489884Y370436D02*
X489916Y369681D01*
X489163Y369246D01*
X488525Y369651D01*
X488437Y369803D01*
X489797Y370587D01*
X489884Y370436D01*
G37*
G36*
G01X497194Y376907D02*
X497864Y376557D01*
Y375687D01*
X497194Y375337D01*
X497019D01*
Y376907D01*
X497194D01*
G37*
G36*
G01X496659Y374344D02*
X496691Y373589D01*
X495938Y373154D01*
X495300Y373559D01*
X495213Y373710D01*
X496573Y374495D01*
X496659Y374344D01*
G37*
G36*
G01X497194Y384684D02*
X497864Y384334D01*
Y383464D01*
X497194Y383114D01*
X497019D01*
Y384684D01*
X497194D01*
G37*
G36*
G01Y380807D02*
X497864Y380457D01*
Y379587D01*
X497194Y379237D01*
X497019D01*
Y380807D01*
X497194D01*
G37*
G36*
G01X493273Y372391D02*
X493305Y371636D01*
X492552Y371201D01*
X491914Y371606D01*
X491826Y371757D01*
X493186Y372543D01*
X493273Y372391D01*
G37*
G36*
G01X497194Y388584D02*
X497864Y388234D01*
Y387364D01*
X497194Y387014D01*
X497019D01*
Y388584D01*
X497194D01*
G37*
G36*
G01Y392506D02*
X497864Y392156D01*
Y391286D01*
X497194Y390936D01*
X497019D01*
Y392506D01*
X497194D01*
G37*
G36*
G01X500033Y399691D02*
X500065Y398936D01*
X499312Y398501D01*
X498674Y398906D01*
X498586Y399057D01*
X499946Y399843D01*
X500033Y399691D01*
G37*
G36*
G01X497194Y396357D02*
X497864Y396007D01*
Y395137D01*
X497194Y394787D01*
X497019D01*
Y396357D01*
X497194D01*
G37*
G36*
G01X503288Y403898D02*
X504048Y403549D01*
Y402649D01*
X503288Y402299D01*
X503113D01*
Y403898D01*
X503288D01*
G37*
G36*
G01X478670Y387014D02*
X478000Y387364D01*
Y388234D01*
X478670Y388584D01*
X478845D01*
Y387014D01*
X478670D01*
G37*
G36*
G01Y390936D02*
X478000Y391286D01*
Y392156D01*
X478670Y392506D01*
X478845D01*
Y390936D01*
X478670D01*
G37*
G36*
G01Y402636D02*
X478000Y402986D01*
Y403856D01*
X478670Y404206D01*
X478845D01*
Y402636D01*
X478670D01*
G37*
G36*
G01Y394836D02*
X478000Y395186D01*
Y396056D01*
X478670Y396406D01*
X478845D01*
Y394836D01*
X478670D01*
G37*
G36*
G01Y398736D02*
X478000Y399086D01*
Y399956D01*
X478670Y400306D01*
X478845D01*
Y398736D01*
X478670D01*
G37*
G36*
G01X480294Y386634D02*
X480964Y386284D01*
Y385414D01*
X480294Y385064D01*
X480119D01*
Y386634D01*
X480294D01*
G37*
G36*
G01X479759Y384096D02*
X479791Y383341D01*
X479038Y382906D01*
X478400Y383311D01*
X478312Y383462D01*
X479672Y384247D01*
X479759Y384096D01*
G37*
G36*
G01X480293Y390536D02*
X480963Y390186D01*
Y389316D01*
X480293Y388966D01*
X480118D01*
Y390536D01*
X480293D01*
G37*
G36*
G01X480294Y402207D02*
X480964Y401857D01*
Y400987D01*
X480294Y400637D01*
X480119D01*
Y402207D01*
X480294D01*
G37*
G36*
G01Y398307D02*
X480964Y397957D01*
Y397087D01*
X480294Y396737D01*
X480119D01*
Y398307D01*
X480294D01*
G37*
G36*
G01Y394407D02*
X480964Y394057D01*
Y393187D01*
X480294Y392837D01*
X480119D01*
Y394407D01*
X480294D01*
G37*
G36*
G01X479220Y370057D02*
X479188Y370812D01*
X479941Y371247D01*
X480579Y370842D01*
X480667Y370691D01*
X479307Y369905D01*
X479220Y370057D01*
G37*
G36*
G01X482585Y371999D02*
X482553Y372754D01*
X483306Y373189D01*
X483944Y372784D01*
X484032Y372633D01*
X482672Y371847D01*
X482585Y371999D01*
G37*
G36*
G01X485971Y373952D02*
X485939Y374707D01*
X486692Y375142D01*
X487330Y374737D01*
X487418Y374585D01*
X486058Y373801D01*
X485971Y373952D01*
G37*
G36*
G01X489351Y375903D02*
X489319Y376658D01*
X490072Y377093D01*
X490710Y376688D01*
X490798Y376537D01*
X489438Y375751D01*
X489351Y375903D01*
G37*
G36*
G01X492190Y379188D02*
X491520Y379538D01*
Y380408D01*
X492190Y380758D01*
X492365D01*
Y379188D01*
X492190D01*
G37*
G36*
G01Y383114D02*
X491520Y383464D01*
Y384334D01*
X492190Y384684D01*
X492365D01*
Y383114D01*
X492190D01*
G37*
G36*
G01Y387036D02*
X491520Y387386D01*
Y388256D01*
X492190Y388606D01*
X492365D01*
Y387036D01*
X492190D01*
G37*
G36*
G01Y390936D02*
X491520Y391286D01*
Y392156D01*
X492190Y392506D01*
X492365D01*
Y390936D01*
X492190D01*
G37*
G36*
G01X492725Y401248D02*
X492693Y402003D01*
X493446Y402438D01*
X494084Y402033D01*
X494171Y401882D01*
X492812Y401096D01*
X492725Y401248D01*
G37*
G36*
G01X492190Y398687D02*
X491520Y399037D01*
Y399907D01*
X492190Y400257D01*
X492365D01*
Y398687D01*
X492190D01*
G37*
G36*
G01Y394787D02*
X491520Y395137D01*
Y396007D01*
X492190Y396357D01*
X492365D01*
Y394787D01*
X492190D01*
G37*
G36*
G01X486513Y372391D02*
X486545Y371636D01*
X485792Y371201D01*
X485154Y371606D01*
X485066Y371757D01*
X486426Y372543D01*
X486513Y372391D01*
G37*
G36*
G01X483124Y370436D02*
X483156Y369681D01*
X482403Y369246D01*
X481765Y369651D01*
X481677Y369803D01*
X483037Y370587D01*
X483124Y370436D01*
G37*
G36*
G01X479759Y368495D02*
X479791Y367740D01*
X479038Y367305D01*
X478400Y367710D01*
X478312Y367861D01*
X479672Y368647D01*
X479759Y368495D01*
G37*
G36*
G01X489899Y374344D02*
X489931Y373589D01*
X489178Y373154D01*
X488540Y373559D01*
X488452Y373711D01*
X489812Y374495D01*
X489899Y374344D01*
G37*
G36*
G01X493814Y378858D02*
X494484Y378508D01*
Y377638D01*
X493814Y377288D01*
X493639D01*
Y378858D01*
X493814D01*
G37*
G36*
G01X493279Y376295D02*
X493311Y375540D01*
X492558Y375105D01*
X491920Y375510D01*
X491833Y375661D01*
X493192Y376447D01*
X493279Y376295D01*
G37*
G36*
G01X493813Y386632D02*
X494483Y386282D01*
Y385412D01*
X493813Y385062D01*
X493638D01*
Y386632D01*
X493813D01*
G37*
G36*
G01X493814Y382758D02*
X494484Y382408D01*
Y381538D01*
X493814Y381188D01*
X493639D01*
Y382758D01*
X493814D01*
G37*
G36*
G01Y390507D02*
X494484Y390157D01*
Y389287D01*
X493814Y388937D01*
X493639D01*
Y390507D01*
X493814D01*
G37*
G36*
G01X499579Y404011D02*
X499806Y403291D01*
X499192Y402675D01*
X498471Y402900D01*
X498346Y403024D01*
X499455Y404135D01*
X499579Y404011D01*
G37*
G36*
G01X496659Y401644D02*
X496691Y400889D01*
X495938Y400454D01*
X495300Y400859D01*
X495212Y401011D01*
X496572Y401795D01*
X496659Y401644D01*
G37*
G36*
G01X493814Y398356D02*
X494484Y398006D01*
Y397136D01*
X493814Y396786D01*
X493639D01*
Y398356D01*
X493814D01*
G37*
G36*
G01Y394432D02*
X494484Y394082D01*
Y393212D01*
X493814Y392862D01*
X493639D01*
Y394432D01*
X493814D01*
G37*
G36*
G01X483133Y378241D02*
X483165Y377486D01*
X482412Y377051D01*
X481774Y377456D01*
X481686Y377607D01*
X483046Y378393D01*
X483133Y378241D01*
G37*
G36*
G01X479744Y376286D02*
X479776Y375531D01*
X479023Y375096D01*
X478385Y375501D01*
X478297Y375653D01*
X479657Y376437D01*
X479744Y376286D01*
G37*
G36*
G01X486498Y380181D02*
X486530Y379426D01*
X485776Y378992D01*
X485139Y379397D01*
X485050Y379548D01*
X486410Y380334D01*
X486498Y380181D01*
G37*
G36*
G01X487054Y386607D02*
X487724Y386257D01*
Y385387D01*
X487054Y385037D01*
X486879D01*
Y386607D01*
X487054D01*
G37*
G36*
G01Y382749D02*
X487724Y382399D01*
X487723Y381530D01*
X487054Y381180D01*
X486878Y381179D01*
Y382750D01*
X487054Y382749D01*
G37*
G36*
G01Y390507D02*
X487724Y390157D01*
Y389287D01*
X487054Y388937D01*
X486879D01*
Y390507D01*
X487054D01*
G37*
G36*
G01Y402207D02*
X487724Y401857D01*
Y400987D01*
X487054Y400637D01*
X486879D01*
Y402207D01*
X487054D01*
G37*
G36*
G01Y398307D02*
X487724Y397957D01*
Y397087D01*
X487054Y396737D01*
X486879D01*
Y398307D01*
X487054D01*
G37*
G36*
G01Y394432D02*
X487724Y394082D01*
Y393212D01*
X487054Y392862D01*
X486879D01*
Y394432D01*
X487054D01*
G37*
G36*
G01X479211Y373952D02*
X479179Y374707D01*
X479932Y375142D01*
X480570Y374737D01*
X480658Y374585D01*
X479298Y373801D01*
X479211Y373952D01*
G37*
G36*
G01X482600Y375907D02*
X482568Y376662D01*
X483321Y377097D01*
X483959Y376692D01*
X484047Y376541D01*
X482687Y375755D01*
X482600Y375907D01*
G37*
G36*
G01X485965Y377848D02*
X485933Y378603D01*
X486686Y379038D01*
X487324Y378633D01*
X487412Y378481D01*
X486052Y377697D01*
X485965Y377848D01*
G37*
G36*
G01X488810Y385064D02*
X488140Y385414D01*
Y386284D01*
X488810Y386634D01*
X488985D01*
Y385064D01*
X488810D01*
G37*
G36*
G01Y381137D02*
X488140Y381487D01*
Y382357D01*
X488810Y382707D01*
X488985D01*
Y381137D01*
X488810D01*
G37*
G36*
G01Y388937D02*
X488140Y389287D01*
Y390157D01*
X488810Y390507D01*
X488985D01*
Y388937D01*
X488810D01*
G37*
G36*
G01Y400686D02*
X488140Y401036D01*
Y401906D01*
X488810Y402256D01*
X488985D01*
Y400686D01*
X488810D01*
G37*
G36*
G01Y396786D02*
X488140Y397136D01*
Y398006D01*
X488810Y398356D01*
X488985D01*
Y396786D01*
X488810D01*
G37*
G36*
G01Y392862D02*
X488140Y393212D01*
Y394082D01*
X488810Y394432D01*
X488985D01*
Y392862D01*
X488810D01*
G37*
G36*
G01X479205Y377848D02*
X479173Y378603D01*
X479926Y379038D01*
X480564Y378633D01*
X480652Y378481D01*
X479292Y377697D01*
X479205Y377848D01*
G37*
G36*
G01X485430Y383136D02*
X484760Y383486D01*
Y384356D01*
X485430Y384706D01*
X485605D01*
Y383136D01*
X485430D01*
G37*
G36*
G01X482591Y379802D02*
X482559Y380557D01*
X483312Y380992D01*
X483950Y380587D01*
X484038Y380435D01*
X482678Y379651D01*
X482591Y379802D01*
G37*
G36*
G01X485430Y387036D02*
X484760Y387386D01*
Y388256D01*
X485430Y388606D01*
X485605D01*
Y387036D01*
X485430D01*
G37*
G36*
G01Y390936D02*
X484760Y391286D01*
Y392156D01*
X485430Y392506D01*
X485605D01*
Y390936D01*
X485430D01*
G37*
G36*
G01Y402636D02*
X484760Y402986D01*
Y403856D01*
X485430Y404206D01*
X485605D01*
Y402636D01*
X485430D01*
G37*
G36*
G01Y394812D02*
X484760Y395162D01*
Y396032D01*
X485430Y396382D01*
X485605D01*
Y394812D01*
X485430D01*
G37*
G36*
G01Y398736D02*
X484760Y399086D01*
Y399956D01*
X485430Y400306D01*
X485605D01*
Y398736D01*
X485430D01*
G37*
G36*
G01X486504Y376286D02*
X486536Y375531D01*
X485783Y375096D01*
X485145Y375501D01*
X485057Y375653D01*
X486417Y376437D01*
X486504Y376286D01*
G37*
G36*
G01X483139Y374344D02*
X483171Y373589D01*
X482418Y373154D01*
X481780Y373559D01*
X481692Y373711D01*
X483052Y374495D01*
X483139Y374344D01*
G37*
G36*
G01X479753Y372391D02*
X479785Y371636D01*
X479032Y371201D01*
X478394Y371606D01*
X478306Y371757D01*
X479666Y372543D01*
X479753Y372391D01*
G37*
G36*
G01X489892Y378239D02*
X489924Y377484D01*
X489171Y377050D01*
X488533Y377455D01*
X488445Y377606D01*
X489805Y378392D01*
X489892Y378239D01*
G37*
G36*
G01X490433Y380783D02*
X491103Y380433D01*
Y379563D01*
X490433Y379213D01*
X490258D01*
Y380783D01*
X490433D01*
G37*
G36*
G01Y384683D02*
X491103Y384333D01*
Y383463D01*
X490433Y383113D01*
X490258D01*
Y384683D01*
X490433D01*
G37*
G36*
G01Y388582D02*
X491103Y388232D01*
Y387362D01*
X490433Y387012D01*
X490258D01*
Y388582D01*
X490433D01*
G37*
G36*
G01X490434Y392506D02*
X491104Y392156D01*
Y391286D01*
X490434Y390936D01*
X490259D01*
Y392506D01*
X490434D01*
G37*
G36*
G01X493279Y403595D02*
X493311Y402840D01*
X492558Y402405D01*
X491920Y402810D01*
X491832Y402961D01*
X493192Y403747D01*
X493279Y403595D01*
G37*
G36*
G01X490434Y400281D02*
X491104Y399931D01*
Y399061D01*
X490434Y398711D01*
X490259D01*
Y400281D01*
X490434D01*
G37*
G36*
G01Y396357D02*
X491104Y396007D01*
Y395137D01*
X490434Y394787D01*
X490259D01*
Y396357D01*
X490434D01*
G37*
G36*
G01X485531Y408376D02*
X485307Y409098D01*
X485924Y409710D01*
X486644Y409482D01*
X486768Y409358D01*
X485654Y408251D01*
X485531Y408376D01*
G37*
G36*
G01X482050Y404537D02*
X481380Y404887D01*
Y405757D01*
X482050Y406107D01*
X482225D01*
Y404537D01*
X482050D01*
G37*
G36*
G01X482592Y407104D02*
X482560Y407859D01*
X483313Y408293D01*
X483951Y407888D01*
X484039Y407737D01*
X482679Y406951D01*
X482592Y407104D01*
G37*
G36*
G01X486498Y407481D02*
X486530Y406726D01*
X485776Y406292D01*
X485139Y406697D01*
X485050Y406848D01*
X486410Y407634D01*
X486498Y407481D01*
G37*
G36*
G01X487989Y412683D02*
X488749Y412333D01*
Y411433D01*
X487989Y411083D01*
X487814D01*
Y412683D01*
X487989D01*
G37*
G36*
G01X502188Y402799D02*
X501428Y403149D01*
Y404048D01*
X502188Y404398D01*
X502363D01*
Y402799D01*
X502188D01*
G37*
G36*
G01X478670Y406536D02*
X478000Y406886D01*
Y407756D01*
X478670Y408106D01*
X478845D01*
Y406536D01*
X478670D01*
G37*
G36*
G01X479226Y409062D02*
X479194Y409817D01*
X479948Y410251D01*
X480585Y409846D01*
X480673Y409695D01*
X479314Y408909D01*
X479226Y409062D01*
G37*
G36*
G01X483132Y409439D02*
X483164Y408684D01*
X482411Y408250D01*
X481773Y408655D01*
X481686Y408806D01*
X483046Y409591D01*
X483132Y409439D01*
G37*
G36*
G01X480294Y406107D02*
X480964Y405757D01*
Y404887D01*
X480294Y404537D01*
X480119D01*
Y406107D01*
X480294D01*
G37*
G36*
G01X483674Y412006D02*
X484344Y411656D01*
Y410786D01*
X483674Y410436D01*
X483499D01*
Y412006D01*
X483674D01*
G37*
G36*
G01X498556Y405715D02*
X497796Y406065D01*
Y406965D01*
X498556Y407315D01*
X498731D01*
Y405715D01*
X498556D01*
G37*
G36*
G01X496105Y403198D02*
X496073Y403953D01*
X496826Y404388D01*
X497464Y403983D01*
X497551Y403832D01*
X496192Y403046D01*
X496105Y403198D01*
G37*
G36*
G01X499656Y407315D02*
X500416Y406965D01*
Y406065D01*
X499656Y405715D01*
X499481D01*
Y407315D01*
X499656D01*
G37*
G36*
G01X489893Y405541D02*
X489925Y404786D01*
X489172Y404351D01*
X488534Y404756D01*
X488446Y404907D01*
X489806Y405693D01*
X489893Y405541D01*
G37*
G36*
G01X492725Y405148D02*
X492693Y405903D01*
X493446Y406338D01*
X494084Y405933D01*
X494172Y405782D01*
X492812Y404996D01*
X492725Y405148D01*
G37*
G36*
G01X489352Y403204D02*
X489320Y403959D01*
X490073Y404393D01*
X490711Y403988D01*
X490798Y403837D01*
X489438Y403052D01*
X489352Y403204D01*
G37*
G36*
G01X494976Y406654D02*
X494216Y407004D01*
Y407904D01*
X494976Y408254D01*
X495151D01*
Y406654D01*
X494976D01*
G37*
G36*
G01X485965Y405148D02*
X485933Y405903D01*
X486686Y406338D01*
X487324Y405933D01*
X487412Y405782D01*
X486052Y404996D01*
X485965Y405148D01*
G37*
G36*
G01X496095Y407847D02*
X496764Y407496D01*
X496761Y406626D01*
X496091Y406278D01*
X495916D01*
X495919Y407849D01*
X496095Y407847D01*
G37*
G36*
G01X496074Y405729D02*
X496252Y404995D01*
X495597Y404422D01*
X494893Y404696D01*
X494777Y404827D01*
X495959Y405862D01*
X496074Y405729D01*
G37*
G36*
G01X718400Y320600D02*
X711500D01*
X709800Y322300D01*
Y327200D01*
X711100Y328500D01*
X717000D01*
X719200Y326300D01*
Y321400D01*
X718400Y320600D01*
G37*
G36*
G01X763700Y110800D02*
X767100D01*
X768500Y109400D01*
Y105800D01*
X767400Y104700D01*
Y101900D01*
X766900Y101400D01*
X762400D01*
X761500Y102300D01*
Y108600D01*
X763700Y110800D01*
G37*
G36*
G01X785400Y203600D02*
X784952Y204048D01*
Y363572D01*
X787090Y365710D01*
Y366180D01*
X794084D01*
X794466Y365798D01*
X817779D01*
X818216Y365362D01*
X818300D01*
Y209300D01*
X815900Y206900D01*
X812900D01*
X811180Y205180D01*
X802879D01*
X801299Y203600D01*
X785400D01*
G37*
G36*
G01X795710Y368802D02*
X795328Y369184D01*
X787090D01*
Y370740D01*
X786477Y371353D01*
G03X785488Y373899I-1077J1047D01*
G02X785112Y374299I24J399D01*
G01Y400889D01*
X786421Y402198D01*
X794672D01*
X805160Y391710D01*
X810266D01*
X814673Y387304D01*
X817566D01*
X818300Y386570D01*
Y368802D01*
X795710D01*
G37*
G36*
G01X821000Y211600D02*
X820608Y211992D01*
Y362622D01*
X822134Y364148D01*
X840961D01*
G02X841325Y363582I0J-400D01*
G03X843573Y361990I1275J-582D01*
G02X844127I277J-288D01*
G03X846073I973J1010D01*
G02X846627I277J-288D01*
G03X848875Y363582I973J1010D01*
G02X849239Y364148I364J166D01*
G01X850681D01*
X887488Y327341D01*
X888959D01*
X890874Y325426D01*
X910150D01*
X912065Y327341D01*
X912469D01*
G03X913787Y326559I1318J720D01*
G01X916337D01*
G03X917265Y326880I0J1502D01*
G01X917319Y326922D01*
X917754D01*
X919654Y325022D01*
X920954D01*
X923028Y322949D01*
X922965Y322821D01*
G03X924301Y320809I1262J-612D01*
G02X924722Y320410I21J-399D01*
G01Y319254D01*
X926612Y317364D01*
X926503Y317224D01*
G03X928817Y315651I1105J-863D01*
G02X929444Y315732I345J-202D01*
G01X929654Y315522D01*
X932446D01*
X932578Y315654D01*
G02X933195Y315591I283J-283D01*
G03X935528Y315575I1172J769D01*
G02X936143Y315634I332J-224D01*
G01X936554Y315222D01*
X937954D01*
X939754Y313422D01*
X942546D01*
X944146Y315022D01*
X944854D01*
X946354Y313522D01*
X949446D01*
X951346Y315422D01*
X952346D01*
X952755Y315831D01*
G02X953395Y315729I283J-282D01*
G03X956046Y316448I1252J631D01*
G02X956445Y316873I399J25D01*
G01X959608D01*
G02X960007Y316448I0J-400D01*
G03X962805I1399J-88D01*
G02X963204Y316873I399J25D01*
G01X966368D01*
G02X966767Y316448I0J-400D01*
G03X969565I1399J-88D01*
G02X969964Y316873I399J25D01*
G01X973128D01*
G02X973527Y316448I0J-400D01*
G03X976325I1399J-88D01*
G02X976724Y316873I399J25D01*
G01X979808D01*
X980217Y317282D01*
X980455Y317044D01*
X980400Y316919D01*
G03X981668Y317762I1286J-559D01*
G02X981380Y318445I-6J400D01*
G01X981796Y318861D01*
X981863Y318869D01*
G03X983077Y320083I-177J1391D01*
G01X983085Y320150D01*
X984107Y321172D01*
X984245Y321072D01*
G03X986096Y323161I821J1137D01*
G01X986558Y323623D01*
G02X987197Y323522I283J-283D01*
G03X989084Y325409I1249J638D01*
G02X988983Y326048I182J356D01*
G01X991563Y328628D01*
X991660Y328617D01*
G03X993218Y330175I166J1392D01*
G01X993207Y330272D01*
X993918Y330983D01*
G02X994202Y330981I141J-142D01*
G03X996252Y332894I1004J979D01*
G02X996259Y333169I149J134D01*
G01X996625Y333535D01*
G02X997281Y333398I283J-283D01*
G03X999008Y335246I1305J511D01*
G02X998845Y335910I120J381D01*
G01X1001404Y338469D01*
X1001521Y338430D01*
G03X1003295Y340204I444J1330D01*
G01X1003256Y340321D01*
X1003722Y340787D01*
G02X1004302Y340772I283J-283D01*
G03X1006282Y342752I1043J937D01*
G02X1006267Y343332I268J297D01*
G01X1006654Y343719D01*
G02X1007334Y343486I283J-283D01*
G03X1010020Y344198I1391J174D01*
G02X1010122Y344457I185J77D01*
G03X1010715Y344799I-1395J3104D01*
G02X1010991Y344758I117J-162D01*
G03X1013219I1114J851D01*
G02X1013495Y344799I159J-121D01*
G03X1014088Y344457I1988J2762D01*
G02X1014190Y344198I-83J-182D01*
G03X1016780I1295J-538D01*
G02X1016882Y344457I185J77D01*
G03X1017475Y344799I-1395J3104D01*
G02X1017751Y344758I117J-162D01*
G03X1020211Y345215I1114J851D01*
G01X1020253Y345359D01*
X1022888D01*
X1024424Y343823D01*
Y341476D01*
X1026384Y339516D01*
X1026377Y339424D01*
G03X1027990Y337811I1498J-115D01*
G01X1028082Y337818D01*
X1031500Y334400D01*
X1057000D01*
X1057085Y334485D01*
X1081077D01*
X1082190Y335598D01*
Y339319D01*
X1082671Y339800D01*
X1087261D01*
X1100862Y326199D01*
G02X1100704Y325536I-283J-283D01*
G03X1100082Y325161I495J-1524D01*
G02X1099523I-279J286D01*
G03X1097162Y325031I-1121J-1144D01*
G02X1096562Y325008I-310J253D01*
G03X1096642Y322890I-1160J-1104D01*
G02X1097242Y322913I310J-253D01*
G03X1099520Y322869I1161J1104D01*
G02X1100079I280J-286D01*
G03X1102723Y323517I1121J1144D01*
G02X1103386Y323676I380J-124D01*
G01X1105316Y321746D01*
Y311720D01*
G02X1104659Y311414I-400J0D01*
G03X1102359Y310464I-903J-1073D01*
G02X1101805Y310131I-398J35D01*
G03X1100630Y310095I-549J-1290D01*
G02X1100075Y310317I-179J358D01*
G03X1097583Y310609I-1319J-476D01*
G02X1096905Y310623I-335J219D01*
G03X1094539Y310687I-1203J-719D01*
G02X1093885Y310673I-332J223D01*
G03X1091583Y310609I-1129J-832D01*
G02X1090905Y310623I-335J219D01*
G03X1090875Y309136I-1203J-720D01*
G02X1091553Y309122I335J-219D01*
G03X1093919Y309058I1203J719D01*
G02X1094573Y309072I332J-223D01*
G03X1096875Y309136I1129J832D01*
G02X1097553Y309122I335J-219D01*
G03X1099382Y308587I1203J719D01*
G02X1099937Y308365I179J-358D01*
G03X1101882Y307587I1319J476D01*
G02X1102437Y307365I179J-358D01*
G03X1104659Y306768I1319J476D01*
G02X1105316Y306462I257J-306D01*
G01Y297573D01*
G02X1104777Y297198I-400J0D01*
G03X1103233Y296957I-556J-1502D01*
G02X1102702Y296989I-248J314D01*
G03X1100360Y296913I-1136J-1130D01*
G02X1099761Y296909I-301J263D01*
G03X1097367Y296902I-1194J-1068D01*
G02X1096767I-300J265D01*
G03X1094373Y296909I-1200J-1061D01*
G02X1093774Y296913I-298J267D01*
G03X1091367Y296920I-1207J-1054D01*
G02X1090767I-300J265D01*
G03X1088672Y294530I-1200J-1061D01*
G02X1088727Y293911I-223J-332D01*
G03X1090869Y292127I975J-1007D01*
G02X1091535I333J-222D01*
G03X1093775Y292002I1167J777D01*
G02X1094416Y291963I306J-258D01*
G03X1096956Y291780I1340J878D01*
G02X1097556I300J-265D01*
G03X1099748Y291583I1200J1061D01*
G02X1100320Y291505I249J-314D01*
G03X1102408Y291055I1296J942D01*
G02X1102936Y290934I198J-348D01*
G03X1104784Y290329I1320J907D01*
G02X1105316Y289951I132J-378D01*
G01Y265999D01*
X1088019Y254781D01*
X1086919D01*
X1086300Y255400D01*
Y259650D01*
X1085700Y260250D01*
Y261300D01*
X1085676Y261324D01*
Y261798D01*
X1085529Y261945D01*
Y266905D01*
X1084331Y268103D01*
X1084113D01*
X1083730Y268486D01*
X1077159D01*
X1076776Y268103D01*
X1068613D01*
X1067960Y267450D01*
X1038930D01*
X1023453Y251973D01*
X1021101D01*
X1020177Y252507D01*
X1020151Y252567D01*
G03X1018707Y253402I-1286J-558D01*
G01X1018642Y253395D01*
X1016796Y254462D01*
X1016770Y254522D01*
G03X1015331Y255353I-1284J-562D01*
G01X1015266Y255346D01*
X1014209Y255957D01*
X1013388Y256478D01*
X1013363Y256529D01*
G03X1012130Y257311I-1258J-620D01*
G01X1012073Y257312D01*
X1009811Y258747D01*
X1009792Y258770D01*
G03X1009094Y259213I-1067J-910D01*
G01X1009065Y259221D01*
X995821Y267622D01*
G02X995851Y268315I214J338D01*
G03X993805Y269613I-645J1245D01*
G02X993191Y269291I-400J16D01*
G01X992601Y269665D01*
G02X992596Y270337I214J338D01*
G03X990438Y271706I-770J1172D01*
G02X989828Y271424I-396J56D01*
G01X989363Y271719D01*
G02X989326Y272369I214J338D01*
G03X987116Y273903I-880J1091D01*
G02X986454Y273746I-380J126D01*
G01X985920Y274280D01*
X986061Y274421D01*
G03X983706Y275751I-995J988D01*
G01X983668Y275600D01*
X982868D01*
G02X982606Y276302I0J400D01*
G03X980766I-920J1058D01*
G02X980504Y275600I-262J-302D01*
G01X979704D01*
X979666Y275751D01*
G03X976946I-1360J-342D01*
G01X976908Y275600D01*
X976108D01*
G02X975846Y276302I0J400D01*
G03X974006I-920J1058D01*
G02X973744Y275600I-262J-302D01*
G01X972944D01*
X972906Y275751D01*
G03X970186I-1360J-342D01*
G01X970148Y275600D01*
X969348D01*
G02X969086Y276302I0J400D01*
G03X967246I-920J1058D01*
G02X966984Y275600I-262J-302D01*
G01X966184D01*
X966146Y275751D01*
G03X963426I-1360J-342D01*
G01X963388Y275600D01*
X962588D01*
G02X962326Y276302I0J400D01*
G03X960486I-920J1058D01*
G02X960224Y275600I-262J-302D01*
G01X959424D01*
X959386Y275751D01*
G03X956666I-1360J-342D01*
G01X956628Y275600D01*
X955829D01*
G02X955567Y276302I0J400D01*
G03X953727I-920J1058D01*
G02X953465Y275600I-262J-302D01*
G01X952665D01*
X952627Y275751D01*
G03X949907I-1360J-342D01*
G01X949869Y275600D01*
X949069D01*
G02X948807Y276302I0J400D01*
G03X946967I-920J1058D01*
G02X946705Y275600I-262J-302D01*
G01X945905D01*
X945867Y275751D01*
G03X943147I-1360J-342D01*
G01X943109Y275600D01*
X942309D01*
G02X942047Y276302I0J400D01*
G03X940207I-920J1058D01*
G02X939945Y275600I-262J-302D01*
G01X939145D01*
X939107Y275751D01*
G03X936387I-1360J-342D01*
G01X936349Y275600D01*
X935549D01*
G02X935287Y276302I0J400D01*
G03X933447I-920J1058D01*
G02X933185Y275600I-262J-302D01*
G01X932385D01*
X932347Y275751D01*
G03X929590Y275290I-1360J-341D01*
G01X929598Y275198D01*
X928727Y274327D01*
X928585Y274464D01*
G03X926375Y272791I-978J-1005D01*
G02X926024Y272200I-351J-191D01*
G01X925447D01*
G03X923007I-1220J-691D01*
G01X922430D01*
G02X922079Y272791I0J400D01*
G03X919615I-1232J669D01*
G02X919264Y272200I-351J-191D01*
G01X918687D01*
G03X916247I-1220J-691D01*
G01X915370D01*
G02X915019Y272791I0J400D01*
G03X912555I-1232J669D01*
G02X912204Y272200I-351J-191D01*
G01X909315D01*
X905757Y268642D01*
X887342D01*
X887100Y268400D01*
Y268142D01*
X830558Y211600D01*
X821000D01*
G37*
G36*
G01X907984Y230896D02*
X908333Y231656D01*
X909234D01*
X909583Y230896D01*
Y230721D01*
X907984D01*
Y230896D01*
G37*
G36*
G01X909569Y229796D02*
X909219Y229036D01*
X908319D01*
X907969Y229796D01*
Y229971D01*
X909569D01*
Y229796D01*
G37*
G36*
G01X908718Y338981D02*
X909071Y339649D01*
X909941Y339645D01*
X910287Y338973D01*
Y338798D01*
X908717Y338807D01*
X908718Y338981D01*
G37*
G36*
G01X908783Y343166D02*
X908433Y342406D01*
X907533D01*
X907183Y343166D01*
Y343341D01*
X908783D01*
Y343166D01*
G37*
G36*
G01X910021Y366329D02*
X909236Y366039D01*
X908600Y366675D01*
X908890Y367460D01*
X909013Y367584D01*
X910145Y366452D01*
X910021Y366329D01*
G37*
G36*
G01X909666Y368236D02*
X910451Y368526D01*
X911087Y367890D01*
X910797Y367105D01*
X910674Y366981D01*
X909542Y368113D01*
X909666Y368236D01*
G37*
G36*
G01X905986Y368763D02*
X906337Y369524D01*
X907236D01*
X907586Y368763D01*
X907587Y368589D01*
X905986D01*
Y368763D01*
G37*
G36*
G01X908846Y388566D02*
X908496Y387806D01*
X907596D01*
X907246Y388566D01*
Y388741D01*
X908846D01*
Y388566D01*
G37*
G36*
G01X907246Y389664D02*
X907596Y390424D01*
X908496D01*
X908846Y389664D01*
Y389489D01*
X907246D01*
Y389664D01*
G37*
G36*
G01X907183Y344264D02*
X907533Y345024D01*
X908433D01*
X908783Y344264D01*
Y344089D01*
X907183D01*
Y344264D01*
G37*
G36*
G01X903783D02*
X904133Y345024D01*
X905033D01*
X905383Y344264D01*
Y344089D01*
X903783D01*
Y344264D01*
G37*
G36*
G01X910129Y361566D02*
X909779Y360806D01*
X908879D01*
X908529Y361566D01*
Y361741D01*
X910129D01*
Y361566D01*
G37*
G36*
G01X906229D02*
X905879Y360806D01*
X904979D01*
X904629Y361566D01*
Y361741D01*
X906229D01*
Y361566D01*
G37*
G36*
G01X902329D02*
X901979Y360806D01*
X901079D01*
X900729Y361566D01*
Y361741D01*
X902329D01*
Y361566D01*
G37*
G36*
G01X900729Y362664D02*
X901079Y363424D01*
X901979D01*
X902329Y362664D01*
Y362489D01*
X900729D01*
Y362664D01*
G37*
G36*
G01X908529D02*
X908879Y363424D01*
X909779D01*
X910129Y362664D01*
Y362489D01*
X908529D01*
Y362664D01*
G37*
G36*
G01X904629D02*
X904979Y363424D01*
X905879D01*
X906229Y362664D01*
Y362489D01*
X904629D01*
Y362664D01*
G37*
G36*
G01X909968Y356466D02*
X909618Y355706D01*
X908718D01*
X908368Y356466D01*
Y356641D01*
X909968D01*
Y356466D01*
G37*
G36*
G01X906068D02*
X905718Y355706D01*
X904818D01*
X904468Y356466D01*
Y356641D01*
X906068D01*
Y356466D01*
G37*
G36*
G01X902168D02*
X901818Y355706D01*
X900918D01*
X900568Y356466D01*
Y356641D01*
X902168D01*
Y356466D01*
G37*
G36*
G01X900868Y357564D02*
X901218Y358324D01*
X902118D01*
X902468Y357564D01*
Y357389D01*
X900868D01*
Y357564D01*
G37*
G36*
G01X904768D02*
X905118Y358324D01*
X906018D01*
X906368Y357564D01*
Y357389D01*
X904768D01*
Y357564D01*
G37*
G36*
G01X908668D02*
X909018Y358324D01*
X909918D01*
X910268Y357564D01*
Y357389D01*
X908668D01*
Y357564D01*
G37*
G36*
G01X909211Y371481D02*
X908426Y371191D01*
X907790Y371827D01*
X908080Y372612D01*
X908203Y372736D01*
X909335Y371604D01*
X909211Y371481D01*
G37*
G36*
G01X908856Y373388D02*
X909641Y373678D01*
X910277Y373042D01*
X909987Y372257D01*
X909864Y372133D01*
X908732Y373265D01*
X908856Y373388D01*
G37*
G36*
G01X904145Y374318D02*
X904495Y375078D01*
X905394D01*
X905744Y374318D01*
X905745Y374143D01*
X904144D01*
X904145Y374318D01*
G37*
G36*
G01X908817Y351637D02*
X909167Y350967D01*
X910037D01*
X910386Y351637D01*
X910388Y351813D01*
X908817Y351811D01*
Y351637D01*
G37*
G36*
G01X904917D02*
X905267Y350967D01*
X906137D01*
X906486Y351637D01*
X906488Y351813D01*
X904917Y351811D01*
Y351637D01*
G37*
G36*
G01X901017D02*
X901367Y350967D01*
X902237D01*
X902586Y351637D01*
X902588Y351813D01*
X901017Y351811D01*
Y351637D01*
G37*
G36*
G01X909330Y377075D02*
X910115Y377365D01*
X910751Y376729D01*
X910461Y375944D01*
X910338Y375820D01*
X909206Y376952D01*
X909330Y377075D01*
G37*
G36*
G01X910168Y382636D02*
X909818Y381876D01*
X908918D01*
X908568Y382636D01*
Y382811D01*
X910168D01*
Y382636D01*
G37*
G36*
G01X906268D02*
X905918Y381876D01*
X905018D01*
X904668Y382636D01*
Y382811D01*
X906268D01*
Y382636D01*
G37*
G36*
G01X909595Y348859D02*
X909945Y349619D01*
X910845D01*
X911195Y348859D01*
Y348684D01*
X909595D01*
Y348859D01*
G37*
G36*
G01X908817Y352745D02*
X909167Y353415D01*
X910037D01*
X910386Y352745D01*
X910388Y352569D01*
X908817Y352571D01*
Y352745D01*
G37*
G36*
G01X904917D02*
X905267Y353415D01*
X906137D01*
X906486Y352745D01*
X906488Y352569D01*
X904917Y352571D01*
Y352745D01*
G37*
G36*
G01X901017D02*
X901367Y353415D01*
X902237D01*
X902586Y352745D01*
X902588Y352569D01*
X901017Y352571D01*
Y352745D01*
G37*
G36*
G01X909683Y375166D02*
X908899Y374876D01*
X908262Y375513D01*
X908552Y376297D01*
X908676Y376421D01*
X909807Y375290D01*
X909683Y375166D01*
G37*
G36*
G01X908568Y383736D02*
X908918Y384496D01*
X909818D01*
X910168Y383736D01*
Y383561D01*
X908568D01*
Y383736D01*
G37*
G36*
G01X904668D02*
X905018Y384496D01*
X905918D01*
X906268Y383736D01*
Y383561D01*
X904668D01*
Y383736D01*
G37*
G36*
G01X911195Y347759D02*
X910845Y346999D01*
X909945D01*
X909595Y347759D01*
Y347934D01*
X911195D01*
Y347759D01*
G37*
G36*
G01X917258Y214931D02*
X916968Y215715D01*
X917605Y216352D01*
X918389Y216062D01*
X918513Y215938D01*
X917382Y214807D01*
X917258Y214931D01*
G37*
G36*
G01X920058Y217731D02*
X919768Y218515D01*
X920405Y219152D01*
X921189Y218862D01*
X921313Y218738D01*
X920182Y217607D01*
X920058Y217731D01*
G37*
G36*
G01X914458Y212131D02*
X914168Y212915D01*
X914805Y213552D01*
X915589Y213262D01*
X915713Y213138D01*
X914582Y212007D01*
X914458Y212131D01*
G37*
G36*
G01X919166Y215285D02*
X919456Y214501D01*
X918819Y213864D01*
X918035Y214154D01*
X917911Y214278D01*
X919042Y215409D01*
X919166Y215285D01*
G37*
G36*
G01X916408Y212528D02*
X916698Y211743D01*
X916062Y211106D01*
X915277Y211396D01*
X915153Y211520D01*
X916284Y212651D01*
X916408Y212528D01*
G37*
G36*
G01X921966Y218085D02*
X922256Y217301D01*
X921619Y216664D01*
X920835Y216954D01*
X920711Y217078D01*
X921842Y218209D01*
X921966Y218085D01*
G37*
G36*
G01X914957Y216901D02*
X914667Y217685D01*
X915304Y218322D01*
X916088Y218032D01*
X916212Y217908D01*
X915081Y216777D01*
X914957Y216901D01*
G37*
G36*
G01X916866Y217254D02*
X917156Y216469D01*
X916520Y215833D01*
X915735Y216123D01*
X915611Y216246D01*
X916743Y217378D01*
X916866Y217254D01*
G37*
G36*
G01X925106Y210233D02*
X924436Y210582D01*
Y211452D01*
X925106Y211802D01*
X925281Y211803D01*
Y210232D01*
X925106Y210233D01*
G37*
G36*
G01X921726Y204383D02*
X921056Y204732D01*
Y205602D01*
X921726Y205952D01*
X921901Y205953D01*
Y204382D01*
X921726Y204383D01*
G37*
G36*
G01X922260Y206962D02*
X922228Y207717D01*
X922981Y208152D01*
X923619Y207747D01*
X923707Y207596D01*
X922347Y206810D01*
X922260Y206962D01*
G37*
G36*
G01X929020Y214761D02*
X928988Y215516D01*
X929741Y215951D01*
X930379Y215546D01*
X930467Y215395D01*
X929107Y214609D01*
X929020Y214761D01*
G37*
G36*
G01X925640Y212812D02*
X925608Y213567D01*
X926361Y214002D01*
X926999Y213597D01*
X927087Y213446D01*
X925727Y212660D01*
X925640Y212812D01*
G37*
G36*
G01X932406Y216715D02*
X932374Y217470D01*
X933127Y217905D01*
X933765Y217500D01*
X933853Y217348D01*
X932493Y216563D01*
X932406Y216715D01*
G37*
G36*
G01X923349Y204045D02*
X924019Y203695D01*
Y202825D01*
X923349Y202475D01*
X923174D01*
Y204045D01*
X923349D01*
G37*
G36*
G01X926728Y209936D02*
X927398Y209587D01*
Y208717D01*
X926728Y208367D01*
X926553Y208366D01*
Y209937D01*
X926728Y209936D01*
G37*
G36*
G01X926194Y207357D02*
X926226Y206602D01*
X925473Y206167D01*
X924835Y206572D01*
X924747Y206723D01*
X926107Y207509D01*
X926194Y207357D01*
G37*
G36*
G01X932948Y215154D02*
X932980Y214399D01*
X932227Y213964D01*
X931589Y214369D01*
X931501Y214520D01*
X932861Y215306D01*
X932948Y215154D01*
G37*
G36*
G01X929574Y213208D02*
X929606Y212453D01*
X928853Y212018D01*
X928215Y212423D01*
X928127Y212574D01*
X929487Y213360D01*
X929574Y213208D01*
G37*
G36*
G01X936334Y217108D02*
X936366Y216353D01*
X935613Y215918D01*
X934975Y216323D01*
X934887Y216474D01*
X936247Y217260D01*
X936334Y217108D01*
G37*
G36*
G01X938626Y202442D02*
X937956Y202793D01*
X937957Y203663D01*
X938627Y204012D01*
X938803D01*
X938801Y202441D01*
X938626Y202442D01*
G37*
G36*
G01Y198542D02*
X937956Y198893D01*
X937957Y199763D01*
X938627Y200112D01*
X938803D01*
X938801Y198541D01*
X938626Y198542D01*
G37*
G36*
G01X940008Y194479D02*
X939248Y194829D01*
Y195729D01*
X940008Y196079D01*
X940183D01*
Y194479D01*
X940008D01*
G37*
G36*
G01X939166Y205015D02*
X939134Y205770D01*
X939887Y206205D01*
X940525Y205800D01*
X940613Y205648D01*
X939253Y204863D01*
X939166Y205015D01*
G37*
G36*
G01X942546Y206965D02*
X942514Y207720D01*
X943267Y208155D01*
X943905Y207750D01*
X943993Y207598D01*
X942633Y206813D01*
X942546Y206965D01*
G37*
G36*
G01X945935Y208920D02*
X945903Y209675D01*
X946656Y210110D01*
X947294Y209705D01*
X947382Y209554D01*
X946022Y208768D01*
X945935Y208920D01*
G37*
G36*
G01X949306Y210864D02*
X949274Y211619D01*
X950027Y212054D01*
X950665Y211649D01*
X950753Y211497D01*
X949393Y210712D01*
X949306Y210864D01*
G37*
G36*
G01X959445Y216715D02*
X959413Y217470D01*
X960166Y217905D01*
X960804Y217500D01*
X960892Y217348D01*
X959532Y216563D01*
X959445Y216715D01*
G37*
G36*
G01X952686Y212816D02*
X952654Y213571D01*
X953407Y214006D01*
X954045Y213601D01*
X954133Y213450D01*
X952773Y212664D01*
X952686Y212816D01*
G37*
G36*
G01X956065Y214764D02*
X956033Y215519D01*
X956786Y215954D01*
X957424Y215549D01*
X957512Y215397D01*
X956152Y214612D01*
X956065Y214764D01*
G37*
G36*
G01X940249Y202119D02*
X940919Y201769D01*
Y200899D01*
X940249Y200549D01*
X940074D01*
Y202119D01*
X940249D01*
G37*
G36*
G01X941108Y196079D02*
X941868Y195729D01*
Y194829D01*
X941108Y194479D01*
X940933D01*
Y196079D01*
X941108D01*
G37*
G36*
G01X943094Y205408D02*
X943126Y204653D01*
X942373Y204218D01*
X941735Y204623D01*
X941647Y204774D01*
X943007Y205559D01*
X943094Y205408D01*
G37*
G36*
G01X946474Y207357D02*
X946506Y206602D01*
X945753Y206167D01*
X945115Y206572D01*
X945027Y206723D01*
X946387Y207508D01*
X946474Y207357D01*
G37*
G36*
G01X949854Y209308D02*
X949886Y208553D01*
X949133Y208118D01*
X948495Y208523D01*
X948407Y208674D01*
X949767Y209459D01*
X949854Y209308D01*
G37*
G36*
G01X963373Y217108D02*
X963405Y216353D01*
X962652Y215918D01*
X962014Y216323D01*
X961926Y216474D01*
X963286Y217260D01*
X963373Y217108D01*
G37*
G36*
G01X959993Y215157D02*
X960025Y214402D01*
X959272Y213967D01*
X958634Y214372D01*
X958546Y214523D01*
X959906Y215308D01*
X959993Y215157D01*
G37*
G36*
G01X956614Y213208D02*
X956646Y212453D01*
X955893Y212018D01*
X955255Y212423D01*
X955167Y212574D01*
X956527Y213359D01*
X956614Y213208D01*
G37*
G36*
G01X953228Y211254D02*
X953260Y210499D01*
X952507Y210064D01*
X951869Y210469D01*
X951781Y210620D01*
X953141Y211406D01*
X953228Y211254D01*
G37*
G36*
G01X918880Y208911D02*
X918848Y209666D01*
X919601Y210101D01*
X920239Y209696D01*
X920327Y209545D01*
X918967Y208759D01*
X918880Y208911D01*
G37*
G36*
G01X921647Y213543D02*
X921242Y214181D01*
X921677Y214934D01*
X922432Y214902D01*
X922583Y214815D01*
X921798Y213455D01*
X921647Y213543D01*
G37*
G36*
G01X925646Y216715D02*
X925614Y217470D01*
X926367Y217905D01*
X927005Y217500D01*
X927093Y217348D01*
X925733Y216563D01*
X925646Y216715D01*
G37*
G36*
G01X923347Y211881D02*
X924017Y211531D01*
Y210661D01*
X923348Y210311D01*
X923173D01*
X923172Y211881D01*
X923347D01*
G37*
G36*
G01X922808Y209305D02*
X922840Y208550D01*
X922087Y208115D01*
X921449Y208520D01*
X921361Y208671D01*
X922721Y209457D01*
X922808Y209305D01*
G37*
G36*
G01X926188Y215154D02*
X926220Y214399D01*
X925467Y213964D01*
X924829Y214369D01*
X924741Y214520D01*
X926101Y215306D01*
X926188Y215154D01*
G37*
G36*
G01X929574Y217108D02*
X929606Y216353D01*
X928853Y215918D01*
X928215Y216323D01*
X928127Y216474D01*
X929487Y217260D01*
X929574Y217108D01*
G37*
G36*
G01X935245Y200549D02*
X934575Y200899D01*
Y201769D01*
X935245Y202119D01*
X935420D01*
Y200549D01*
X935245D01*
G37*
G36*
G01X935769Y195444D02*
X935009Y195794D01*
Y196694D01*
X935769Y197044D01*
X935944D01*
Y195444D01*
X935769D01*
G37*
G36*
G01X939175Y208920D02*
X939143Y209675D01*
X939896Y210110D01*
X940534Y209705D01*
X940622Y209554D01*
X939262Y208768D01*
X939175Y208920D01*
G37*
G36*
G01X935795Y206971D02*
X935763Y207726D01*
X936516Y208161D01*
X937154Y207756D01*
X937242Y207605D01*
X935882Y206819D01*
X935795Y206971D01*
G37*
G36*
G01X935247Y204396D02*
X934577Y204745D01*
X934575Y205614D01*
X935244Y205965D01*
X935419Y205966D01*
X935422Y204396D01*
X935247D01*
G37*
G36*
G01X945926Y212815D02*
X945894Y213570D01*
X946647Y214005D01*
X947285Y213600D01*
X947373Y213448D01*
X946013Y212663D01*
X945926Y212815D01*
G37*
G36*
G01X942540Y210861D02*
X942508Y211616D01*
X943261Y212051D01*
X943899Y211646D01*
X943987Y211495D01*
X942627Y210709D01*
X942540Y210861D01*
G37*
G36*
G01X952686Y216715D02*
X952654Y217470D01*
X953407Y217905D01*
X954045Y217500D01*
X954133Y217348D01*
X952773Y216563D01*
X952686Y216715D01*
G37*
G36*
G01X949300Y214761D02*
X949268Y215516D01*
X950021Y215951D01*
X950659Y215546D01*
X950747Y215395D01*
X949387Y214609D01*
X949300Y214761D01*
G37*
G36*
G01X936869Y204045D02*
X937539Y203695D01*
Y202825D01*
X936869Y202475D01*
X936694D01*
Y204045D01*
X936869D01*
G37*
G36*
G01X936868Y197044D02*
X937628Y196694D01*
Y195794D01*
X936868Y195444D01*
X936693D01*
Y197044D01*
X936868D01*
G37*
G36*
G01X939714Y207357D02*
X939746Y206602D01*
X938993Y206167D01*
X938355Y206572D01*
X938267Y206723D01*
X939627Y207508D01*
X939714Y207357D01*
G37*
G36*
G01X943079Y209299D02*
X943111Y208544D01*
X942358Y208109D01*
X941720Y208514D01*
X941632Y208665D01*
X942992Y209450D01*
X943079Y209299D01*
G37*
G36*
G01X946468Y211254D02*
X946500Y210499D01*
X945747Y210064D01*
X945109Y210469D01*
X945021Y210620D01*
X946381Y211406D01*
X946468Y211254D01*
G37*
G36*
G01X949854Y213208D02*
X949886Y212453D01*
X949133Y212018D01*
X948495Y212423D01*
X948407Y212574D01*
X949767Y213360D01*
X949854Y213208D01*
G37*
G36*
G01X956608Y217105D02*
X956640Y216350D01*
X955887Y215915D01*
X955249Y216320D01*
X955161Y216471D01*
X956521Y217257D01*
X956608Y217105D01*
G37*
G36*
G01X953228Y215154D02*
X953260Y214399D01*
X952507Y213964D01*
X951869Y214369D01*
X951781Y214520D01*
X953141Y215306D01*
X953228Y215154D01*
G37*
G36*
G01X970681Y209313D02*
X970391Y210098D01*
X971027Y210734D01*
X971812Y210444D01*
X971936Y210321D01*
X970804Y209189D01*
X970681Y209313D01*
G37*
G36*
G01X967881Y206513D02*
X967591Y207298D01*
X968227Y207934D01*
X969012Y207644D01*
X969136Y207521D01*
X968004Y206389D01*
X967881Y206513D01*
G37*
G36*
G01X972588Y209668D02*
X972878Y208883D01*
X972242Y208247D01*
X971457Y208537D01*
X971333Y208660D01*
X972465Y209792D01*
X972588Y209668D01*
G37*
G36*
G01X969788Y206868D02*
X970078Y206083D01*
X969442Y205447D01*
X968657Y205737D01*
X968533Y205860D01*
X969665Y206992D01*
X969788Y206868D01*
G37*
G36*
G01X970561Y217655D02*
X970271Y218439D01*
X970908Y219076D01*
X971692Y218786D01*
X971816Y218662D01*
X970685Y217531D01*
X970561Y217655D01*
G37*
G36*
G01X958428Y207765D02*
X958138Y208549D01*
X958775Y209186D01*
X959559Y208896D01*
X959683Y208772D01*
X958552Y207641D01*
X958428Y207765D01*
G37*
G36*
G01X955628Y204965D02*
X955338Y205749D01*
X955975Y206386D01*
X956759Y206096D01*
X956883Y205972D01*
X955752Y204841D01*
X955628Y204965D01*
G37*
G36*
G01X967761Y214855D02*
X967471Y215639D01*
X968108Y216276D01*
X968892Y215986D01*
X969016Y215862D01*
X967885Y214731D01*
X967761Y214855D01*
G37*
G36*
G01X969672Y215206D02*
X969962Y214422D01*
X969325Y213785D01*
X968541Y214075D01*
X968417Y214199D01*
X969548Y215330D01*
X969672Y215206D01*
G37*
G36*
G01X972472Y218006D02*
X972762Y217222D01*
X972125Y216585D01*
X971341Y216875D01*
X971217Y216999D01*
X972348Y218130D01*
X972472Y218006D01*
G37*
G36*
G01X957539Y205316D02*
X957829Y204532D01*
X957192Y203895D01*
X956408Y204185D01*
X956284Y204309D01*
X957415Y205440D01*
X957539Y205316D01*
G37*
G36*
G01X960339Y208116D02*
X960629Y207332D01*
X959992Y206695D01*
X959208Y206985D01*
X959084Y207109D01*
X960215Y208240D01*
X960339Y208116D01*
G37*
G36*
G01X968075Y212232D02*
X968365Y211448D01*
X967728Y210811D01*
X966944Y211101D01*
X966820Y211225D01*
X967951Y212356D01*
X968075Y212232D01*
G37*
G36*
G01X926728Y202120D02*
X927398Y201770D01*
Y200900D01*
X926728Y200550D01*
X926553D01*
Y202120D01*
X926728D01*
G37*
G36*
G01X932948Y211254D02*
X932980Y210499D01*
X932227Y210064D01*
X931589Y210469D01*
X931501Y210620D01*
X932861Y211406D01*
X932948Y211254D01*
G37*
G36*
G01X930107Y207980D02*
X930777Y207630D01*
Y206760D01*
X930108Y206410D01*
X929933D01*
X929932Y207980D01*
X930107D01*
G37*
G36*
G01X929568Y205404D02*
X929600Y204649D01*
X928847Y204214D01*
X928209Y204619D01*
X928121Y204770D01*
X929481Y205556D01*
X929568Y205404D01*
G37*
G36*
G01X939708Y215154D02*
X939740Y214399D01*
X938987Y213964D01*
X938349Y214369D01*
X938261Y214520D01*
X939621Y215306D01*
X939708Y215154D01*
G37*
G36*
G01X936334Y213208D02*
X936366Y212453D01*
X935613Y212018D01*
X934975Y212423D01*
X934887Y212574D01*
X936247Y213360D01*
X936334Y213208D01*
G37*
G36*
G01X943094Y217108D02*
X943126Y216353D01*
X942373Y215918D01*
X941735Y216323D01*
X941647Y216474D01*
X943007Y217260D01*
X943094Y217108D01*
G37*
G36*
G01X971602Y200763D02*
X971892Y199979D01*
X971255Y199342D01*
X970471Y199632D01*
X970347Y199756D01*
X971478Y200887D01*
X971602Y200763D01*
G37*
G36*
G01X933489Y202119D02*
X934159Y201769D01*
Y200899D01*
X933489Y200549D01*
X933314D01*
Y202119D01*
X933489D01*
G37*
G36*
G01X939708Y211254D02*
X939740Y210499D01*
X938987Y210064D01*
X938349Y210469D01*
X938261Y210620D01*
X939621Y211406D01*
X939708Y211254D01*
G37*
G36*
G01X933489Y205970D02*
X934159Y205620D01*
Y204750D01*
X933489Y204400D01*
X933314D01*
Y205970D01*
X933489D01*
G37*
G36*
G01X936328Y209305D02*
X936360Y208550D01*
X935607Y208115D01*
X934969Y208520D01*
X934881Y208671D01*
X936241Y209457D01*
X936328Y209305D01*
G37*
G36*
G01X943094Y213208D02*
X943126Y212453D01*
X942373Y212018D01*
X941735Y212423D01*
X941647Y212574D01*
X943007Y213360D01*
X943094Y213208D01*
G37*
G36*
G01X949854Y217108D02*
X949886Y216353D01*
X949133Y215918D01*
X948495Y216323D01*
X948407Y216474D01*
X949767Y217260D01*
X949854Y217108D01*
G37*
G36*
G01X946468Y215154D02*
X946500Y214399D01*
X945747Y213964D01*
X945109Y214369D01*
X945021Y214520D01*
X946381Y215306D01*
X946468Y215154D01*
G37*
G36*
G01X925107Y202447D02*
X924437Y202797D01*
Y203667D01*
X925106Y204017D01*
X925282D01*
Y202447D01*
X925107D01*
G37*
G36*
G01X924161Y198357D02*
X923756Y198995D01*
X924191Y199749D01*
X924945Y199717D01*
X925098Y199629D01*
X924312Y198270D01*
X924161Y198357D01*
G37*
G36*
G01X928487Y208296D02*
X927817Y208646D01*
Y209516D01*
X928486Y209866D01*
X928662D01*
Y208296D01*
X928487D01*
G37*
G36*
G01X925653Y205019D02*
X925621Y205774D01*
X926374Y206209D01*
X927012Y205804D01*
X927100Y205652D01*
X925740Y204867D01*
X925653Y205019D01*
G37*
G36*
G01X935786Y214764D02*
X935754Y215519D01*
X936507Y215954D01*
X937145Y215549D01*
X937233Y215398D01*
X935873Y214612D01*
X935786Y214764D01*
G37*
G36*
G01X932413Y212819D02*
X932381Y213574D01*
X933134Y214009D01*
X933772Y213604D01*
X933860Y213452D01*
X932500Y212667D01*
X932413Y212819D01*
G37*
G36*
G01X929033Y210868D02*
X929001Y211623D01*
X929754Y212058D01*
X930392Y211653D01*
X930480Y211501D01*
X929120Y210716D01*
X929033Y210868D01*
G37*
G36*
G01X939173Y216719D02*
X939141Y217474D01*
X939894Y217909D01*
X940532Y217504D01*
X940620Y217352D01*
X939260Y216567D01*
X939173Y216719D01*
G37*
G36*
G01X969193Y199910D02*
X968903Y200695D01*
X969539Y201331D01*
X970324Y201041D01*
X970448Y200918D01*
X969316Y199786D01*
X969193Y199910D01*
G37*
G36*
G01X931865Y202475D02*
X931195Y202825D01*
Y203695D01*
X931865Y204045D01*
X932040D01*
Y202475D01*
X931865D01*
G37*
G36*
G01Y206374D02*
X931196Y206724D01*
Y207594D01*
X931866Y207943D01*
X932040Y207944D01*
X932041Y206374D01*
X931865D01*
G37*
G36*
G01X932463Y208962D02*
X932442Y209716D01*
X933202Y210140D01*
X933833Y209725D01*
X933919Y209574D01*
X932548Y208808D01*
X932463Y208962D01*
G37*
G36*
G01X939166Y212815D02*
X939134Y213570D01*
X939887Y214005D01*
X940525Y213600D01*
X940613Y213448D01*
X939253Y212663D01*
X939166Y212815D01*
G37*
G36*
G01X935780Y210861D02*
X935748Y211616D01*
X936501Y212051D01*
X937139Y211646D01*
X937227Y211495D01*
X935867Y210709D01*
X935780Y210861D01*
G37*
G36*
G01X945926Y216715D02*
X945894Y217470D01*
X946647Y217905D01*
X947285Y217500D01*
X947373Y217348D01*
X946013Y216563D01*
X945926Y216715D01*
G37*
G36*
G01X942540Y214761D02*
X942508Y215516D01*
X943261Y215951D01*
X943899Y215546D01*
X943987Y215395D01*
X942627Y214609D01*
X942540Y214761D01*
G37*
G36*
G01X935780Y265461D02*
X935748Y266216D01*
X936501Y266651D01*
X937139Y266246D01*
X937227Y266094D01*
X935867Y265310D01*
X935780Y265461D01*
G37*
G36*
G01X914689Y260400D02*
X915327Y260805D01*
X916080Y260370D01*
X916048Y259615D01*
X915961Y259463D01*
X914601Y260248D01*
X914689Y260400D01*
G37*
G36*
G01X918886Y259615D02*
X918854Y260370D01*
X919607Y260805D01*
X920245Y260400D01*
X920333Y260248D01*
X918973Y259463D01*
X918886Y259615D01*
G37*
G36*
G01X921449Y260400D02*
X922087Y260805D01*
X922840Y260370D01*
X922808Y259615D01*
X922721Y259463D01*
X921361Y260248D01*
X921449Y260400D01*
G37*
G36*
G01X925646Y259615D02*
X925614Y260370D01*
X926367Y260805D01*
X927005Y260400D01*
X927093Y260248D01*
X925733Y259463D01*
X925646Y259615D01*
G37*
G36*
G01X929020Y261561D02*
X928988Y262316D01*
X929741Y262751D01*
X930379Y262346D01*
X930467Y262194D01*
X929107Y261409D01*
X929020Y261561D01*
G37*
G36*
G01X932406Y263515D02*
X932374Y264270D01*
X933127Y264705D01*
X933765Y264300D01*
X933853Y264148D01*
X932493Y263364D01*
X932406Y263515D01*
G37*
G36*
G01X939166Y267415D02*
X939134Y268170D01*
X939887Y268605D01*
X940525Y268200D01*
X940613Y268048D01*
X939253Y267264D01*
X939166Y267415D01*
G37*
G36*
G01X945115Y266246D02*
X945753Y266651D01*
X946506Y266216D01*
X946474Y265461D01*
X946387Y265310D01*
X945027Y266094D01*
X945115Y266246D01*
G37*
G36*
G01X941729Y268200D02*
X942367Y268605D01*
X943120Y268170D01*
X943088Y267415D01*
X943001Y267264D01*
X941641Y268048D01*
X941729Y268200D01*
G37*
G36*
G01X939160Y228412D02*
X939128Y229167D01*
X939881Y229602D01*
X940519Y229197D01*
X940607Y229046D01*
X939247Y228260D01*
X939160Y228412D01*
G37*
G36*
G01X935795Y226470D02*
X935763Y227225D01*
X936516Y227660D01*
X937154Y227255D01*
X937242Y227104D01*
X935882Y226318D01*
X935795Y226470D01*
G37*
G36*
G01X932406Y224515D02*
X932374Y225270D01*
X933127Y225705D01*
X933765Y225300D01*
X933853Y225148D01*
X932493Y224363D01*
X932406Y224515D01*
G37*
G36*
G01X929020Y222561D02*
X928988Y223316D01*
X929741Y223751D01*
X930379Y223346D01*
X930467Y223195D01*
X929107Y222409D01*
X929020Y222561D01*
G37*
G36*
G01X925646Y220615D02*
X925614Y221370D01*
X926367Y221805D01*
X927005Y221400D01*
X927093Y221248D01*
X925733Y220463D01*
X925646Y220615D01*
G37*
G36*
G01X939699Y226849D02*
X939731Y226094D01*
X938978Y225659D01*
X938340Y226064D01*
X938252Y226215D01*
X939612Y227000D01*
X939699Y226849D01*
G37*
G36*
G01X936334Y224908D02*
X936366Y224153D01*
X935613Y223718D01*
X934975Y224123D01*
X934887Y224274D01*
X936247Y225060D01*
X936334Y224908D01*
G37*
G36*
G01X929574Y221008D02*
X929606Y220253D01*
X928853Y219818D01*
X928215Y220223D01*
X928127Y220374D01*
X929487Y221160D01*
X929574Y221008D01*
G37*
G36*
G01X926188Y219054D02*
X926220Y218299D01*
X925467Y217864D01*
X924829Y218269D01*
X924741Y218420D01*
X926101Y219206D01*
X926188Y219054D01*
G37*
G36*
G01X932954Y222957D02*
X932986Y222202D01*
X932233Y221767D01*
X931595Y222172D01*
X931507Y222323D01*
X932867Y223109D01*
X932954Y222957D01*
G37*
G36*
G01X943088Y228804D02*
X943120Y228049D01*
X942367Y227614D01*
X941729Y228019D01*
X941641Y228170D01*
X943001Y228956D01*
X943088Y228804D01*
G37*
G36*
G01X939166Y247915D02*
X939134Y248670D01*
X939887Y249105D01*
X940525Y248700D01*
X940613Y248548D01*
X939253Y247763D01*
X939166Y247915D01*
G37*
G36*
G01X935780Y245961D02*
X935748Y246716D01*
X936501Y247151D01*
X937139Y246746D01*
X937227Y246595D01*
X935867Y245809D01*
X935780Y245961D01*
G37*
G36*
G01X932406Y244015D02*
X932374Y244770D01*
X933127Y245205D01*
X933765Y244800D01*
X933853Y244648D01*
X932493Y243863D01*
X932406Y244015D01*
G37*
G36*
G01X929020Y242061D02*
X928988Y242816D01*
X929741Y243251D01*
X930379Y242846D01*
X930467Y242695D01*
X929107Y241909D01*
X929020Y242061D01*
G37*
G36*
G01X925646Y240115D02*
X925614Y240870D01*
X926367Y241305D01*
X927005Y240900D01*
X927093Y240748D01*
X925733Y239963D01*
X925646Y240115D01*
G37*
G36*
G01X921449Y240900D02*
X922087Y241305D01*
X922840Y240870D01*
X922808Y240115D01*
X922721Y239963D01*
X921361Y240748D01*
X921449Y240900D01*
G37*
G36*
G01X918886Y240115D02*
X918854Y240870D01*
X919607Y241305D01*
X920245Y240900D01*
X920333Y240748D01*
X918973Y239963D01*
X918886Y240115D01*
G37*
G36*
G01X911198Y236264D02*
X911548Y237024D01*
X912448D01*
X912798Y236264D01*
Y236089D01*
X911198D01*
Y236264D01*
G37*
G36*
G01X948102Y248057D02*
X948740Y248462D01*
X949493Y248027D01*
X949461Y247272D01*
X949374Y247120D01*
X948014Y247906D01*
X948102Y248057D01*
G37*
G36*
G01X947279Y247523D02*
X946641Y247118D01*
X945888Y247553D01*
X945920Y248308D01*
X946007Y248460D01*
X947367Y247674D01*
X947279Y247523D01*
G37*
G36*
G01X912798Y235166D02*
X912448Y234406D01*
X911548D01*
X911198Y235166D01*
Y235341D01*
X912798D01*
Y235166D01*
G37*
G36*
G01X939708Y246354D02*
X939740Y245599D01*
X938987Y245164D01*
X938349Y245569D01*
X938261Y245720D01*
X939621Y246506D01*
X939708Y246354D01*
G37*
G36*
G01X936334Y244408D02*
X936366Y243653D01*
X935613Y243218D01*
X934975Y243623D01*
X934887Y243774D01*
X936247Y244560D01*
X936334Y244408D01*
G37*
G36*
G01X932948Y242454D02*
X932980Y241699D01*
X932227Y241264D01*
X931589Y241669D01*
X931501Y241820D01*
X932861Y242606D01*
X932948Y242454D01*
G37*
G36*
G01X929574Y240508D02*
X929606Y239753D01*
X928853Y239318D01*
X928215Y239723D01*
X928127Y239874D01*
X929487Y240660D01*
X929574Y240508D01*
G37*
G36*
G01X926188Y238554D02*
X926220Y237799D01*
X925467Y237364D01*
X924829Y237769D01*
X924741Y237920D01*
X926101Y238706D01*
X926188Y238554D01*
G37*
G36*
G01X923625Y237769D02*
X922987Y237364D01*
X922234Y237799D01*
X922266Y238554D01*
X922353Y238706D01*
X923713Y237920D01*
X923625Y237769D01*
G37*
G36*
G01X948489Y244800D02*
X949127Y245205D01*
X949880Y244770D01*
X949848Y244015D01*
X949761Y243863D01*
X948401Y244648D01*
X948489Y244800D01*
G37*
G36*
G01X945115Y246746D02*
X945753Y247151D01*
X946506Y246716D01*
X946474Y245961D01*
X946387Y245809D01*
X945027Y246595D01*
X945115Y246746D01*
G37*
G36*
G01X939175Y232320D02*
X939143Y233075D01*
X939896Y233510D01*
X940534Y233105D01*
X940622Y232954D01*
X939262Y232168D01*
X939175Y232320D01*
G37*
G36*
G01X932400Y228412D02*
X932368Y229167D01*
X933121Y229602D01*
X933759Y229197D01*
X933847Y229046D01*
X932487Y228260D01*
X932400Y228412D01*
G37*
G36*
G01X929035Y226470D02*
X929003Y227225D01*
X929756Y227660D01*
X930394Y227255D01*
X930482Y227104D01*
X929122Y226318D01*
X929035Y226470D01*
G37*
G36*
G01X925646Y224515D02*
X925614Y225270D01*
X926367Y225705D01*
X927005Y225300D01*
X927093Y225148D01*
X925733Y224363D01*
X925646Y224515D01*
G37*
G36*
G01X935780Y230362D02*
X935748Y231117D01*
X936501Y231552D01*
X937139Y231147D01*
X937227Y230996D01*
X935867Y230210D01*
X935780Y230362D01*
G37*
G36*
G01X917757Y219701D02*
X917467Y220485D01*
X918104Y221122D01*
X918888Y220832D01*
X919012Y220708D01*
X917881Y219577D01*
X917757Y219701D01*
G37*
G36*
G01X921717Y223326D02*
X922067Y224085D01*
X922967D01*
X923317Y223326D01*
Y223150D01*
X921717D01*
Y223326D01*
G37*
G36*
G01X939714Y230757D02*
X939746Y230002D01*
X938993Y229567D01*
X938355Y229972D01*
X938267Y230123D01*
X939627Y230908D01*
X939714Y230757D01*
G37*
G36*
G01X932939Y226849D02*
X932971Y226094D01*
X932218Y225659D01*
X931580Y226064D01*
X931492Y226215D01*
X932852Y227000D01*
X932939Y226849D01*
G37*
G36*
G01X926188Y222954D02*
X926220Y222199D01*
X925467Y221764D01*
X924829Y222169D01*
X924741Y222320D01*
X926101Y223106D01*
X926188Y222954D01*
G37*
G36*
G01X929574Y224908D02*
X929606Y224153D01*
X928853Y223718D01*
X928215Y224123D01*
X928127Y224274D01*
X929487Y225060D01*
X929574Y224908D01*
G37*
G36*
G01X936328Y228804D02*
X936360Y228049D01*
X935607Y227614D01*
X934969Y228019D01*
X934881Y228170D01*
X936241Y228956D01*
X936328Y228804D01*
G37*
G36*
G01X919666Y220054D02*
X919956Y219269D01*
X919320Y218633D01*
X918535Y218923D01*
X918411Y219046D01*
X919543Y220178D01*
X919666Y220054D01*
G37*
G36*
G01X943079Y232699D02*
X943111Y231944D01*
X942358Y231509D01*
X941720Y231914D01*
X941632Y232065D01*
X942992Y232850D01*
X943079Y232699D01*
G37*
G36*
G01X923317Y222225D02*
X922967Y221465D01*
X922067D01*
X921717Y222225D01*
Y222400D01*
X923317D01*
Y222225D01*
G37*
G36*
G01X939166Y220615D02*
X939134Y221370D01*
X939887Y221805D01*
X940525Y221400D01*
X940613Y221248D01*
X939253Y220463D01*
X939166Y220615D01*
G37*
G36*
G01X935780Y218661D02*
X935748Y219416D01*
X936501Y219851D01*
X937139Y219446D01*
X937227Y219295D01*
X935867Y218509D01*
X935780Y218661D01*
G37*
G36*
G01X956065Y230365D02*
X956033Y231120D01*
X956786Y231555D01*
X957424Y231150D01*
X957512Y230998D01*
X956152Y230213D01*
X956065Y230365D01*
G37*
G36*
G01X949315Y226470D02*
X949283Y227225D01*
X950036Y227660D01*
X950674Y227255D01*
X950762Y227104D01*
X949402Y226318D01*
X949315Y226470D01*
G37*
G36*
G01X945926Y224515D02*
X945894Y225270D01*
X946647Y225705D01*
X947285Y225300D01*
X947373Y225148D01*
X946013Y224363D01*
X945926Y224515D01*
G37*
G36*
G01X952680Y228412D02*
X952648Y229167D01*
X953401Y229602D01*
X954039Y229197D01*
X954127Y229046D01*
X952767Y228260D01*
X952680Y228412D01*
G37*
G36*
G01X942540Y222561D02*
X942508Y223316D01*
X943261Y223751D01*
X943899Y223346D01*
X943987Y223195D01*
X942627Y222409D01*
X942540Y222561D01*
G37*
G36*
G01X939708Y219054D02*
X939740Y218299D01*
X938987Y217864D01*
X938349Y218269D01*
X938261Y218420D01*
X939621Y219206D01*
X939708Y219054D01*
G37*
G36*
G01X956614Y228807D02*
X956646Y228052D01*
X955893Y227617D01*
X955255Y228022D01*
X955167Y228173D01*
X956527Y228958D01*
X956614Y228807D01*
G37*
G36*
G01X953219Y226849D02*
X953251Y226094D01*
X952498Y225659D01*
X951860Y226064D01*
X951772Y226215D01*
X953132Y227000D01*
X953219Y226849D01*
G37*
G36*
G01X949854Y224908D02*
X949886Y224153D01*
X949133Y223718D01*
X948495Y224123D01*
X948407Y224274D01*
X949767Y225060D01*
X949854Y224908D01*
G37*
G36*
G01X946474Y222957D02*
X946506Y222202D01*
X945753Y221767D01*
X945115Y222172D01*
X945027Y222323D01*
X946387Y223109D01*
X946474Y222957D01*
G37*
G36*
G01X943094Y221008D02*
X943126Y220253D01*
X942373Y219818D01*
X941735Y220223D01*
X941647Y220374D01*
X943007Y221160D01*
X943094Y221008D01*
G37*
G36*
G01X962819Y218661D02*
X962787Y219416D01*
X963540Y219851D01*
X964178Y219446D01*
X964266Y219295D01*
X962906Y218509D01*
X962819Y218661D01*
G37*
G36*
G01X970217Y222100D02*
X969747Y222692D01*
X970101Y223487D01*
X970856Y223534D01*
X971016Y223462D01*
X970377Y222029D01*
X970217Y222100D01*
G37*
G36*
G01X970118Y221037D02*
X970176Y220283D01*
X969438Y219822D01*
X968786Y220205D01*
X968694Y220354D01*
X970025Y221185D01*
X970118Y221037D01*
G37*
G36*
G01X966747Y219054D02*
X966779Y218299D01*
X966026Y217864D01*
X965388Y218269D01*
X965300Y218420D01*
X966660Y219206D01*
X966747Y219054D01*
G37*
G36*
G01X939708Y265854D02*
X939740Y265099D01*
X938987Y264664D01*
X938349Y265069D01*
X938261Y265220D01*
X939621Y266006D01*
X939708Y265854D01*
G37*
G36*
G01X916865Y257269D02*
X916227Y256864D01*
X915474Y257299D01*
X915506Y258054D01*
X915593Y258206D01*
X916953Y257420D01*
X916865Y257269D01*
G37*
G36*
G01X919428Y258054D02*
X919460Y257299D01*
X918707Y256864D01*
X918069Y257269D01*
X917981Y257420D01*
X919341Y258206D01*
X919428Y258054D01*
G37*
G36*
G01X923625Y257269D02*
X922987Y256864D01*
X922234Y257299D01*
X922266Y258054D01*
X922353Y258206D01*
X923713Y257420D01*
X923625Y257269D01*
G37*
G36*
G01X926188Y258054D02*
X926220Y257299D01*
X925467Y256864D01*
X924829Y257269D01*
X924741Y257420D01*
X926101Y258206D01*
X926188Y258054D01*
G37*
G36*
G01X929574Y260008D02*
X929606Y259253D01*
X928853Y258818D01*
X928215Y259223D01*
X928127Y259374D01*
X929487Y260160D01*
X929574Y260008D01*
G37*
G36*
G01X932948Y261954D02*
X932980Y261199D01*
X932227Y260764D01*
X931589Y261169D01*
X931501Y261320D01*
X932861Y262106D01*
X932948Y261954D01*
G37*
G36*
G01X936334Y263908D02*
X936366Y263153D01*
X935613Y262718D01*
X934975Y263123D01*
X934887Y263274D01*
X936247Y264060D01*
X936334Y263908D01*
G37*
G36*
G01X943905Y265069D02*
X943267Y264664D01*
X942514Y265099D01*
X942546Y265854D01*
X942633Y266006D01*
X943993Y265220D01*
X943905Y265069D01*
G37*
G36*
G01X929020Y218661D02*
X928988Y219416D01*
X929741Y219851D01*
X930379Y219446D01*
X930467Y219295D01*
X929107Y218509D01*
X929020Y218661D01*
G37*
G36*
G01X932406Y220615D02*
X932374Y221370D01*
X933127Y221805D01*
X933765Y221400D01*
X933853Y221248D01*
X932493Y220463D01*
X932406Y220615D01*
G37*
G36*
G01X935780Y222561D02*
X935748Y223316D01*
X936501Y223751D01*
X937139Y223346D01*
X937227Y223195D01*
X935867Y222409D01*
X935780Y222561D01*
G37*
G36*
G01X939166Y224515D02*
X939134Y225270D01*
X939887Y225705D01*
X940525Y225300D01*
X940613Y225148D01*
X939253Y224363D01*
X939166Y224515D01*
G37*
G36*
G01X942555Y226470D02*
X942523Y227225D01*
X943276Y227660D01*
X943914Y227255D01*
X944002Y227104D01*
X942642Y226318D01*
X942555Y226470D01*
G37*
G36*
G01X945920Y228412D02*
X945888Y229167D01*
X946641Y229602D01*
X947279Y229197D01*
X947367Y229046D01*
X946007Y228260D01*
X945920Y228412D01*
G37*
G36*
G01X949306Y230365D02*
X949274Y231120D01*
X950027Y231555D01*
X950665Y231150D01*
X950753Y230998D01*
X949393Y230213D01*
X949306Y230365D01*
G37*
G36*
G01X952695Y232320D02*
X952663Y233075D01*
X953416Y233510D01*
X954054Y233105D01*
X954142Y232954D01*
X952782Y232168D01*
X952695Y232320D01*
G37*
G36*
G01X932948Y219054D02*
X932980Y218299D01*
X932227Y217864D01*
X931589Y218269D01*
X931501Y218420D01*
X932861Y219206D01*
X932948Y219054D01*
G37*
G36*
G01X936334Y221008D02*
X936366Y220253D01*
X935613Y219818D01*
X934975Y220223D01*
X934887Y220374D01*
X936247Y221160D01*
X936334Y221008D01*
G37*
G36*
G01X939714Y222957D02*
X939746Y222202D01*
X938993Y221767D01*
X938355Y222172D01*
X938267Y222323D01*
X939627Y223109D01*
X939714Y222957D01*
G37*
G36*
G01X956607Y232703D02*
X956639Y231948D01*
X955886Y231513D01*
X955248Y231918D01*
X955160Y232069D01*
X956520Y232854D01*
X956607Y232703D01*
G37*
G36*
G01X946459Y226849D02*
X946491Y226094D01*
X945738Y225659D01*
X945100Y226064D01*
X945012Y226215D01*
X946372Y227000D01*
X946459Y226849D01*
G37*
G36*
G01X949848Y228804D02*
X949880Y228049D01*
X949127Y227614D01*
X948489Y228019D01*
X948401Y228170D01*
X949761Y228956D01*
X949848Y228804D01*
G37*
G36*
G01X953234Y230757D02*
X953266Y230002D01*
X952513Y229567D01*
X951875Y229972D01*
X951787Y230123D01*
X953147Y230908D01*
X953234Y230757D01*
G37*
G36*
G01X943094Y224908D02*
X943126Y224153D01*
X942373Y223718D01*
X941735Y224123D01*
X941647Y224274D01*
X943007Y225060D01*
X943094Y224908D01*
G37*
G36*
G01X959445Y220615D02*
X959413Y221370D01*
X960166Y221805D01*
X960804Y221400D01*
X960892Y221248D01*
X959532Y220463D01*
X959445Y220615D01*
G37*
G36*
G01X956065Y218664D02*
X956033Y219419D01*
X956786Y219854D01*
X957424Y219449D01*
X957512Y219297D01*
X956152Y218512D01*
X956065Y218664D01*
G37*
G36*
G01X966592Y223872D02*
X966560Y224627D01*
X967313Y225062D01*
X967951Y224657D01*
X968039Y224506D01*
X966679Y223720D01*
X966592Y223872D01*
G37*
G36*
G01X966753Y222957D02*
X966785Y222202D01*
X966032Y221767D01*
X965394Y222172D01*
X965306Y222323D01*
X966666Y223109D01*
X966753Y222957D01*
G37*
G36*
G01X963373Y221008D02*
X963405Y220253D01*
X962652Y219818D01*
X962014Y220223D01*
X961926Y220374D01*
X963286Y221160D01*
X963373Y221008D01*
G37*
G36*
G01X959987Y219054D02*
X960019Y218299D01*
X959266Y217864D01*
X958628Y218269D01*
X958540Y218420D01*
X959900Y219206D01*
X959987Y219054D01*
G37*
G36*
G01X939166Y251815D02*
X939134Y252570D01*
X939887Y253005D01*
X940525Y252600D01*
X940613Y252448D01*
X939253Y251663D01*
X939166Y251815D01*
G37*
G36*
G01X935780Y249861D02*
X935748Y250616D01*
X936501Y251051D01*
X937139Y250646D01*
X937227Y250495D01*
X935867Y249709D01*
X935780Y249861D01*
G37*
G36*
G01X932406Y247915D02*
X932374Y248670D01*
X933127Y249105D01*
X933765Y248700D01*
X933853Y248548D01*
X932493Y247763D01*
X932406Y247915D01*
G37*
G36*
G01X929020Y245961D02*
X928988Y246716D01*
X929741Y247151D01*
X930379Y246746D01*
X930467Y246595D01*
X929107Y245809D01*
X929020Y245961D01*
G37*
G36*
G01X925646Y244015D02*
X925614Y244770D01*
X926367Y245205D01*
X927005Y244800D01*
X927093Y244648D01*
X925733Y243863D01*
X925646Y244015D01*
G37*
G36*
G01X921449Y244800D02*
X922087Y245205D01*
X922840Y244770D01*
X922808Y244015D01*
X922721Y243863D01*
X921361Y244648D01*
X921449Y244800D01*
G37*
G36*
G01X918886Y244015D02*
X918854Y244770D01*
X919607Y245205D01*
X920245Y244800D01*
X920333Y244648D01*
X918973Y243863D01*
X918886Y244015D01*
G37*
G36*
G01X914605Y244832D02*
X915250Y245225D01*
X915995Y244777D01*
X915951Y244022D01*
X915860Y243872D01*
X914515Y244682D01*
X914605Y244832D01*
G37*
G36*
G01X939708Y250254D02*
X939740Y249499D01*
X938987Y249064D01*
X938349Y249469D01*
X938261Y249620D01*
X939621Y250406D01*
X939708Y250254D01*
G37*
G36*
G01X936334Y248308D02*
X936366Y247553D01*
X935613Y247118D01*
X934975Y247523D01*
X934887Y247674D01*
X936247Y248460D01*
X936334Y248308D01*
G37*
G36*
G01X932948Y246354D02*
X932980Y245599D01*
X932227Y245164D01*
X931589Y245569D01*
X931501Y245720D01*
X932861Y246506D01*
X932948Y246354D01*
G37*
G36*
G01X929574Y244408D02*
X929606Y243653D01*
X928853Y243218D01*
X928215Y243623D01*
X928127Y243774D01*
X929487Y244560D01*
X929574Y244408D01*
G37*
G36*
G01X926188Y242454D02*
X926220Y241699D01*
X925467Y241264D01*
X924829Y241669D01*
X924741Y241820D01*
X926101Y242606D01*
X926188Y242454D01*
G37*
G36*
G01X923625Y241669D02*
X922987Y241264D01*
X922234Y241699D01*
X922266Y242454D01*
X922353Y242606D01*
X923713Y241820D01*
X923625Y241669D01*
G37*
G36*
G01X916459Y241601D02*
X915760Y241313D01*
X915094Y241872D01*
X915256Y242611D01*
X915369Y242745D01*
X916571Y241735D01*
X916459Y241601D01*
G37*
G36*
G01X919428Y242454D02*
X919460Y241699D01*
X918707Y241264D01*
X918069Y241669D01*
X917981Y241820D01*
X919341Y242606D01*
X919428Y242454D01*
G37*
G36*
G01X929020Y265461D02*
X928988Y266216D01*
X929741Y266651D01*
X930379Y266246D01*
X930467Y266094D01*
X929107Y265310D01*
X929020Y265461D01*
G37*
G36*
G01X914689Y264300D02*
X915327Y264705D01*
X916080Y264270D01*
X916048Y263515D01*
X915961Y263364D01*
X914601Y264148D01*
X914689Y264300D01*
G37*
G36*
G01X918886Y263515D02*
X918854Y264270D01*
X919607Y264705D01*
X920245Y264300D01*
X920333Y264148D01*
X918973Y263364D01*
X918886Y263515D01*
G37*
G36*
G01X921449Y264300D02*
X922087Y264705D01*
X922840Y264270D01*
X922808Y263515D01*
X922721Y263364D01*
X921361Y264148D01*
X921449Y264300D01*
G37*
G36*
G01X925646Y263515D02*
X925614Y264270D01*
X926367Y264705D01*
X927005Y264300D01*
X927093Y264148D01*
X925733Y263364D01*
X925646Y263515D01*
G37*
G36*
G01X932406Y267415D02*
X932374Y268170D01*
X933127Y268605D01*
X933765Y268200D01*
X933853Y268048D01*
X932493Y267264D01*
X932406Y267415D01*
G37*
G36*
G01X939166Y271315D02*
X939134Y272070D01*
X939887Y272505D01*
X940525Y272100D01*
X940613Y271948D01*
X939253Y271164D01*
X939166Y271315D01*
G37*
G36*
G01X935780Y269361D02*
X935748Y270116D01*
X936501Y270551D01*
X937139Y270146D01*
X937227Y269994D01*
X935867Y269210D01*
X935780Y269361D01*
G37*
G36*
G01X941729Y272100D02*
X942367Y272505D01*
X943120Y272070D01*
X943088Y271315D01*
X943001Y271164D01*
X941641Y271948D01*
X941729Y272100D01*
G37*
G36*
G01X945115Y270146D02*
X945753Y270551D01*
X946506Y270116D01*
X946474Y269361D01*
X946387Y269210D01*
X945027Y269994D01*
X945115Y270146D01*
G37*
G36*
G01X932948Y265854D02*
X932980Y265099D01*
X932227Y264664D01*
X931589Y265069D01*
X931501Y265220D01*
X932861Y266006D01*
X932948Y265854D01*
G37*
G36*
G01X916865Y261169D02*
X916227Y260764D01*
X915474Y261199D01*
X915506Y261954D01*
X915593Y262106D01*
X916953Y261320D01*
X916865Y261169D01*
G37*
G36*
G01X919428Y261954D02*
X919460Y261199D01*
X918707Y260764D01*
X918069Y261169D01*
X917981Y261320D01*
X919341Y262106D01*
X919428Y261954D01*
G37*
G36*
G01X923625Y261169D02*
X922987Y260764D01*
X922234Y261199D01*
X922266Y261954D01*
X922353Y262106D01*
X923713Y261320D01*
X923625Y261169D01*
G37*
G36*
G01X926188Y261954D02*
X926220Y261199D01*
X925467Y260764D01*
X924829Y261169D01*
X924741Y261320D01*
X926101Y262106D01*
X926188Y261954D01*
G37*
G36*
G01X929574Y263908D02*
X929606Y263153D01*
X928853Y262718D01*
X928215Y263123D01*
X928127Y263274D01*
X929487Y264060D01*
X929574Y263908D01*
G37*
G36*
G01X936334Y267808D02*
X936366Y267053D01*
X935613Y266618D01*
X934975Y267023D01*
X934887Y267174D01*
X936247Y267960D01*
X936334Y267808D01*
G37*
G36*
G01X947279Y267023D02*
X946641Y266618D01*
X945888Y267053D01*
X945920Y267808D01*
X946007Y267960D01*
X947367Y267174D01*
X947279Y267023D01*
G37*
G36*
G01X939708Y269754D02*
X939740Y268999D01*
X938987Y268564D01*
X938349Y268969D01*
X938261Y269120D01*
X939621Y269906D01*
X939708Y269754D01*
G37*
G36*
G01X943905Y268969D02*
X943267Y268564D01*
X942514Y268999D01*
X942546Y269754D01*
X942633Y269906D01*
X943993Y269120D01*
X943905Y268969D01*
G37*
G36*
G01X939166Y255715D02*
X939134Y256470D01*
X939887Y256905D01*
X940525Y256500D01*
X940613Y256348D01*
X939253Y255563D01*
X939166Y255715D01*
G37*
G36*
G01X935780Y253761D02*
X935748Y254516D01*
X936501Y254951D01*
X937139Y254546D01*
X937227Y254395D01*
X935867Y253609D01*
X935780Y253761D01*
G37*
G36*
G01X932406Y251815D02*
X932374Y252570D01*
X933127Y253005D01*
X933765Y252600D01*
X933853Y252448D01*
X932493Y251663D01*
X932406Y251815D01*
G37*
G36*
G01X929020Y249861D02*
X928988Y250616D01*
X929741Y251051D01*
X930379Y250646D01*
X930467Y250495D01*
X929107Y249709D01*
X929020Y249861D01*
G37*
G36*
G01X925646Y247915D02*
X925614Y248670D01*
X926367Y249105D01*
X927005Y248700D01*
X927093Y248548D01*
X925733Y247763D01*
X925646Y247915D01*
G37*
G36*
G01X921449Y248700D02*
X922087Y249105D01*
X922840Y248670D01*
X922808Y247915D01*
X922721Y247763D01*
X921361Y248548D01*
X921449Y248700D01*
G37*
G36*
G01X918886Y247915D02*
X918854Y248670D01*
X919607Y249105D01*
X920245Y248700D01*
X920333Y248548D01*
X918973Y247763D01*
X918886Y247915D01*
G37*
G36*
G01X914689Y248700D02*
X915327Y249105D01*
X916080Y248670D01*
X916048Y247915D01*
X915961Y247763D01*
X914601Y248548D01*
X914689Y248700D01*
G37*
G36*
G01X939708Y254154D02*
X939740Y253399D01*
X938987Y252964D01*
X938349Y253369D01*
X938261Y253520D01*
X939621Y254306D01*
X939708Y254154D01*
G37*
G36*
G01X916865Y245569D02*
X916227Y245164D01*
X915474Y245599D01*
X915506Y246354D01*
X915593Y246506D01*
X916953Y245720D01*
X916865Y245569D01*
G37*
G36*
G01X919428Y246354D02*
X919460Y245599D01*
X918707Y245164D01*
X918069Y245569D01*
X917981Y245720D01*
X919341Y246506D01*
X919428Y246354D01*
G37*
G36*
G01X923625Y245569D02*
X922987Y245164D01*
X922234Y245599D01*
X922266Y246354D01*
X922353Y246506D01*
X923713Y245720D01*
X923625Y245569D01*
G37*
G36*
G01X926188Y246354D02*
X926220Y245599D01*
X925467Y245164D01*
X924829Y245569D01*
X924741Y245720D01*
X926101Y246506D01*
X926188Y246354D01*
G37*
G36*
G01X929574Y248308D02*
X929606Y247553D01*
X928853Y247118D01*
X928215Y247523D01*
X928127Y247674D01*
X929487Y248460D01*
X929574Y248308D01*
G37*
G36*
G01X932948Y250254D02*
X932980Y249499D01*
X932227Y249064D01*
X931589Y249469D01*
X931501Y249620D01*
X932861Y250406D01*
X932948Y250254D01*
G37*
G36*
G01X936334Y252208D02*
X936366Y251453D01*
X935613Y251018D01*
X934975Y251423D01*
X934887Y251574D01*
X936247Y252360D01*
X936334Y252208D01*
G37*
G36*
G01X943905Y253369D02*
X943267Y252964D01*
X942514Y253399D01*
X942546Y254154D01*
X942633Y254306D01*
X943993Y253520D01*
X943905Y253369D01*
G37*
G36*
G01X944729Y253903D02*
X945367Y254308D01*
X946120Y253873D01*
X946088Y253118D01*
X946001Y252966D01*
X944641Y253752D01*
X944729Y253903D01*
G37*
G36*
G01X921351Y235009D02*
X921701Y235769D01*
X922601D01*
X922951Y235009D01*
Y234834D01*
X921351D01*
Y235009D01*
G37*
G36*
G01X911884Y230896D02*
X912233Y231656D01*
X913134D01*
X913483Y230896D01*
Y230721D01*
X911884D01*
Y230896D01*
G37*
G36*
G01X917285Y232336D02*
X916994Y233120D01*
X917631Y233757D01*
X918415Y233467D01*
X918539Y233343D01*
X917408Y232212D01*
X917285Y232336D01*
G37*
G36*
G01X939166Y244015D02*
X939134Y244770D01*
X939887Y245205D01*
X940525Y244800D01*
X940613Y244648D01*
X939253Y243863D01*
X939166Y244015D01*
G37*
G36*
G01X932406Y240115D02*
X932374Y240870D01*
X933127Y241305D01*
X933765Y240900D01*
X933853Y240748D01*
X932493Y239963D01*
X932406Y240115D01*
G37*
G36*
G01X935780Y242061D02*
X935748Y242816D01*
X936501Y243251D01*
X937139Y242846D01*
X937227Y242695D01*
X935867Y241909D01*
X935780Y242061D01*
G37*
G36*
G01X929020Y238161D02*
X928988Y238916D01*
X929741Y239351D01*
X930379Y238946D01*
X930467Y238795D01*
X929107Y238009D01*
X929020Y238161D01*
G37*
G36*
G01X925640Y236212D02*
X925608Y236967D01*
X926361Y237402D01*
X926999Y236997D01*
X927087Y236846D01*
X925727Y236060D01*
X925640Y236212D01*
G37*
G36*
G01X926188Y234654D02*
X926220Y233899D01*
X925467Y233464D01*
X924829Y233869D01*
X924741Y234020D01*
X926101Y234806D01*
X926188Y234654D01*
G37*
G36*
G01X922951Y233909D02*
X922601Y233149D01*
X921701D01*
X921351Y233909D01*
Y234084D01*
X922951D01*
Y233909D01*
G37*
G36*
G01X913469Y229796D02*
X913119Y229036D01*
X912219D01*
X911869Y229796D01*
Y229971D01*
X913469D01*
Y229796D01*
G37*
G36*
G01X918975Y232470D02*
X919265Y231685D01*
X918629Y231049D01*
X917844Y231339D01*
X917720Y231462D01*
X918852Y232594D01*
X918975Y232470D01*
G37*
G36*
G01X939708Y242454D02*
X939740Y241699D01*
X938987Y241264D01*
X938349Y241669D01*
X938261Y241820D01*
X939621Y242606D01*
X939708Y242454D01*
G37*
G36*
G01X936334Y240508D02*
X936366Y239753D01*
X935613Y239318D01*
X934975Y239723D01*
X934887Y239874D01*
X936247Y240660D01*
X936334Y240508D01*
G37*
G36*
G01X932948Y238554D02*
X932980Y237799D01*
X932227Y237364D01*
X931589Y237769D01*
X931501Y237920D01*
X932861Y238706D01*
X932948Y238554D01*
G37*
G36*
G01X929574Y236608D02*
X929606Y235853D01*
X928853Y235418D01*
X928215Y235823D01*
X928127Y235974D01*
X929487Y236760D01*
X929574Y236608D01*
G37*
G36*
G01X945115Y242846D02*
X945753Y243251D01*
X946506Y242816D01*
X946474Y242061D01*
X946387Y241909D01*
X945027Y242695D01*
X945115Y242846D01*
G37*
G36*
G01X916894Y249452D02*
X916256Y249047D01*
X915503Y249482D01*
X915535Y250237D01*
X915622Y250389D01*
X916982Y249604D01*
X916894Y249452D01*
G37*
G36*
G01X919399Y250237D02*
X919431Y249482D01*
X918678Y249047D01*
X918040Y249452D01*
X917952Y249604D01*
X919312Y250389D01*
X919399Y250237D01*
G37*
G36*
G01X923655Y249452D02*
X923017Y249047D01*
X922264Y249482D01*
X922296Y250237D01*
X922383Y250389D01*
X923743Y249604D01*
X923655Y249452D01*
G37*
G36*
G01X926159Y250237D02*
X926191Y249482D01*
X925438Y249047D01*
X924800Y249452D01*
X924712Y249604D01*
X926072Y250389D01*
X926159Y250237D01*
G37*
G36*
G01X929574Y252208D02*
X929606Y251453D01*
X928853Y251018D01*
X928215Y251423D01*
X928127Y251574D01*
X929487Y252360D01*
X929574Y252208D01*
G37*
G36*
G01X932948Y254154D02*
X932980Y253399D01*
X932227Y252964D01*
X931589Y253369D01*
X931501Y253520D01*
X932861Y254306D01*
X932948Y254154D01*
G37*
G36*
G01X936334Y256108D02*
X936366Y255353D01*
X935613Y254918D01*
X934975Y255323D01*
X934887Y255474D01*
X936247Y256260D01*
X936334Y256108D01*
G37*
G36*
G01X939714Y258057D02*
X939746Y257302D01*
X938993Y256867D01*
X938355Y257272D01*
X938267Y257423D01*
X939627Y258209D01*
X939714Y258057D01*
G37*
G36*
G01X943912Y257265D02*
X943274Y256860D01*
X942521Y257295D01*
X942553Y258050D01*
X942640Y258202D01*
X944000Y257416D01*
X943912Y257265D01*
G37*
G36*
G01X947279Y255323D02*
X946641Y254918D01*
X945888Y255353D01*
X945920Y256108D01*
X946007Y256260D01*
X947367Y255474D01*
X947279Y255323D01*
G37*
G36*
G01X932948Y234654D02*
X932980Y233899D01*
X932227Y233464D01*
X931589Y233869D01*
X931501Y234020D01*
X932861Y234806D01*
X932948Y234654D01*
G37*
G36*
G01X929559Y232699D02*
X929591Y231944D01*
X928838Y231509D01*
X928200Y231914D01*
X928112Y232065D01*
X929472Y232850D01*
X929559Y232699D01*
G37*
G36*
G01X926194Y230757D02*
X926226Y230002D01*
X925473Y229567D01*
X924835Y229972D01*
X924747Y230123D01*
X926107Y230908D01*
X926194Y230757D01*
G37*
G36*
G01X917568Y226501D02*
X917858Y225716D01*
X917222Y225080D01*
X916437Y225370D01*
X916313Y225493D01*
X917445Y226625D01*
X917568Y226501D01*
G37*
G36*
G01X923158Y230009D02*
X922808Y229249D01*
X921909D01*
X921559Y230009D01*
X921558Y230184D01*
X923159D01*
X923158Y230009D01*
G37*
G36*
G01X920368Y229301D02*
X920658Y228516D01*
X920022Y227880D01*
X919237Y228170D01*
X919113Y228293D01*
X920245Y229425D01*
X920368Y229301D01*
G37*
G36*
G01X912049Y224160D02*
X911699Y223400D01*
X910799D01*
X910449Y224160D01*
Y224335D01*
X912049D01*
Y224160D01*
G37*
G36*
G01X939708Y238554D02*
X939740Y237799D01*
X938987Y237364D01*
X938349Y237769D01*
X938261Y237920D01*
X939621Y238706D01*
X939708Y238554D01*
G37*
G36*
G01X936334Y236608D02*
X936366Y235853D01*
X935613Y235418D01*
X934975Y235823D01*
X934887Y235974D01*
X936247Y236760D01*
X936334Y236608D01*
G37*
G36*
G01X956614Y224908D02*
X956646Y224153D01*
X955893Y223718D01*
X955255Y224123D01*
X955167Y224274D01*
X956527Y225060D01*
X956614Y224908D01*
G37*
G36*
G01X949854Y221008D02*
X949886Y220253D01*
X949133Y219818D01*
X948495Y220223D01*
X948407Y220374D01*
X949767Y221160D01*
X949854Y221008D01*
G37*
G36*
G01X946468Y219054D02*
X946500Y218299D01*
X945747Y217864D01*
X945109Y218269D01*
X945021Y218420D01*
X946381Y219206D01*
X946468Y219054D01*
G37*
G36*
G01X953234Y222957D02*
X953266Y222202D01*
X952513Y221767D01*
X951875Y222172D01*
X951787Y222323D01*
X953147Y223109D01*
X953234Y222957D01*
G37*
G36*
G01X939708Y234654D02*
X939740Y233899D01*
X938987Y233464D01*
X938349Y233869D01*
X938261Y234020D01*
X939621Y234806D01*
X939708Y234654D01*
G37*
G36*
G01X932954Y230757D02*
X932986Y230002D01*
X932233Y229567D01*
X931595Y229972D01*
X931507Y230123D01*
X932867Y230908D01*
X932954Y230757D01*
G37*
G36*
G01X936319Y232699D02*
X936351Y231944D01*
X935598Y231509D01*
X934960Y231914D01*
X934872Y232065D01*
X936232Y232850D01*
X936319Y232699D01*
G37*
G36*
G01X929574Y228807D02*
X929606Y228052D01*
X928853Y227617D01*
X928215Y228022D01*
X928127Y228173D01*
X929487Y228958D01*
X929574Y228807D01*
G37*
G36*
G01X926194Y226858D02*
X926226Y226103D01*
X925473Y225668D01*
X924835Y226073D01*
X924747Y226224D01*
X926107Y227009D01*
X926194Y226858D01*
G37*
G36*
G01X912088Y220166D02*
X911738Y219406D01*
X910838D01*
X910488Y220166D01*
Y220341D01*
X912088D01*
Y220166D01*
G37*
G36*
G01X919533Y224194D02*
X919823Y223409D01*
X919187Y222773D01*
X918402Y223063D01*
X918278Y223186D01*
X919410Y224318D01*
X919533Y224194D01*
G37*
G36*
G01X950665Y233869D02*
X950027Y233464D01*
X949274Y233899D01*
X949306Y234654D01*
X949393Y234806D01*
X950753Y234020D01*
X950665Y233869D01*
G37*
G36*
G01X943094Y236608D02*
X943126Y235853D01*
X942373Y235418D01*
X941735Y235823D01*
X941647Y235974D01*
X943007Y236760D01*
X943094Y236608D01*
G37*
G36*
G01X947279Y235823D02*
X946641Y235418D01*
X945888Y235853D01*
X945920Y236608D01*
X946007Y236760D01*
X947367Y235974D01*
X947279Y235823D01*
G37*
G36*
G01X966738Y226849D02*
X966770Y226094D01*
X966017Y225659D01*
X965379Y226064D01*
X965291Y226215D01*
X966651Y227000D01*
X966738Y226849D01*
G37*
G36*
G01X963373Y224908D02*
X963405Y224153D01*
X962652Y223718D01*
X962014Y224123D01*
X961926Y224274D01*
X963286Y225060D01*
X963373Y224908D01*
G37*
G36*
G01X959987Y222954D02*
X960019Y222199D01*
X959266Y221764D01*
X958628Y222169D01*
X958540Y222320D01*
X959900Y223106D01*
X959987Y222954D01*
G37*
G36*
G01X953228Y219054D02*
X953260Y218299D01*
X952507Y217864D01*
X951869Y218269D01*
X951781Y218420D01*
X953141Y219206D01*
X953228Y219054D01*
G37*
G36*
G01X956608Y221005D02*
X956640Y220250D01*
X955887Y219815D01*
X955249Y220220D01*
X955161Y220371D01*
X956521Y221157D01*
X956608Y221005D01*
G37*
G36*
G01X916895Y253352D02*
X916257Y252947D01*
X915504Y253382D01*
X915536Y254137D01*
X915623Y254289D01*
X916983Y253504D01*
X916895Y253352D01*
G37*
G36*
G01X919399Y254137D02*
X919431Y253382D01*
X918678Y252947D01*
X918040Y253352D01*
X917952Y253504D01*
X919312Y254289D01*
X919399Y254137D01*
G37*
G36*
G01X923655Y253352D02*
X923017Y252947D01*
X922264Y253382D01*
X922296Y254137D01*
X922383Y254289D01*
X923743Y253504D01*
X923655Y253352D01*
G37*
G36*
G01X926159Y254137D02*
X926191Y253382D01*
X925438Y252947D01*
X924800Y253352D01*
X924712Y253504D01*
X926072Y254289D01*
X926159Y254137D01*
G37*
G36*
G01X929568Y256105D02*
X929600Y255350D01*
X928847Y254915D01*
X928209Y255320D01*
X928121Y255471D01*
X929481Y256256D01*
X929568Y256105D01*
G37*
G36*
G01X936328Y260005D02*
X936360Y259250D01*
X935607Y258815D01*
X934969Y259220D01*
X934881Y259371D01*
X936241Y260156D01*
X936328Y260005D01*
G37*
G36*
G01X932948Y258054D02*
X932980Y257299D01*
X932227Y256864D01*
X931589Y257269D01*
X931501Y257420D01*
X932861Y258205D01*
X932948Y258054D01*
G37*
G36*
G01X939708Y261954D02*
X939740Y261199D01*
X938987Y260764D01*
X938349Y261169D01*
X938261Y261320D01*
X939621Y262105D01*
X939708Y261954D01*
G37*
G36*
G01X912648Y255360D02*
X912298Y254600D01*
X911398D01*
X911048Y255360D01*
Y255535D01*
X912648D01*
Y255360D01*
G37*
G36*
G01X939196Y259632D02*
X939164Y260387D01*
X939917Y260822D01*
X940555Y260417D01*
X940643Y260266D01*
X939283Y259480D01*
X939196Y259632D01*
G37*
G36*
G01X914682Y252604D02*
X915320Y253009D01*
X916073Y252574D01*
X916041Y251819D01*
X915954Y251667D01*
X914594Y252452D01*
X914682Y252604D01*
G37*
G36*
G01X918915Y251832D02*
X918883Y252587D01*
X919636Y253022D01*
X920274Y252617D01*
X920362Y252466D01*
X919002Y251680D01*
X918915Y251832D01*
G37*
G36*
G01X921420Y252617D02*
X922058Y253022D01*
X922811Y252587D01*
X922779Y251832D01*
X922692Y251680D01*
X921332Y252466D01*
X921420Y252617D01*
G37*
G36*
G01X929020Y253761D02*
X928988Y254516D01*
X929741Y254951D01*
X930379Y254546D01*
X930467Y254395D01*
X929107Y253609D01*
X929020Y253761D01*
G37*
G36*
G01X932406Y255715D02*
X932374Y256470D01*
X933127Y256905D01*
X933765Y256500D01*
X933853Y256348D01*
X932493Y255563D01*
X932406Y255715D01*
G37*
G36*
G01X935780Y257661D02*
X935748Y258416D01*
X936501Y258851D01*
X937139Y258446D01*
X937227Y258295D01*
X935867Y257509D01*
X935780Y257661D01*
G37*
G36*
G01X941699Y260417D02*
X942337Y260822D01*
X943090Y260387D01*
X943058Y259632D01*
X942971Y259480D01*
X941611Y260266D01*
X941699Y260417D01*
G37*
G36*
G01X945115Y258446D02*
X945753Y258851D01*
X946506Y258416D01*
X946474Y257661D01*
X946387Y257509D01*
X945027Y258295D01*
X945115Y258446D01*
G37*
G36*
G01X948489Y256500D02*
X949127Y256905D01*
X949880Y256470D01*
X949848Y255715D01*
X949761Y255563D01*
X948401Y256348D01*
X948489Y256500D01*
G37*
G36*
G01X929020Y234261D02*
X928988Y235016D01*
X929741Y235451D01*
X930379Y235046D01*
X930467Y234895D01*
X929107Y234109D01*
X929020Y234261D01*
G37*
G36*
G01X925655Y232320D02*
X925623Y233075D01*
X926376Y233510D01*
X927014Y233105D01*
X927102Y232954D01*
X925742Y232168D01*
X925655Y232320D01*
G37*
G36*
G01X921689Y231109D02*
X922039Y231869D01*
X922939D01*
X923289Y231109D01*
Y230934D01*
X921689D01*
Y231109D01*
G37*
G36*
G01X915659Y226148D02*
X915369Y226932D01*
X916006Y227569D01*
X916790Y227279D01*
X916914Y227155D01*
X915783Y226024D01*
X915659Y226148D01*
G37*
G36*
G01X918459Y228948D02*
X918169Y229732D01*
X918806Y230369D01*
X919590Y230079D01*
X919714Y229955D01*
X918583Y228824D01*
X918459Y228948D01*
G37*
G36*
G01X910449Y225260D02*
X910799Y226020D01*
X911699D01*
X912049Y225260D01*
Y225085D01*
X910449D01*
Y225260D01*
G37*
G36*
G01X939166Y240115D02*
X939134Y240870D01*
X939887Y241305D01*
X940525Y240900D01*
X940613Y240748D01*
X939253Y239963D01*
X939166Y240115D01*
G37*
G36*
G01X935780Y238161D02*
X935748Y238916D01*
X936501Y239351D01*
X937139Y238946D01*
X937227Y238795D01*
X935867Y238009D01*
X935780Y238161D01*
G37*
G36*
G01X932400Y236212D02*
X932368Y236967D01*
X933121Y237402D01*
X933759Y236997D01*
X933847Y236846D01*
X932487Y236060D01*
X932400Y236212D01*
G37*
G36*
G01X956108Y226489D02*
X956076Y227244D01*
X956829Y227679D01*
X957467Y227274D01*
X957555Y227123D01*
X956195Y226338D01*
X956108Y226489D01*
G37*
G36*
G01X945926Y220615D02*
X945894Y221370D01*
X946647Y221805D01*
X947285Y221400D01*
X947373Y221249D01*
X946013Y220463D01*
X945926Y220615D01*
G37*
G36*
G01X949306Y222564D02*
X949274Y223319D01*
X950027Y223754D01*
X950665Y223349D01*
X950753Y223198D01*
X949393Y222412D01*
X949306Y222564D01*
G37*
G36*
G01X952686Y224515D02*
X952654Y225270D01*
X953407Y225705D01*
X954045Y225300D01*
X954133Y225149D01*
X952773Y224363D01*
X952686Y224515D01*
G37*
G36*
G01X942546Y218664D02*
X942514Y219419D01*
X943267Y219854D01*
X943905Y219449D01*
X943993Y219298D01*
X942633Y218512D01*
X942546Y218664D01*
G37*
G36*
G01X935780Y234261D02*
X935748Y235016D01*
X936501Y235451D01*
X937139Y235046D01*
X937227Y234895D01*
X935867Y234109D01*
X935780Y234261D01*
G37*
G36*
G01X932415Y232320D02*
X932383Y233075D01*
X933136Y233510D01*
X933774Y233105D01*
X933862Y232954D01*
X932502Y232168D01*
X932415Y232320D01*
G37*
G36*
G01X929020Y230362D02*
X928988Y231117D01*
X929741Y231552D01*
X930379Y231147D01*
X930467Y230996D01*
X929107Y230210D01*
X929020Y230362D01*
G37*
G36*
G01X925640Y228412D02*
X925608Y229167D01*
X926361Y229602D01*
X926999Y229197D01*
X927087Y229046D01*
X925727Y228260D01*
X925640Y228412D01*
G37*
G36*
G01X910488Y221266D02*
X910838Y222026D01*
X911738D01*
X912088Y221266D01*
Y221091D01*
X910488D01*
Y221266D01*
G37*
G36*
G01X917624Y223841D02*
X917334Y224625D01*
X917971Y225262D01*
X918755Y224972D01*
X918879Y224848D01*
X917748Y223717D01*
X917624Y223841D01*
G37*
G36*
G01X939160Y236212D02*
X939128Y236967D01*
X939881Y237402D01*
X940519Y236997D01*
X940607Y236846D01*
X939247Y236060D01*
X939160Y236212D01*
G37*
G36*
G01X942540Y238161D02*
X942508Y238916D01*
X943261Y239351D01*
X943899Y238946D01*
X943987Y238795D01*
X942627Y238009D01*
X942540Y238161D01*
G37*
G36*
G01X945115Y238946D02*
X945753Y239351D01*
X946506Y238916D01*
X946474Y238161D01*
X946387Y238009D01*
X945027Y238795D01*
X945115Y238946D01*
G37*
G36*
G01X948489Y237000D02*
X949127Y237405D01*
X949880Y236970D01*
X949848Y236215D01*
X949761Y236063D01*
X948401Y236848D01*
X948489Y237000D01*
G37*
G36*
G01X966199Y228412D02*
X966167Y229167D01*
X966920Y229602D01*
X967558Y229197D01*
X967646Y229046D01*
X966286Y228260D01*
X966199Y228412D01*
G37*
G36*
G01X962834Y226470D02*
X962802Y227225D01*
X963555Y227660D01*
X964193Y227255D01*
X964281Y227104D01*
X962921Y226318D01*
X962834Y226470D01*
G37*
G36*
G01X959445Y224515D02*
X959413Y225270D01*
X960166Y225705D01*
X960804Y225300D01*
X960892Y225148D01*
X959532Y224363D01*
X959445Y224515D01*
G37*
G36*
G01X956065Y222564D02*
X956033Y223319D01*
X956786Y223754D01*
X957424Y223349D01*
X957512Y223197D01*
X956152Y222412D01*
X956065Y222564D01*
G37*
G36*
G01X949300Y218661D02*
X949268Y219416D01*
X950021Y219851D01*
X950659Y219446D01*
X950747Y219295D01*
X949387Y218509D01*
X949300Y218661D01*
G37*
G36*
G01X952680Y220612D02*
X952648Y221367D01*
X953401Y221802D01*
X954039Y221397D01*
X954127Y221246D01*
X952767Y220460D01*
X952680Y220612D01*
G37*
G36*
G01X939196Y263532D02*
X939164Y264287D01*
X939917Y264722D01*
X940555Y264317D01*
X940643Y264166D01*
X939283Y263380D01*
X939196Y263532D01*
G37*
G36*
G01X914682Y256504D02*
X915320Y256909D01*
X916073Y256474D01*
X916041Y255719D01*
X915954Y255567D01*
X914594Y256352D01*
X914682Y256504D01*
G37*
G36*
G01X918915Y255732D02*
X918883Y256487D01*
X919636Y256922D01*
X920274Y256517D01*
X920362Y256366D01*
X919002Y255580D01*
X918915Y255732D01*
G37*
G36*
G01X921420Y256517D02*
X922058Y256922D01*
X922811Y256487D01*
X922779Y255732D01*
X922692Y255580D01*
X921332Y256366D01*
X921420Y256517D01*
G37*
G36*
G01X929020Y257661D02*
X928988Y258416D01*
X929741Y258851D01*
X930379Y258446D01*
X930467Y258295D01*
X929107Y257509D01*
X929020Y257661D01*
G37*
G36*
G01X932406Y259615D02*
X932374Y260370D01*
X933127Y260805D01*
X933765Y260400D01*
X933853Y260248D01*
X932493Y259463D01*
X932406Y259615D01*
G37*
G36*
G01X935780Y261561D02*
X935748Y262316D01*
X936501Y262751D01*
X937139Y262346D01*
X937227Y262194D01*
X935867Y261409D01*
X935780Y261561D01*
G37*
G36*
G01X925640Y255712D02*
X925608Y256467D01*
X926361Y256902D01*
X926999Y256497D01*
X927087Y256346D01*
X925727Y255560D01*
X925640Y255712D01*
G37*
G36*
G01X911048Y256460D02*
X911398Y257220D01*
X912298D01*
X912648Y256460D01*
Y256285D01*
X911048D01*
Y256460D01*
G37*
G36*
G01X941699Y264317D02*
X942337Y264722D01*
X943090Y264287D01*
X943058Y263532D01*
X942971Y263380D01*
X941611Y264166D01*
X941699Y264317D01*
G37*
G36*
G01X930385Y335269D02*
X929747Y334864D01*
X928994Y335299D01*
X929026Y336054D01*
X929113Y336205D01*
X930473Y335420D01*
X930385Y335269D01*
G37*
G36*
G01X926999Y337223D02*
X926361Y336818D01*
X925608Y337253D01*
X925640Y338008D01*
X925727Y338160D01*
X927087Y337375D01*
X926999Y337223D01*
G37*
G36*
G01X923625Y339169D02*
X922987Y338764D01*
X922234Y339199D01*
X922266Y339954D01*
X922353Y340105D01*
X923713Y339320D01*
X923625Y339169D01*
G37*
G36*
G01X920239Y341123D02*
X919601Y340718D01*
X918848Y341153D01*
X918880Y341908D01*
X918967Y342060D01*
X920327Y341275D01*
X920239Y341123D01*
G37*
G36*
G01X933759Y333323D02*
X933121Y332918D01*
X932368Y333353D01*
X932400Y334108D01*
X932487Y334260D01*
X933847Y333475D01*
X933759Y333323D01*
G37*
G36*
G01X949854Y334108D02*
X949886Y333353D01*
X949133Y332918D01*
X948495Y333323D01*
X948407Y333475D01*
X949767Y334260D01*
X949854Y334108D01*
G37*
G36*
G01X937145Y331369D02*
X936507Y330964D01*
X935754Y331399D01*
X935786Y332154D01*
X935873Y332305D01*
X937233Y331520D01*
X937145Y331369D01*
G37*
G36*
G01X940519Y329423D02*
X939881Y329018D01*
X939128Y329453D01*
X939160Y330208D01*
X939247Y330360D01*
X940607Y329575D01*
X940519Y329423D01*
G37*
G36*
G01X946468Y332154D02*
X946500Y331399D01*
X945747Y330964D01*
X945109Y331369D01*
X945021Y331520D01*
X946381Y332305D01*
X946468Y332154D01*
G37*
G36*
G01X943094Y330208D02*
X943126Y329453D01*
X942373Y329018D01*
X941735Y329423D01*
X941647Y329575D01*
X943007Y330360D01*
X943094Y330208D01*
G37*
G36*
G01X931595Y336446D02*
X932233Y336851D01*
X932986Y336416D01*
X932954Y335661D01*
X932867Y335509D01*
X931507Y336295D01*
X931595Y336446D01*
G37*
G36*
G01X928209Y338400D02*
X928847Y338805D01*
X929600Y338370D01*
X929568Y337615D01*
X929481Y337463D01*
X928121Y338249D01*
X928209Y338400D01*
G37*
G36*
G01X924835Y340346D02*
X925473Y340751D01*
X926226Y340316D01*
X926194Y339561D01*
X926107Y339409D01*
X924747Y340195D01*
X924835Y340346D01*
G37*
G36*
G01X934969Y334500D02*
X935607Y334905D01*
X936360Y334470D01*
X936328Y333715D01*
X936241Y333563D01*
X934881Y334349D01*
X934969Y334500D01*
G37*
G36*
G01X938355Y332546D02*
X938993Y332951D01*
X939746Y332516D01*
X939714Y331761D01*
X939627Y331609D01*
X938267Y332395D01*
X938355Y332546D01*
G37*
G36*
G01X942540Y331761D02*
X942508Y332516D01*
X943261Y332951D01*
X943899Y332546D01*
X943987Y332395D01*
X942627Y331609D01*
X942540Y331761D01*
G37*
G36*
G01X912290Y339106D02*
X912515Y338385D01*
X911900Y337771D01*
X911179Y337997D01*
X911055Y338121D01*
X912167Y339230D01*
X912290Y339106D01*
G37*
G36*
G01X923625Y335269D02*
X922987Y334864D01*
X922234Y335299D01*
X922266Y336054D01*
X922353Y336205D01*
X923713Y335420D01*
X923625Y335269D01*
G37*
G36*
G01X920239Y337223D02*
X919601Y336818D01*
X918848Y337253D01*
X918880Y338008D01*
X918967Y338160D01*
X920327Y337375D01*
X920239Y337223D01*
G37*
G36*
G01X916865Y339169D02*
X916227Y338764D01*
X915474Y339199D01*
X915506Y339954D01*
X915593Y340105D01*
X916953Y339320D01*
X916865Y339169D01*
G37*
G36*
G01X926999Y333323D02*
X926361Y332918D01*
X925608Y333353D01*
X925640Y334108D01*
X925727Y334260D01*
X927087Y333475D01*
X926999Y333323D01*
G37*
G36*
G01X930385Y331369D02*
X929747Y330964D01*
X928994Y331399D01*
X929026Y332154D01*
X929113Y332305D01*
X930473Y331520D01*
X930385Y331369D01*
G37*
G36*
G01X937145Y327469D02*
X936507Y327064D01*
X935754Y327499D01*
X935786Y328254D01*
X935873Y328405D01*
X937233Y327620D01*
X937145Y327469D01*
G37*
G36*
G01X933759Y329423D02*
X933121Y329018D01*
X932368Y329453D01*
X932400Y330208D01*
X932487Y330360D01*
X933847Y329575D01*
X933759Y329423D01*
G37*
G36*
G01X946468Y328254D02*
X946500Y327499D01*
X945747Y327064D01*
X945109Y327469D01*
X945021Y327620D01*
X946381Y328405D01*
X946468Y328254D01*
G37*
G36*
G01X953228Y332154D02*
X953260Y331399D01*
X952507Y330964D01*
X951869Y331369D01*
X951781Y331520D01*
X953141Y332305D01*
X953228Y332154D01*
G37*
G36*
G01X949854Y330208D02*
X949886Y329453D01*
X949133Y329018D01*
X948495Y329423D01*
X948407Y329575D01*
X949767Y330360D01*
X949854Y330208D01*
G37*
G36*
G01X940519Y325523D02*
X939881Y325118D01*
X939128Y325553D01*
X939160Y326308D01*
X939247Y326460D01*
X940607Y325675D01*
X940519Y325523D01*
G37*
G36*
G01X943094Y326308D02*
X943126Y325553D01*
X942373Y325118D01*
X941735Y325523D01*
X941647Y325675D01*
X943007Y326460D01*
X943094Y326308D01*
G37*
G36*
G01X911518Y341077D02*
X911295Y341799D01*
X911913Y342411D01*
X912633Y342181D01*
X912757Y342057D01*
X911640Y340953D01*
X911518Y341077D01*
G37*
G36*
G01X924835Y336446D02*
X925473Y336851D01*
X926226Y336416D01*
X926194Y335661D01*
X926107Y335509D01*
X924747Y336295D01*
X924835Y336446D01*
G37*
G36*
G01X921449Y338400D02*
X922087Y338805D01*
X922840Y338370D01*
X922808Y337615D01*
X922721Y337463D01*
X921361Y338249D01*
X921449Y338400D01*
G37*
G36*
G01X918075Y340346D02*
X918713Y340751D01*
X919466Y340316D01*
X919434Y339561D01*
X919347Y339409D01*
X917987Y340195D01*
X918075Y340346D01*
G37*
G36*
G01X928209Y334500D02*
X928847Y334905D01*
X929600Y334470D01*
X929568Y333715D01*
X929481Y333563D01*
X928121Y334349D01*
X928209Y334500D01*
G37*
G36*
G01X931595Y332546D02*
X932233Y332951D01*
X932986Y332516D01*
X932954Y331761D01*
X932867Y331609D01*
X931507Y332395D01*
X931595Y332546D01*
G37*
G36*
G01X938355Y328647D02*
X938993Y329052D01*
X939746Y328617D01*
X939714Y327862D01*
X939627Y327711D01*
X938267Y328495D01*
X938355Y328647D01*
G37*
G36*
G01X934969Y330600D02*
X935607Y331005D01*
X936360Y330570D01*
X936328Y329815D01*
X936241Y329663D01*
X934881Y330449D01*
X934969Y330600D01*
G37*
G36*
G01X942540Y327862D02*
X942508Y328617D01*
X943261Y329052D01*
X943899Y328647D01*
X943987Y328495D01*
X942627Y327711D01*
X942540Y327862D01*
G37*
G36*
G01X945926Y329815D02*
X945894Y330570D01*
X946647Y331005D01*
X947285Y330600D01*
X947373Y330449D01*
X946013Y329663D01*
X945926Y329815D01*
G37*
G36*
G01X940519Y341123D02*
X939881Y340718D01*
X939128Y341153D01*
X939160Y341908D01*
X939247Y342060D01*
X940607Y341275D01*
X940519Y341123D01*
G37*
G36*
G01X949854Y341908D02*
X949886Y341153D01*
X949133Y340718D01*
X948495Y341123D01*
X948407Y341275D01*
X949767Y342060D01*
X949854Y341908D01*
G37*
G36*
G01X940519Y337223D02*
X939881Y336818D01*
X939128Y337253D01*
X939160Y338008D01*
X939247Y338160D01*
X940607Y337375D01*
X940519Y337223D01*
G37*
G36*
G01X937145Y339169D02*
X936507Y338764D01*
X935754Y339199D01*
X935786Y339954D01*
X935873Y340105D01*
X937233Y339320D01*
X937145Y339169D01*
G37*
G36*
G01X933759Y341123D02*
X933121Y340718D01*
X932368Y341153D01*
X932400Y341908D01*
X932487Y342060D01*
X933847Y341275D01*
X933759Y341123D01*
G37*
G36*
G01X931595Y340346D02*
X932233Y340751D01*
X932986Y340316D01*
X932954Y339561D01*
X932867Y339409D01*
X931507Y340195D01*
X931595Y340346D01*
G37*
G36*
G01X938355Y336446D02*
X938993Y336851D01*
X939746Y336416D01*
X939714Y335661D01*
X939627Y335509D01*
X938267Y336295D01*
X938355Y336446D01*
G37*
G36*
G01X934969Y338400D02*
X935607Y338805D01*
X936360Y338370D01*
X936328Y337615D01*
X936241Y337463D01*
X934881Y338249D01*
X934969Y338400D01*
G37*
G36*
G01X949300Y339561D02*
X949268Y340316D01*
X950021Y340751D01*
X950659Y340346D01*
X950747Y340195D01*
X949387Y339409D01*
X949300Y339561D01*
G37*
G36*
G01X945926Y337615D02*
X945894Y338370D01*
X946647Y338805D01*
X947285Y338400D01*
X947373Y338249D01*
X946013Y337463D01*
X945926Y337615D01*
G37*
G36*
G01X942540Y335661D02*
X942508Y336416D01*
X943261Y336851D01*
X943899Y336446D01*
X943987Y336295D01*
X942627Y335509D01*
X942540Y335661D01*
G37*
G36*
G01X938355Y340346D02*
X938993Y340751D01*
X939746Y340316D01*
X939714Y339561D01*
X939627Y339409D01*
X938267Y340195D01*
X938355Y340346D01*
G37*
G36*
G01X930385Y339169D02*
X929747Y338764D01*
X928994Y339199D01*
X929026Y339954D01*
X929113Y340105D01*
X930473Y339320D01*
X930385Y339169D01*
G37*
G36*
G01X926999Y341123D02*
X926361Y340718D01*
X925608Y341153D01*
X925640Y341908D01*
X925727Y342060D01*
X927087Y341275D01*
X926999Y341123D01*
G37*
G36*
G01X937145Y335269D02*
X936507Y334864D01*
X935754Y335299D01*
X935786Y336054D01*
X935873Y336205D01*
X937233Y335420D01*
X937145Y335269D01*
G37*
G36*
G01X933759Y337223D02*
X933121Y336818D01*
X932368Y337253D01*
X932400Y338008D01*
X932487Y338160D01*
X933847Y337375D01*
X933759Y337223D01*
G37*
G36*
G01X949854Y338008D02*
X949886Y337253D01*
X949133Y336818D01*
X948495Y337223D01*
X948407Y337375D01*
X949767Y338160D01*
X949854Y338008D01*
G37*
G36*
G01X946468Y336054D02*
X946500Y335299D01*
X945747Y334864D01*
X945109Y335269D01*
X945021Y335420D01*
X946381Y336205D01*
X946468Y336054D01*
G37*
G36*
G01X953160Y339933D02*
X953191Y339178D01*
X952438Y338743D01*
X951800Y339148D01*
X951713Y339299D01*
X953073Y340085D01*
X953160Y339933D01*
G37*
G36*
G01X940519Y333323D02*
X939881Y332918D01*
X939128Y333353D01*
X939160Y334108D01*
X939247Y334260D01*
X940607Y333475D01*
X940519Y333323D01*
G37*
G36*
G01X943094Y334108D02*
X943126Y333353D01*
X942373Y332918D01*
X941735Y333323D01*
X941647Y333475D01*
X943007Y334260D01*
X943094Y334108D01*
G37*
G36*
G01X912144Y344814D02*
X912434Y344029D01*
X911797Y343393D01*
X911012Y343683D01*
X910889Y343807D01*
X912020Y344938D01*
X912144Y344814D01*
G37*
G36*
G01X916865Y343069D02*
X916227Y342664D01*
X915474Y343099D01*
X915506Y343854D01*
X915593Y344005D01*
X916953Y343220D01*
X916865Y343069D01*
G37*
G36*
G01X920209Y379988D02*
X919571Y379583D01*
X918818Y380017D01*
X918849Y380772D01*
X918936Y380924D01*
X920297Y380139D01*
X920209Y379988D01*
G37*
G36*
G01X918345Y389675D02*
X917675Y390025D01*
Y390895D01*
X918345Y391245D01*
X918520D01*
Y389675D01*
X918345D01*
G37*
G36*
G01Y385750D02*
X917675Y386100D01*
Y386970D01*
X918345Y387320D01*
X918520D01*
Y385750D01*
X918345D01*
G37*
G36*
G01X930385Y374269D02*
X929747Y373864D01*
X928994Y374299D01*
X929026Y375054D01*
X929113Y375205D01*
X930473Y374420D01*
X930385Y374269D01*
G37*
G36*
G01X926999Y376223D02*
X926361Y375818D01*
X925608Y376253D01*
X925640Y377008D01*
X925727Y377160D01*
X927087Y376375D01*
X926999Y376223D01*
G37*
G36*
G01X922821Y378667D02*
X922100Y378441D01*
X921485Y379056D01*
X921712Y379777D01*
X921835Y379901D01*
X922945Y378790D01*
X922821Y378667D01*
G37*
G36*
G01X940525Y368419D02*
X939887Y368014D01*
X939134Y368449D01*
X939166Y369204D01*
X939253Y369355D01*
X940613Y368570D01*
X940525Y368419D01*
G37*
G36*
G01X937139Y370372D02*
X936501Y369967D01*
X935748Y370402D01*
X935780Y371157D01*
X935867Y371309D01*
X937227Y370523D01*
X937139Y370372D01*
G37*
G36*
G01X933774Y372314D02*
X933136Y371909D01*
X932383Y372344D01*
X932415Y373099D01*
X932502Y373251D01*
X933862Y372465D01*
X933774Y372314D01*
G37*
G36*
G01X914810Y393965D02*
X914460Y393205D01*
X913560D01*
X913210Y393965D01*
Y394140D01*
X914810D01*
Y393965D01*
G37*
G36*
G01X947279Y364523D02*
X946641Y364118D01*
X945888Y364553D01*
X945920Y365308D01*
X946007Y365460D01*
X947367Y364675D01*
X947279Y364523D01*
G37*
G36*
G01X943914Y366464D02*
X943276Y366059D01*
X942523Y366494D01*
X942555Y367249D01*
X942642Y367401D01*
X944002Y366615D01*
X943914Y366464D01*
G37*
G36*
G01X918345Y381850D02*
X917675Y382200D01*
Y383070D01*
X918345Y383420D01*
X918520D01*
Y381850D01*
X918345D01*
G37*
G36*
G01X919969Y389319D02*
X920639Y388969D01*
Y388099D01*
X919969Y387749D01*
X919794D01*
Y389319D01*
X919969D01*
G37*
G36*
G01X921449Y381300D02*
X922087Y381705D01*
X922840Y381270D01*
X922808Y380515D01*
X922721Y380363D01*
X921361Y381149D01*
X921449Y381300D01*
G37*
G36*
G01X919969Y385419D02*
X920639Y385069D01*
Y384199D01*
X919969Y383849D01*
X919794D01*
Y385419D01*
X919969D01*
G37*
G36*
G01X931595Y375446D02*
X932233Y375851D01*
X932986Y375416D01*
X932954Y374661D01*
X932867Y374509D01*
X931507Y375295D01*
X931595Y375446D01*
G37*
G36*
G01X928209Y377400D02*
X928847Y377805D01*
X929600Y377370D01*
X929568Y376615D01*
X929481Y376463D01*
X928121Y377249D01*
X928209Y377400D01*
G37*
G36*
G01X924835Y379346D02*
X925473Y379751D01*
X926226Y379316D01*
X926194Y378561D01*
X926107Y378409D01*
X924747Y379195D01*
X924835Y379346D01*
G37*
G36*
G01X938349Y371550D02*
X938987Y371955D01*
X939740Y371520D01*
X939708Y370765D01*
X939621Y370613D01*
X938261Y371399D01*
X938349Y371550D01*
G37*
G36*
G01X934960Y373505D02*
X935598Y373910D01*
X936351Y373475D01*
X936319Y372720D01*
X936232Y372568D01*
X934872Y373353D01*
X934960Y373505D01*
G37*
G36*
G01X919969Y393170D02*
X920639Y392820D01*
Y391950D01*
X919969Y391600D01*
X919794D01*
Y393170D01*
X919969D01*
G37*
G36*
G01X913210Y395063D02*
X913560Y395823D01*
X914460D01*
X914810Y395063D01*
Y394888D01*
X913210D01*
Y395063D01*
G37*
G36*
G01X941735Y369597D02*
X942373Y370002D01*
X943126Y369567D01*
X943094Y368812D01*
X943007Y368661D01*
X941647Y369445D01*
X941735Y369597D01*
G37*
G36*
G01X930385Y354769D02*
X929747Y354364D01*
X928994Y354799D01*
X929026Y355554D01*
X929113Y355705D01*
X930473Y354920D01*
X930385Y354769D01*
G37*
G36*
G01X926999Y356723D02*
X926361Y356318D01*
X925608Y356753D01*
X925640Y357508D01*
X925727Y357660D01*
X927087Y356875D01*
X926999Y356723D01*
G37*
G36*
G01X937145Y350869D02*
X936507Y350464D01*
X935754Y350899D01*
X935786Y351654D01*
X935873Y351805D01*
X937233Y351020D01*
X937145Y350869D01*
G37*
G36*
G01X933759Y352823D02*
X933121Y352418D01*
X932368Y352853D01*
X932400Y353608D01*
X932487Y353760D01*
X933847Y352975D01*
X933759Y352823D01*
G37*
G36*
G01X912779Y363571D02*
X911994Y363281D01*
X911358Y363917D01*
X911648Y364702D01*
X911771Y364826D01*
X912903Y363694D01*
X912779Y363571D01*
G37*
G36*
G01X916534Y362966D02*
X916184Y362206D01*
X915284D01*
X914934Y362966D01*
Y363141D01*
X916534D01*
Y362966D01*
G37*
G36*
G01X920476Y360273D02*
X919692Y359983D01*
X919055Y360620D01*
X919345Y361404D01*
X919469Y361528D01*
X920600Y360397D01*
X920476Y360273D01*
G37*
G36*
G01X953228Y351654D02*
X953260Y350899D01*
X952507Y350464D01*
X951869Y350869D01*
X951781Y351020D01*
X953141Y351805D01*
X953228Y351654D01*
G37*
G36*
G01X940519Y348923D02*
X939881Y348518D01*
X939128Y348953D01*
X939160Y349708D01*
X939247Y349860D01*
X940607Y349075D01*
X940519Y348923D01*
G37*
G36*
G01X949854Y349708D02*
X949886Y348953D01*
X949133Y348518D01*
X948495Y348923D01*
X948407Y349075D01*
X949767Y349860D01*
X949854Y349708D01*
G37*
G36*
G01X946468Y347754D02*
X946500Y346999D01*
X945747Y346564D01*
X945109Y346969D01*
X945021Y347120D01*
X946381Y347905D01*
X946468Y347754D01*
G37*
G36*
G01X943905Y346969D02*
X943267Y346564D01*
X942514Y346999D01*
X942546Y347754D01*
X942633Y347905D01*
X943993Y347120D01*
X943905Y346969D01*
G37*
G36*
G01X931595Y355946D02*
X932233Y356351D01*
X932986Y355916D01*
X932954Y355161D01*
X932867Y355009D01*
X931507Y355795D01*
X931595Y355946D01*
G37*
G36*
G01X928209Y357900D02*
X928847Y358305D01*
X929600Y357870D01*
X929568Y357115D01*
X929481Y356963D01*
X928121Y357749D01*
X928209Y357900D01*
G37*
G36*
G01X934969Y354000D02*
X935607Y354405D01*
X936360Y353970D01*
X936328Y353215D01*
X936241Y353063D01*
X934881Y353849D01*
X934969Y354000D01*
G37*
G36*
G01X938355Y352046D02*
X938993Y352451D01*
X939746Y352016D01*
X939714Y351261D01*
X939627Y351109D01*
X938267Y351895D01*
X938355Y352046D01*
G37*
G36*
G01X912424Y365478D02*
X913209Y365768D01*
X913845Y365132D01*
X913555Y364347D01*
X913432Y364223D01*
X912300Y365355D01*
X912424Y365478D01*
G37*
G36*
G01X914934Y364064D02*
X915284Y364824D01*
X916184D01*
X916534Y364064D01*
Y363889D01*
X914934D01*
Y364064D01*
G37*
G36*
G01X924835Y359846D02*
X925473Y360251D01*
X926226Y359816D01*
X926194Y359061D01*
X926107Y358909D01*
X924747Y359695D01*
X924835Y359846D01*
G37*
G36*
G01X920123Y362182D02*
X920908Y362472D01*
X921544Y361836D01*
X921254Y361051D01*
X921131Y360927D01*
X919999Y362059D01*
X920123Y362182D01*
G37*
G36*
G01X945926Y349315D02*
X945894Y350070D01*
X946647Y350505D01*
X947285Y350100D01*
X947373Y349949D01*
X946013Y349163D01*
X945926Y349315D01*
G37*
G36*
G01X941729Y350100D02*
X942367Y350505D01*
X943120Y350070D01*
X943088Y349315D01*
X943001Y349163D01*
X941641Y349949D01*
X941729Y350100D01*
G37*
G36*
G01X912746Y388566D02*
X912396Y387806D01*
X911496D01*
X911146Y388566D01*
Y388741D01*
X912746D01*
Y388566D01*
G37*
G36*
G01X921597Y376014D02*
X920812Y375724D01*
X920176Y376360D01*
X920466Y377145D01*
X920589Y377269D01*
X921721Y376137D01*
X921597Y376014D01*
G37*
G36*
G01X918796Y377266D02*
X918446Y376506D01*
X917546D01*
X917196Y377266D01*
Y377441D01*
X918796D01*
Y377266D01*
G37*
G36*
G01X914381Y385751D02*
X913621Y386101D01*
Y387001D01*
X914381Y387351D01*
X914556D01*
Y385751D01*
X914381D01*
G37*
G36*
G01Y381851D02*
X913621Y382201D01*
Y383101D01*
X914381Y383451D01*
X914556D01*
Y381851D01*
X914381D01*
G37*
G36*
G01X915848Y378002D02*
X915063Y377712D01*
X914427Y378348D01*
X914717Y379133D01*
X914840Y379257D01*
X915972Y378125D01*
X915848Y378002D01*
G37*
G36*
G01X930379Y370372D02*
X929741Y369967D01*
X928988Y370402D01*
X929020Y371157D01*
X929107Y371309D01*
X930467Y370523D01*
X930379Y370372D01*
G37*
G36*
G01X927014Y372314D02*
X926376Y371909D01*
X925623Y372344D01*
X925655Y373099D01*
X925742Y373251D01*
X927102Y372465D01*
X927014Y372314D01*
G37*
G36*
G01X923619Y374272D02*
X922981Y373867D01*
X922228Y374302D01*
X922260Y375057D01*
X922347Y375209D01*
X923707Y374423D01*
X923619Y374272D01*
G37*
G36*
G01X940519Y364523D02*
X939881Y364118D01*
X939128Y364553D01*
X939160Y365308D01*
X939247Y365460D01*
X940607Y364675D01*
X940519Y364523D01*
G37*
G36*
G01X937154Y366464D02*
X936516Y366059D01*
X935763Y366494D01*
X935795Y367249D01*
X935882Y367401D01*
X937242Y366615D01*
X937154Y366464D01*
G37*
G36*
G01X933765Y368419D02*
X933127Y368014D01*
X932374Y368449D01*
X932406Y369204D01*
X932493Y369355D01*
X933853Y368570D01*
X933765Y368419D01*
G37*
G36*
G01X917996Y378364D02*
X918346Y379124D01*
X919246D01*
X919596Y378364D01*
Y378189D01*
X917996D01*
Y378364D01*
G37*
G36*
G01X915479Y387351D02*
X916239Y387001D01*
Y386101D01*
X915479Y385751D01*
X915304D01*
Y387351D01*
X915479D01*
G37*
G36*
G01Y383451D02*
X916239Y383101D01*
Y382201D01*
X915479Y381851D01*
X915304D01*
Y383451D01*
X915479D01*
G37*
G36*
G01X931589Y371550D02*
X932227Y371955D01*
X932980Y371520D01*
X932948Y370765D01*
X932861Y370613D01*
X931501Y371399D01*
X931589Y371550D01*
G37*
G36*
G01X928200Y373505D02*
X928838Y373910D01*
X929591Y373475D01*
X929559Y372720D01*
X929472Y372568D01*
X928112Y373353D01*
X928200Y373505D01*
G37*
G36*
G01X924829Y375450D02*
X925467Y375855D01*
X926220Y375420D01*
X926188Y374665D01*
X926101Y374513D01*
X924741Y375299D01*
X924829Y375450D01*
G37*
G36*
G01X921510Y377696D02*
X922295Y377986D01*
X922931Y377350D01*
X922641Y376565D01*
X922518Y376441D01*
X921386Y377573D01*
X921510Y377696D01*
G37*
G36*
G01X938340Y367655D02*
X938978Y368060D01*
X939731Y367625D01*
X939699Y366870D01*
X939612Y366718D01*
X938252Y367503D01*
X938340Y367655D01*
G37*
G36*
G01X934975Y369597D02*
X935613Y370002D01*
X936366Y369567D01*
X936334Y368812D01*
X936247Y368661D01*
X934887Y369445D01*
X934975Y369597D01*
G37*
G36*
G01X911146Y389664D02*
X911496Y390424D01*
X912396D01*
X912746Y389664D01*
Y389489D01*
X911146D01*
Y389664D01*
G37*
G36*
G01X925105Y389675D02*
X924435Y390025D01*
Y390895D01*
X925105Y391245D01*
X925280D01*
Y389675D01*
X925105D01*
G37*
G36*
G01X930385Y382069D02*
X929747Y381664D01*
X928994Y382099D01*
X929026Y382854D01*
X929113Y383005D01*
X930473Y382220D01*
X930385Y382069D01*
G37*
G36*
G01X925812Y384667D02*
X925057Y384635D01*
X924622Y385388D01*
X925027Y386026D01*
X925178Y386114D01*
X925964Y384754D01*
X925812Y384667D01*
G37*
G36*
G01X933759Y380123D02*
X933121Y379718D01*
X932368Y380153D01*
X932400Y380908D01*
X932487Y381060D01*
X933847Y380275D01*
X933759Y380123D01*
G37*
G36*
G01X940519Y376223D02*
X939881Y375818D01*
X939128Y376253D01*
X939160Y377008D01*
X939247Y377160D01*
X940607Y376375D01*
X940519Y376223D01*
G37*
G36*
G01X937145Y378169D02*
X936507Y377764D01*
X935754Y378199D01*
X935786Y378954D01*
X935873Y379105D01*
X937233Y378320D01*
X937145Y378169D01*
G37*
G36*
G01X925105Y393599D02*
X924435Y393949D01*
Y394819D01*
X925105Y395169D01*
X925280D01*
Y393599D01*
X925105D01*
G37*
G36*
G01X923625Y397669D02*
X922987Y397264D01*
X922234Y397699D01*
X922266Y398454D01*
X922353Y398605D01*
X923713Y397820D01*
X923625Y397669D01*
G37*
G36*
G01X950659Y370372D02*
X950021Y369967D01*
X949268Y370402D01*
X949300Y371157D01*
X949387Y371309D01*
X950747Y370523D01*
X950659Y370372D01*
G37*
G36*
G01X947294Y372314D02*
X946656Y371909D01*
X945903Y372344D01*
X945935Y373099D01*
X946022Y373251D01*
X947382Y372465D01*
X947294Y372314D01*
G37*
G36*
G01X943905Y374269D02*
X943267Y373864D01*
X942514Y374299D01*
X942546Y375054D01*
X942633Y375205D01*
X943993Y374420D01*
X943905Y374269D01*
G37*
G36*
G01X957474Y366456D02*
X956836Y366051D01*
X956083Y366486D01*
X956115Y367241D01*
X956202Y367393D01*
X957562Y366607D01*
X957474Y366456D01*
G37*
G36*
G01X954045Y368419D02*
X953407Y368014D01*
X952654Y368449D01*
X952686Y369204D01*
X952773Y369355D01*
X954133Y368570D01*
X954045Y368419D01*
G37*
G36*
G01X964571Y363212D02*
X963933Y362807D01*
X963180Y363242D01*
X963212Y363997D01*
X963299Y364149D01*
X964659Y363363D01*
X964571Y363212D01*
G37*
G36*
G01X961184Y365166D02*
X960546Y364761D01*
X959793Y365196D01*
X959825Y365951D01*
X959912Y366103D01*
X961272Y365317D01*
X961184Y365166D01*
G37*
G36*
G01X926729Y389295D02*
X927399Y388945D01*
Y388075D01*
X926729Y387725D01*
X926554D01*
Y389295D01*
X926729D01*
G37*
G36*
G01X931595Y383246D02*
X932233Y383651D01*
X932986Y383216D01*
X932954Y382461D01*
X932867Y382309D01*
X931507Y383095D01*
X931595Y383246D01*
G37*
G36*
G01X928209Y385200D02*
X928847Y385605D01*
X929600Y385170D01*
X929568Y384415D01*
X929481Y384263D01*
X928121Y385049D01*
X928209Y385200D01*
G37*
G36*
G01X938355Y379346D02*
X938993Y379751D01*
X939746Y379316D01*
X939714Y378561D01*
X939627Y378409D01*
X938267Y379195D01*
X938355Y379346D01*
G37*
G36*
G01X934969Y381300D02*
X935607Y381705D01*
X936360Y381270D01*
X936328Y380515D01*
X936241Y380363D01*
X934881Y381149D01*
X934969Y381300D01*
G37*
G36*
G01X926729Y393170D02*
X927399Y392820D01*
Y391950D01*
X926729Y391600D01*
X926554D01*
Y393170D01*
X926729D01*
G37*
G36*
G01X926728Y397051D02*
X927398Y396701D01*
Y395831D01*
X926728Y395481D01*
X926554D01*
X926553Y397052D01*
X926728Y397051D01*
G37*
G36*
G01X924835Y398846D02*
X925473Y399251D01*
X926226Y398816D01*
X926195Y398061D01*
X926108Y397910D01*
X924747Y398695D01*
X924835Y398846D01*
G37*
G36*
G01X948480Y373505D02*
X949118Y373910D01*
X949871Y373475D01*
X949839Y372720D01*
X949752Y372568D01*
X948392Y373353D01*
X948480Y373505D01*
G37*
G36*
G01X945115Y375446D02*
X945753Y375851D01*
X946506Y375416D01*
X946474Y374661D01*
X946387Y374509D01*
X945027Y375295D01*
X945115Y375446D01*
G37*
G36*
G01X941729Y377400D02*
X942367Y377805D01*
X943120Y377370D01*
X943088Y376615D01*
X943001Y376463D01*
X941641Y377249D01*
X941729Y377400D01*
G37*
G36*
G01X955255Y369597D02*
X955893Y370002D01*
X956646Y369567D01*
X956614Y368812D01*
X956527Y368661D01*
X955167Y369445D01*
X955255Y369597D01*
G37*
G36*
G01X951869Y371550D02*
X952507Y371955D01*
X953260Y371520D01*
X953228Y370765D01*
X953141Y370613D01*
X951781Y371399D01*
X951869Y371550D01*
G37*
G36*
G01X947279Y387923D02*
X946641Y387518D01*
X945888Y387953D01*
X945919Y388708D01*
X946006Y388859D01*
X947367Y388074D01*
X947279Y387923D01*
G37*
G36*
G01X950665Y385969D02*
X950027Y385564D01*
X949274Y385999D01*
X949306Y386754D01*
X949393Y386905D01*
X950753Y386120D01*
X950665Y385969D01*
G37*
G36*
G01X960798Y380123D02*
X960160Y379718D01*
X959407Y380153D01*
X959439Y380908D01*
X959526Y381060D01*
X960886Y380275D01*
X960798Y380123D01*
G37*
G36*
G01X957424Y382069D02*
X956786Y381664D01*
X956033Y382099D01*
X956065Y382854D01*
X956152Y383005D01*
X957512Y382220D01*
X957424Y382069D01*
G37*
G36*
G01X954039Y384023D02*
X953401Y383618D01*
X952648Y384053D01*
X952680Y384808D01*
X952767Y384960D01*
X954127Y384175D01*
X954039Y384023D01*
G37*
G36*
G01X964184Y378169D02*
X963546Y377764D01*
X962793Y378199D01*
X962825Y378954D01*
X962912Y379105D01*
X964272Y378320D01*
X964184Y378169D01*
G37*
G36*
G01X967944Y372966D02*
X967306Y372561D01*
X966553Y372996D01*
X966585Y373751D01*
X966672Y373903D01*
X968032Y373117D01*
X967944Y372966D01*
G37*
G36*
G01X945385Y393599D02*
X944715Y393949D01*
Y394819D01*
X945385Y395169D01*
X945560D01*
Y393599D01*
X945385D01*
G37*
G36*
G01Y397450D02*
X944715Y397800D01*
Y398670D01*
X945385Y399020D01*
X945560D01*
Y397450D01*
X945385D01*
G37*
G36*
G01X945386Y389718D02*
X944716Y390068D01*
Y390938D01*
X945386Y391288D01*
X945560D01*
X945561Y389717D01*
X945386Y389718D01*
G37*
G36*
G01X946086Y401097D02*
X945326Y401447D01*
Y402347D01*
X946086Y402697D01*
X946261D01*
Y401097D01*
X946086D01*
G37*
G36*
G01X948489Y389100D02*
X949127Y389505D01*
X949880Y389070D01*
X949848Y388315D01*
X949761Y388163D01*
X948401Y388949D01*
X948489Y389100D01*
G37*
G36*
G01X958634Y383246D02*
X959272Y383651D01*
X960025Y383216D01*
X959993Y382461D01*
X959906Y382309D01*
X958546Y383095D01*
X958634Y383246D01*
G37*
G36*
G01X955249Y385200D02*
X955887Y385605D01*
X956640Y385170D01*
X956608Y384415D01*
X956521Y384263D01*
X955161Y385049D01*
X955249Y385200D01*
G37*
G36*
G01X951875Y387146D02*
X952513Y387551D01*
X953266Y387116D01*
X953234Y386361D01*
X953147Y386209D01*
X951787Y386995D01*
X951875Y387146D01*
G37*
G36*
G01X965394Y379346D02*
X966032Y379751D01*
X966785Y379316D01*
X966753Y378561D01*
X966666Y378409D01*
X965306Y379195D01*
X965394Y379346D01*
G37*
G36*
G01X962008Y381300D02*
X962646Y381705D01*
X963399Y381270D01*
X963367Y380515D01*
X963280Y380363D01*
X961920Y381149D01*
X962008Y381300D01*
G37*
G36*
G01X967327Y377401D02*
X968080Y377346D01*
X968426Y376548D01*
X967951Y375961D01*
X967790Y375890D01*
X967166Y377332D01*
X967327Y377401D01*
G37*
G36*
G01X947009Y393170D02*
X947679Y392820D01*
Y391950D01*
X947009Y391600D01*
X946834D01*
Y393170D01*
X947009D01*
G37*
G36*
G01Y397094D02*
X947679Y396744D01*
Y395874D01*
X947009Y395524D01*
X946834D01*
Y397094D01*
X947009D01*
G37*
G36*
G01X947184Y402197D02*
X947944Y401847D01*
Y400947D01*
X947184Y400597D01*
X947009D01*
Y402197D01*
X947184D01*
G37*
G36*
G01X910236Y344459D02*
X909946Y345244D01*
X910583Y345880D01*
X911367Y345591D01*
X911491Y345467D01*
X910360Y344335D01*
X910236Y344459D01*
G37*
G36*
G01X921449Y342300D02*
X922087Y342705D01*
X922840Y342270D01*
X922808Y341515D01*
X922721Y341363D01*
X921361Y342149D01*
X921449Y342300D01*
G37*
G36*
G01X918075Y344246D02*
X918713Y344651D01*
X919466Y344216D01*
X919434Y343461D01*
X919347Y343309D01*
X917987Y344095D01*
X918075Y344246D01*
G37*
G36*
G01X914689Y346200D02*
X915327Y346605D01*
X916080Y346170D01*
X916048Y345415D01*
X915961Y345263D01*
X914601Y346049D01*
X914689Y346200D01*
G37*
G36*
G01X921725Y387725D02*
X921055Y388075D01*
Y388945D01*
X921725Y389295D01*
X921900D01*
Y387725D01*
X921725D01*
G37*
G36*
G01X926999Y380123D02*
X926361Y379718D01*
X925608Y380153D01*
X925640Y380908D01*
X925727Y381060D01*
X927087Y380275D01*
X926999Y380123D01*
G37*
G36*
G01X921616Y384523D02*
X921059Y385035D01*
X921284Y385875D01*
X922022Y386039D01*
X922191Y385994D01*
X921785Y384477D01*
X921616Y384523D01*
G37*
G36*
G01X923634Y382065D02*
X922996Y381659D01*
X922242Y382094D01*
X922275Y382849D01*
X922362Y383001D01*
X923722Y382216D01*
X923634Y382065D01*
G37*
G36*
G01X930385Y378169D02*
X929747Y377764D01*
X928994Y378199D01*
X929026Y378954D01*
X929113Y379105D01*
X930473Y378320D01*
X930385Y378169D01*
G37*
G36*
G01X940534Y372314D02*
X939896Y371909D01*
X939143Y372344D01*
X939175Y373099D01*
X939262Y373251D01*
X940622Y372465D01*
X940534Y372314D01*
G37*
G36*
G01X937145Y374269D02*
X936507Y373864D01*
X935754Y374299D01*
X935786Y375054D01*
X935873Y375205D01*
X937233Y374420D01*
X937145Y374269D01*
G37*
G36*
G01X933759Y376223D02*
X933121Y375818D01*
X932368Y376253D01*
X932400Y377008D01*
X932487Y377160D01*
X933847Y376375D01*
X933759Y376223D01*
G37*
G36*
G01X921725Y391600D02*
X921055Y391950D01*
Y392820D01*
X921725Y393170D01*
X921900D01*
Y391600D01*
X921725D01*
G37*
G36*
G01X920254Y395714D02*
X919616Y395309D01*
X918863Y395744D01*
X918895Y396499D01*
X918982Y396651D01*
X920342Y395865D01*
X920254Y395714D01*
G37*
G36*
G01X950674Y366464D02*
X950036Y366059D01*
X949283Y366494D01*
X949315Y367249D01*
X949402Y367401D01*
X950762Y366615D01*
X950674Y366464D01*
G37*
G36*
G01X947285Y368419D02*
X946647Y368014D01*
X945894Y368449D01*
X945926Y369204D01*
X946013Y369355D01*
X947373Y368570D01*
X947285Y368419D01*
G37*
G36*
G01X943899Y370372D02*
X943261Y369967D01*
X942508Y370402D01*
X942540Y371157D01*
X942627Y371309D01*
X943987Y370523D01*
X943899Y370372D01*
G37*
G36*
G01X957424Y362569D02*
X956786Y362164D01*
X956033Y362599D01*
X956065Y363354D01*
X956152Y363505D01*
X957512Y362720D01*
X957424Y362569D01*
G37*
G36*
G01X954039Y364523D02*
X953401Y364118D01*
X952648Y364553D01*
X952680Y365308D01*
X952767Y365460D01*
X954127Y364675D01*
X954039Y364523D01*
G37*
G36*
G01X961445Y361352D02*
X961096Y360681D01*
X960227Y360679D01*
X959875Y361348D01*
Y361523D01*
X961444Y361528D01*
X961445Y361352D01*
G37*
G36*
G01X923349Y391245D02*
X924019Y390895D01*
Y390025D01*
X923349Y389675D01*
X923174D01*
Y391245D01*
X923349D01*
G37*
G36*
G01X928209Y381300D02*
X928847Y381705D01*
X929600Y381270D01*
X929568Y380515D01*
X929481Y380363D01*
X928121Y381149D01*
X928209Y381300D01*
G37*
G36*
G01X924820Y383255D02*
X925458Y383660D01*
X926211Y383225D01*
X926179Y382470D01*
X926092Y382318D01*
X924732Y383103D01*
X924820Y383255D01*
G37*
G36*
G01X923349Y387345D02*
X924019Y386995D01*
Y386125D01*
X923349Y385775D01*
X923174D01*
Y387345D01*
X923349D01*
G37*
G36*
G01X931595Y379346D02*
X932233Y379751D01*
X932986Y379316D01*
X932954Y378561D01*
X932867Y378409D01*
X931507Y379195D01*
X931595Y379346D01*
G37*
G36*
G01X938355Y375446D02*
X938993Y375851D01*
X939746Y375416D01*
X939714Y374661D01*
X939627Y374509D01*
X938267Y375295D01*
X938355Y375446D01*
G37*
G36*
G01X934969Y377400D02*
X935607Y377805D01*
X936360Y377370D01*
X936328Y376615D01*
X936241Y376463D01*
X934881Y377249D01*
X934969Y377400D01*
G37*
G36*
G01X923348Y395143D02*
X924018Y394794D01*
Y393924D01*
X923349Y393574D01*
X923173D01*
Y395144D01*
X923348Y395143D01*
G37*
G36*
G01X921419Y396917D02*
X922056Y397323D01*
X922809Y396888D01*
X922778Y396133D01*
X922690Y395981D01*
X921330Y396766D01*
X921419Y396917D01*
G37*
G36*
G01X948495Y369597D02*
X949133Y370002D01*
X949886Y369567D01*
X949854Y368812D01*
X949767Y368661D01*
X948407Y369445D01*
X948495Y369597D01*
G37*
G36*
G01X945109Y371550D02*
X945747Y371955D01*
X946500Y371520D01*
X946468Y370765D01*
X946381Y370613D01*
X945021Y371399D01*
X945109Y371550D01*
G37*
G36*
G01X941720Y373505D02*
X942358Y373910D01*
X943111Y373475D01*
X943079Y372720D01*
X942992Y372568D01*
X941632Y373353D01*
X941720Y373505D01*
G37*
G36*
G01X955249Y365700D02*
X955887Y366105D01*
X956640Y365670D01*
X956608Y364915D01*
X956521Y364763D01*
X955161Y365549D01*
X955249Y365700D01*
G37*
G36*
G01X951860Y367655D02*
X952498Y368060D01*
X953251Y367625D01*
X953219Y366870D01*
X953132Y366718D01*
X951772Y367503D01*
X951860Y367655D01*
G37*
G36*
G01X940519Y387923D02*
X939881Y387518D01*
X939128Y387953D01*
X939159Y388708D01*
X939246Y388859D01*
X940607Y388074D01*
X940519Y387923D01*
G37*
G36*
G01X938625Y397450D02*
X937955Y397800D01*
Y398670D01*
X938625Y399020D01*
X938800D01*
Y397450D01*
X938625D01*
G37*
G36*
G01X939225Y402050D02*
X938555Y402400D01*
Y403270D01*
X939225Y403620D01*
X939400D01*
Y402050D01*
X939225D01*
G37*
G36*
G01X938625Y393599D02*
X937955Y393949D01*
Y394819D01*
X938625Y395169D01*
X938800D01*
Y393599D01*
X938625D01*
G37*
G36*
G01X938626Y389718D02*
X937956Y390068D01*
Y390938D01*
X938626Y391288D01*
X938800D01*
X938801Y389717D01*
X938626Y389718D01*
G37*
G36*
G01X950665Y382069D02*
X950027Y381664D01*
X949274Y382099D01*
X949306Y382854D01*
X949393Y383005D01*
X950753Y382220D01*
X950665Y382069D01*
G37*
G36*
G01X947279Y384023D02*
X946641Y383618D01*
X945888Y384053D01*
X945920Y384808D01*
X946007Y384960D01*
X947367Y384175D01*
X947279Y384023D01*
G37*
G36*
G01X943905Y385969D02*
X943267Y385564D01*
X942514Y385999D01*
X942546Y386754D01*
X942633Y386905D01*
X943993Y386120D01*
X943905Y385969D01*
G37*
G36*
G01X960798Y376223D02*
X960160Y375818D01*
X959407Y376253D01*
X959439Y377008D01*
X959526Y377160D01*
X960886Y376375D01*
X960798Y376223D01*
G37*
G36*
G01X957424Y378169D02*
X956786Y377764D01*
X956033Y378199D01*
X956065Y378954D01*
X956152Y379105D01*
X957512Y378320D01*
X957424Y378169D01*
G37*
G36*
G01X954039Y380123D02*
X953401Y379718D01*
X952648Y380153D01*
X952680Y380908D01*
X952767Y381060D01*
X954127Y380275D01*
X954039Y380123D01*
G37*
G36*
G01X965388Y371550D02*
X966026Y371955D01*
X966779Y371520D01*
X966747Y370765D01*
X966660Y370613D01*
X965300Y371399D01*
X965388Y371550D01*
G37*
G36*
G01X967939Y369069D02*
X967301Y368664D01*
X966548Y369099D01*
X966580Y369854D01*
X966667Y370005D01*
X968027Y369220D01*
X967939Y369069D01*
G37*
G36*
G01X970280Y368959D02*
X969846Y368341D01*
X968984Y368454D01*
X968724Y369163D01*
X968746Y369336D01*
X970303Y369133D01*
X970280Y368959D01*
G37*
G36*
G01X940283Y401883D02*
X941043Y401533D01*
Y400633D01*
X940283Y400283D01*
X940108D01*
Y401883D01*
X940283D01*
G37*
G36*
G01X940249Y393170D02*
X940919Y392820D01*
Y391950D01*
X940249Y391600D01*
X940074D01*
Y393170D01*
X940249D01*
G37*
G36*
G01Y397094D02*
X940919Y396744D01*
Y395874D01*
X940249Y395524D01*
X940074D01*
Y397094D01*
X940249D01*
G37*
G36*
G01X941729Y389100D02*
X942367Y389505D01*
X943120Y389070D01*
X943088Y388315D01*
X943001Y388163D01*
X941641Y388949D01*
X941729Y389100D01*
G37*
G36*
G01X948489Y385200D02*
X949127Y385605D01*
X949880Y385170D01*
X949848Y384415D01*
X949761Y384263D01*
X948401Y385049D01*
X948489Y385200D01*
G37*
G36*
G01X945115Y387146D02*
X945753Y387551D01*
X946506Y387116D01*
X946474Y386361D01*
X946387Y386209D01*
X945027Y386995D01*
X945115Y387146D01*
G37*
G36*
G01X958634Y379346D02*
X959272Y379751D01*
X960025Y379316D01*
X959993Y378561D01*
X959906Y378409D01*
X958546Y379195D01*
X958634Y379346D01*
G37*
G36*
G01X955249Y381300D02*
X955887Y381705D01*
X956640Y381270D01*
X956608Y380515D01*
X956521Y380363D01*
X955161Y381149D01*
X955249Y381300D01*
G37*
G36*
G01X951875Y383246D02*
X952513Y383651D01*
X953266Y383216D01*
X953234Y382461D01*
X953147Y382309D01*
X951787Y383095D01*
X951875Y383246D01*
G37*
G36*
G01X963892Y375448D02*
X964646Y375406D01*
X965005Y374614D01*
X964539Y374019D01*
X964380Y373946D01*
X963732Y375377D01*
X963892Y375448D01*
G37*
G36*
G01X962008Y377400D02*
X962646Y377805D01*
X963399Y377370D01*
X963367Y376615D01*
X963280Y376463D01*
X961920Y377249D01*
X962008Y377400D01*
G37*
G36*
G01X962284Y389669D02*
X961524Y390019D01*
Y390919D01*
X962284Y391269D01*
X962459D01*
Y389669D01*
X962284D01*
G37*
G36*
G01X964193Y385963D02*
X963555Y385558D01*
X962802Y385993D01*
X962833Y386748D01*
X962921Y386899D01*
X964280Y386115D01*
X964193Y385963D01*
G37*
G36*
G01X970975Y382052D02*
X970337Y381647D01*
X969584Y382082D01*
X969616Y382837D01*
X969703Y382989D01*
X971063Y382203D01*
X970975Y382052D01*
G37*
G36*
G01X967558Y384023D02*
X966920Y383618D01*
X966167Y384053D01*
X966199Y384808D01*
X966286Y384960D01*
X967646Y384175D01*
X967558Y384023D01*
G37*
G36*
G01X959881Y395849D02*
X959121Y396199D01*
Y397099D01*
X959881Y397449D01*
X960056D01*
Y395849D01*
X959881D01*
G37*
G36*
G01Y399749D02*
X959121Y400099D01*
Y400999D01*
X959881Y401349D01*
X960056D01*
Y399749D01*
X959881D01*
G37*
G36*
G01X963384Y391269D02*
X964144Y390919D01*
Y390019D01*
X963384Y389669D01*
X963209D01*
Y391269D01*
X963384D01*
G37*
G36*
G01X965394Y387146D02*
X966032Y387551D01*
X966785Y387116D01*
X966753Y386361D01*
X966666Y386209D01*
X965306Y386995D01*
X965394Y387146D01*
G37*
G36*
G01X968768Y385200D02*
X969406Y385605D01*
X970159Y385170D01*
X970127Y384415D01*
X970040Y384263D01*
X968680Y385049D01*
X968768Y385200D01*
G37*
G36*
G01X971453Y383324D02*
X971964Y383880D01*
X972804Y383656D01*
X972968Y382918D01*
X972924Y382748D01*
X971406Y383155D01*
X971453Y383324D01*
G37*
G36*
G01X960979Y397449D02*
X961739Y397099D01*
Y396199D01*
X960979Y395849D01*
X960804D01*
Y397449D01*
X960979D01*
G37*
G36*
G01Y401349D02*
X961739Y400999D01*
Y400099D01*
X960979Y399749D01*
X960804D01*
Y401349D01*
X960979D01*
G37*
G36*
G01X958904Y385793D02*
X958235Y386143D01*
X958234Y387012D01*
X958904Y387362D01*
X959080Y387363D01*
Y385792D01*
X958904Y385793D01*
G37*
G36*
G01X960819Y384010D02*
X960182Y383605D01*
X959429Y384039D01*
X959460Y384794D01*
X959548Y384947D01*
X960908Y384162D01*
X960819Y384010D01*
G37*
G36*
G01X964184Y382069D02*
X963546Y381664D01*
X962793Y382099D01*
X962825Y382854D01*
X962912Y383005D01*
X964272Y382220D01*
X964184Y382069D01*
G37*
G36*
G01X970945Y374268D02*
X970307Y373863D01*
X969554Y374297D01*
X969586Y375052D01*
X969673Y375205D01*
X971032Y374419D01*
X970945Y374268D01*
G37*
G36*
G01X967558Y380123D02*
X966920Y379718D01*
X966167Y380153D01*
X966199Y380908D01*
X966286Y381060D01*
X967646Y380275D01*
X967558Y380123D01*
G37*
G36*
G01X958754Y390788D02*
X957969Y390498D01*
X957333Y391135D01*
X957623Y391919D01*
X957747Y392043D01*
X958878Y390912D01*
X958754Y390788D01*
G37*
G36*
G01X956454Y396188D02*
X955669Y395898D01*
X955033Y396535D01*
X955323Y397319D01*
X955447Y397443D01*
X956578Y396312D01*
X956454Y396188D01*
G37*
G36*
G01X954681Y400627D02*
X953921Y400977D01*
Y401877D01*
X954681Y402227D01*
X954856D01*
Y400627D01*
X954681D01*
G37*
G36*
G01X960713Y389952D02*
X961473Y389602D01*
Y388701D01*
X960714Y388351D01*
X960539D01*
Y389951D01*
X960713Y389952D01*
G37*
G36*
G01X965394Y383246D02*
X966032Y383651D01*
X966785Y383216D01*
X966753Y382461D01*
X966666Y382309D01*
X965306Y383095D01*
X965394Y383246D01*
G37*
G36*
G01X962008Y385200D02*
X962646Y385605D01*
X963399Y385170D01*
X963367Y384415D01*
X963280Y384263D01*
X961920Y385049D01*
X962008Y385200D01*
G37*
G36*
G01X970667Y379510D02*
X971337Y379160D01*
Y378291D01*
X970667Y377941D01*
X970492Y377940D01*
X970493Y379510D01*
X970667D01*
G37*
G36*
G01X968767Y381301D02*
X969405Y381706D01*
X970158Y381272D01*
X970126Y380516D01*
X970039Y380364D01*
X968680Y381150D01*
X968767Y381301D01*
G37*
G36*
G01X958399Y392696D02*
X959184Y392986D01*
X959821Y392349D01*
X959531Y391565D01*
X959407Y391441D01*
X958276Y392572D01*
X958399Y392696D01*
G37*
G36*
G01X956099Y398096D02*
X956884Y398386D01*
X957521Y397749D01*
X957231Y396965D01*
X957107Y396841D01*
X955976Y397972D01*
X956099Y398096D01*
G37*
G36*
G01X955779Y402227D02*
X956539Y401877D01*
Y400977D01*
X955779Y400627D01*
X955604D01*
Y402227D01*
X955779D01*
G37*
G36*
G01X923625Y354769D02*
X922987Y354364D01*
X922234Y354799D01*
X922266Y355554D01*
X922353Y355705D01*
X923713Y354920D01*
X923625Y354769D01*
G37*
G36*
G01X917763Y358670D02*
X917416Y357998D01*
X916547Y357995D01*
X916194Y358663D01*
X916192Y358838D01*
X917763Y358845D01*
Y358670D01*
G37*
G36*
G01X920239Y356723D02*
X919601Y356318D01*
X918848Y356753D01*
X918880Y357508D01*
X918967Y357660D01*
X920327Y356875D01*
X920239Y356723D01*
G37*
G36*
G01X930385Y350869D02*
X929747Y350464D01*
X928994Y350899D01*
X929026Y351654D01*
X929113Y351805D01*
X930473Y351020D01*
X930385Y350869D01*
G37*
G36*
G01X926999Y352823D02*
X926361Y352418D01*
X925608Y352853D01*
X925640Y353608D01*
X925727Y353760D01*
X927087Y352975D01*
X926999Y352823D01*
G37*
G36*
G01X914529Y359786D02*
X914179Y359026D01*
X913279D01*
X912929Y359786D01*
Y359961D01*
X914529D01*
Y359786D01*
G37*
G36*
G01X940519Y345023D02*
X939881Y344618D01*
X939128Y345053D01*
X939160Y345808D01*
X939247Y345960D01*
X940607Y345175D01*
X940519Y345023D01*
G37*
G36*
G01X937145Y346969D02*
X936507Y346564D01*
X935754Y346999D01*
X935786Y347754D01*
X935873Y347905D01*
X937233Y347120D01*
X937145Y346969D01*
G37*
G36*
G01X933759Y348923D02*
X933121Y348518D01*
X932368Y348953D01*
X932400Y349708D01*
X932487Y349860D01*
X933847Y349075D01*
X933759Y348923D01*
G37*
G36*
G01X943905Y343069D02*
X943267Y342664D01*
X942514Y343099D01*
X942546Y343854D01*
X942633Y344005D01*
X943993Y343220D01*
X943905Y343069D01*
G37*
G36*
G01X919020Y359275D02*
X919741Y359502D01*
X920355Y358886D01*
X920129Y358165D01*
X920006Y358042D01*
X918895Y359151D01*
X919020Y359275D01*
G37*
G36*
G01X928209Y354000D02*
X928847Y354405D01*
X929600Y353970D01*
X929568Y353215D01*
X929481Y353063D01*
X928121Y353849D01*
X928209Y354000D01*
G37*
G36*
G01X924835Y355946D02*
X925473Y356351D01*
X926226Y355916D01*
X926194Y355161D01*
X926107Y355009D01*
X924747Y355795D01*
X924835Y355946D01*
G37*
G36*
G01X921324Y358008D02*
X921962Y358413D01*
X922715Y357978D01*
X922683Y357223D01*
X922596Y357072D01*
X921236Y357856D01*
X921324Y358008D01*
G37*
G36*
G01X931595Y352046D02*
X932233Y352451D01*
X932986Y352016D01*
X932954Y351261D01*
X932867Y351109D01*
X931507Y351895D01*
X931595Y352046D01*
G37*
G36*
G01X912929Y360884D02*
X913279Y361644D01*
X914179D01*
X914529Y360884D01*
Y360709D01*
X912929D01*
Y360884D01*
G37*
G36*
G01X938355Y348146D02*
X938993Y348551D01*
X939746Y348116D01*
X939714Y347361D01*
X939627Y347209D01*
X938267Y347995D01*
X938355Y348146D01*
G37*
G36*
G01X934969Y350100D02*
X935607Y350505D01*
X936360Y350070D01*
X936328Y349315D01*
X936241Y349163D01*
X934881Y349949D01*
X934969Y350100D01*
G37*
G36*
G01X914689Y342300D02*
X915327Y342705D01*
X916080Y342270D01*
X916048Y341515D01*
X915961Y341363D01*
X914601Y342149D01*
X914689Y342300D01*
G37*
G36*
G01X920239Y352823D02*
X919601Y352418D01*
X918848Y352853D01*
X918880Y353608D01*
X918967Y353760D01*
X920327Y352975D01*
X920239Y352823D01*
G37*
G36*
G01X923625Y350869D02*
X922987Y350464D01*
X922234Y350899D01*
X922266Y351654D01*
X922353Y351805D01*
X923713Y351020D01*
X923625Y350869D01*
G37*
G36*
G01X930385Y346969D02*
X929747Y346564D01*
X928994Y346999D01*
X929026Y347754D01*
X929113Y347905D01*
X930473Y347120D01*
X930385Y346969D01*
G37*
G36*
G01X926999Y348923D02*
X926361Y348518D01*
X925608Y348953D01*
X925640Y349708D01*
X925727Y349860D01*
X927087Y349075D01*
X926999Y348923D01*
G37*
G36*
G01X937145Y343069D02*
X936507Y342664D01*
X935754Y343099D01*
X935786Y343854D01*
X935873Y344005D01*
X937233Y343220D01*
X937145Y343069D01*
G37*
G36*
G01X933759Y345023D02*
X933121Y344618D01*
X932368Y345053D01*
X932400Y345808D01*
X932487Y345960D01*
X933847Y345175D01*
X933759Y345023D01*
G37*
G36*
G01X946270Y341491D02*
X946619Y342161D01*
X947489D01*
X947839Y341491D01*
X947840Y341317D01*
X946269Y341316D01*
X946270Y341491D01*
G37*
G36*
G01X916859Y354772D02*
X916221Y354367D01*
X915468Y354802D01*
X915500Y355557D01*
X915587Y355709D01*
X916947Y354924D01*
X916859Y354772D01*
G37*
G36*
G01X915673Y357162D02*
X916409Y357332D01*
X916974Y356671D01*
X916694Y355969D01*
X916561Y355856D01*
X915540Y357049D01*
X915673Y357162D01*
G37*
G36*
G01X918075Y355946D02*
X918713Y356351D01*
X919466Y355916D01*
X919434Y355161D01*
X919347Y355009D01*
X917987Y355795D01*
X918075Y355946D01*
G37*
G36*
G01X921449Y354000D02*
X922087Y354405D01*
X922840Y353970D01*
X922808Y353215D01*
X922721Y353063D01*
X921361Y353849D01*
X921449Y354000D01*
G37*
G36*
G01X924835Y352046D02*
X925473Y352451D01*
X926226Y352016D01*
X926194Y351261D01*
X926107Y351109D01*
X924747Y351895D01*
X924835Y352046D01*
G37*
G36*
G01X931595Y348146D02*
X932233Y348551D01*
X932986Y348116D01*
X932954Y347361D01*
X932867Y347209D01*
X931507Y347995D01*
X931595Y348146D01*
G37*
G36*
G01X928209Y350100D02*
X928847Y350505D01*
X929600Y350070D01*
X929568Y349315D01*
X929481Y349163D01*
X928121Y349949D01*
X928209Y350100D01*
G37*
G36*
G01X938355Y344246D02*
X938993Y344651D01*
X939746Y344216D01*
X939714Y343461D01*
X939627Y343309D01*
X938267Y344095D01*
X938355Y344246D01*
G37*
G36*
G01X934969Y346200D02*
X935607Y346605D01*
X936360Y346170D01*
X936328Y345415D01*
X936241Y345263D01*
X934881Y346049D01*
X934969Y346200D01*
G37*
G36*
G01X930385Y358669D02*
X929747Y358264D01*
X928994Y358699D01*
X929026Y359454D01*
X929113Y359605D01*
X930473Y358820D01*
X930385Y358669D01*
G37*
G36*
G01X937145Y354769D02*
X936507Y354364D01*
X935754Y354799D01*
X935786Y355554D01*
X935873Y355705D01*
X937233Y354920D01*
X937145Y354769D01*
G37*
G36*
G01X933759Y356723D02*
X933121Y356318D01*
X932368Y356753D01*
X932400Y357508D01*
X932487Y357660D01*
X933847Y356875D01*
X933759Y356723D01*
G37*
G36*
G01X940519Y352823D02*
X939881Y352418D01*
X939128Y352853D01*
X939160Y353608D01*
X939247Y353760D01*
X940607Y352975D01*
X940519Y352823D01*
G37*
G36*
G01X914327Y366365D02*
X913542Y366075D01*
X912905Y366711D01*
X913195Y367496D01*
X913319Y367620D01*
X914450Y366489D01*
X914327Y366365D01*
G37*
G36*
G01X911969Y368723D02*
X911184Y368433D01*
X910548Y369069D01*
X910838Y369854D01*
X910961Y369978D01*
X912093Y368846D01*
X911969Y368723D01*
G37*
G36*
G01X926999Y360623D02*
X926361Y360218D01*
X925608Y360653D01*
X925640Y361408D01*
X925727Y361560D01*
X927087Y360775D01*
X926999Y360623D01*
G37*
G36*
G01X920782Y363910D02*
X919997Y363620D01*
X919361Y364256D01*
X919651Y365041D01*
X919774Y365165D01*
X920906Y364033D01*
X920782Y363910D01*
G37*
G36*
G01X917956Y365818D02*
X917606Y365058D01*
X916706D01*
X916356Y365818D01*
Y365993D01*
X917956D01*
Y365818D01*
G37*
G36*
G01X949854Y353608D02*
X949886Y352853D01*
X949133Y352418D01*
X948495Y352823D01*
X948407Y352975D01*
X949767Y353760D01*
X949854Y353608D01*
G37*
G36*
G01X946468Y351654D02*
X946500Y350899D01*
X945747Y350464D01*
X945109Y350869D01*
X945021Y351020D01*
X946381Y351805D01*
X946468Y351654D01*
G37*
G36*
G01X943905Y350869D02*
X943267Y350464D01*
X942514Y350899D01*
X942546Y351654D01*
X942633Y351805D01*
X943993Y351020D01*
X943905Y350869D01*
G37*
G36*
G01X938355Y355946D02*
X938993Y356351D01*
X939746Y355916D01*
X939714Y355161D01*
X939627Y355009D01*
X938267Y355795D01*
X938355Y355946D01*
G37*
G36*
G01X934969Y357900D02*
X935607Y358305D01*
X936360Y357870D01*
X936328Y357115D01*
X936241Y356963D01*
X934881Y357749D01*
X934969Y357900D01*
G37*
G36*
G01X911614Y370630D02*
X912399Y370920D01*
X913035Y370284D01*
X912745Y369499D01*
X912622Y369375D01*
X911490Y370507D01*
X911614Y370630D01*
G37*
G36*
G01X913972Y368273D02*
X914757Y368563D01*
X915393Y367926D01*
X915103Y367141D01*
X914979Y367018D01*
X913848Y368149D01*
X913972Y368273D01*
G37*
G36*
G01X931595Y359846D02*
X932233Y360251D01*
X932986Y359816D01*
X932954Y359061D01*
X932867Y358909D01*
X931507Y359695D01*
X931595Y359846D01*
G37*
G36*
G01X928209Y361800D02*
X928847Y362205D01*
X929600Y361770D01*
X929568Y361015D01*
X929481Y360863D01*
X928121Y361649D01*
X928209Y361800D01*
G37*
G36*
G01X924835Y363746D02*
X925473Y364151D01*
X926226Y363716D01*
X926194Y362961D01*
X926107Y362809D01*
X924747Y363595D01*
X924835Y363746D01*
G37*
G36*
G01X920427Y365817D02*
X921212Y366107D01*
X921848Y365471D01*
X921558Y364686D01*
X921435Y364562D01*
X920303Y365694D01*
X920427Y365817D01*
G37*
G36*
G01X917356Y366916D02*
X917706Y367676D01*
X918606D01*
X918956Y366916D01*
Y366741D01*
X917356D01*
Y366916D01*
G37*
G36*
G01X941729Y354000D02*
X942367Y354405D01*
X943120Y353970D01*
X943088Y353215D01*
X943001Y353063D01*
X941641Y353849D01*
X941729Y354000D01*
G37*
G36*
G01X916865Y350869D02*
X916227Y350464D01*
X915474Y350899D01*
X915506Y351654D01*
X915593Y351805D01*
X916953Y351020D01*
X916865Y350869D01*
G37*
G36*
G01X930385Y343069D02*
X929747Y342664D01*
X928994Y343099D01*
X929026Y343854D01*
X929113Y344005D01*
X930473Y343220D01*
X930385Y343069D01*
G37*
G36*
G01X926999Y345023D02*
X926361Y344618D01*
X925608Y345053D01*
X925640Y345808D01*
X925727Y345960D01*
X927087Y345175D01*
X926999Y345023D01*
G37*
G36*
G01X923625Y346969D02*
X922987Y346564D01*
X922234Y346999D01*
X922266Y347754D01*
X922353Y347905D01*
X923713Y347120D01*
X923625Y346969D01*
G37*
G36*
G01X920239Y348923D02*
X919601Y348518D01*
X918848Y348953D01*
X918880Y349708D01*
X918967Y349860D01*
X920327Y349075D01*
X920239Y348923D01*
G37*
G36*
G01X915256Y372066D02*
X915606Y372826D01*
X916506D01*
X916856Y372066D01*
Y371891D01*
X915256D01*
Y372066D01*
G37*
G36*
G01X912088Y374318D02*
X912873Y374608D01*
X913509Y373971D01*
X913219Y373186D01*
X913095Y373063D01*
X911964Y374194D01*
X912088Y374318D01*
G37*
G36*
G01X931595Y363746D02*
X932233Y364151D01*
X932986Y363716D01*
X932954Y362961D01*
X932867Y362809D01*
X931507Y363595D01*
X931595Y363746D01*
G37*
G36*
G01X928209Y365700D02*
X928847Y366105D01*
X929600Y365670D01*
X929568Y364915D01*
X929481Y364763D01*
X928121Y365549D01*
X928209Y365700D01*
G37*
G36*
G01X924820Y367655D02*
X925458Y368060D01*
X926211Y367625D01*
X926179Y366870D01*
X926092Y366718D01*
X924732Y367503D01*
X924820Y367655D01*
G37*
G36*
G01X920323Y369882D02*
X921108Y370172D01*
X921744Y369536D01*
X921454Y368751D01*
X921331Y368627D01*
X920199Y369759D01*
X920323Y369882D01*
G37*
G36*
G01X938355Y359846D02*
X938993Y360251D01*
X939746Y359816D01*
X939714Y359061D01*
X939627Y358909D01*
X938267Y359695D01*
X938355Y359846D01*
G37*
G36*
G01X934969Y361800D02*
X935607Y362205D01*
X936360Y361770D01*
X936328Y361015D01*
X936241Y360863D01*
X934881Y361649D01*
X934969Y361800D01*
G37*
G36*
G01X941722Y357904D02*
X942360Y358309D01*
X943113Y357874D01*
X943081Y357119D01*
X942994Y356967D01*
X941634Y357753D01*
X941722Y357904D01*
G37*
G36*
G01X949300Y359061D02*
X949268Y359816D01*
X950021Y360251D01*
X950659Y359846D01*
X950747Y359695D01*
X949387Y358909D01*
X949300Y359061D01*
G37*
G36*
G01X930109Y391245D02*
X930779Y390895D01*
Y390025D01*
X930109Y389675D01*
X929934D01*
Y391245D01*
X930109D01*
G37*
G36*
G01X931595Y387146D02*
X932233Y387551D01*
X932986Y387116D01*
X932954Y386361D01*
X932867Y386209D01*
X931507Y386995D01*
X931595Y387146D01*
G37*
G36*
G01X938355Y383246D02*
X938993Y383651D01*
X939746Y383216D01*
X939714Y382461D01*
X939627Y382309D01*
X938267Y383095D01*
X938355Y383246D01*
G37*
G36*
G01X934969Y385200D02*
X935607Y385605D01*
X936360Y385170D01*
X936328Y384415D01*
X936241Y384263D01*
X934881Y385049D01*
X934969Y385200D01*
G37*
G36*
G01X930109Y395169D02*
X930779Y394819D01*
Y393949D01*
X930109Y393599D01*
X929934D01*
Y395169D01*
X930109D01*
G37*
G36*
G01Y399020D02*
X930779Y398670D01*
Y397800D01*
X930109Y397450D01*
X929934D01*
Y399020D01*
X930109D01*
G37*
G36*
G01X948489Y377400D02*
X949127Y377805D01*
X949880Y377370D01*
X949848Y376615D01*
X949761Y376463D01*
X948401Y377249D01*
X948489Y377400D01*
G37*
G36*
G01X945115Y379346D02*
X945753Y379751D01*
X946506Y379316D01*
X946474Y378561D01*
X946387Y378409D01*
X945027Y379195D01*
X945115Y379346D01*
G37*
G36*
G01X941729Y381300D02*
X942367Y381705D01*
X943120Y381270D01*
X943088Y380515D01*
X943001Y380363D01*
X941641Y381149D01*
X941729Y381300D01*
G37*
G36*
G01X958628Y371550D02*
X959266Y371955D01*
X960019Y371520D01*
X959987Y370765D01*
X959900Y370613D01*
X958540Y371399D01*
X958628Y371550D01*
G37*
G36*
G01X955240Y373505D02*
X955878Y373910D01*
X956631Y373475D01*
X956599Y372720D01*
X956512Y372568D01*
X955152Y373353D01*
X955240Y373505D01*
G37*
G36*
G01X951875Y375446D02*
X952513Y375851D01*
X953266Y375416D01*
X953234Y374661D01*
X953147Y374509D01*
X951787Y375295D01*
X951875Y375446D01*
G37*
G36*
G01X965379Y367655D02*
X966017Y368060D01*
X966770Y367625D01*
X966738Y366870D01*
X966651Y366718D01*
X965291Y367503D01*
X965379Y367655D01*
G37*
G36*
G01X962014Y369597D02*
X962652Y370002D01*
X963405Y369567D01*
X963373Y368812D01*
X963286Y368661D01*
X961926Y369445D01*
X962014Y369597D01*
G37*
G36*
G01X965833Y398167D02*
X966593Y397817D01*
Y396917D01*
X965833Y396567D01*
X965658D01*
Y398167D01*
X965833D01*
G37*
G36*
G01Y402067D02*
X966593Y401717D01*
Y400817D01*
X965833Y400467D01*
X965658D01*
Y402067D01*
X965833D01*
G37*
G36*
G01X921015Y371673D02*
X920231Y371383D01*
X919594Y372020D01*
X919884Y372804D01*
X920008Y372928D01*
X921139Y371797D01*
X921015Y371673D01*
G37*
G36*
G01X917904Y373966D02*
X917554Y373206D01*
X916654D01*
X916304Y373966D01*
Y374141D01*
X917904D01*
Y373966D01*
G37*
G36*
G01X913708Y375612D02*
X912922Y375326D01*
X912289Y375965D01*
X912582Y376748D01*
X912706Y376872D01*
X913833Y375735D01*
X913708Y375612D01*
G37*
G36*
G01X910951Y379529D02*
X910191Y379879D01*
Y380779D01*
X910951Y381129D01*
X911126D01*
Y379529D01*
X910951D01*
G37*
G36*
G01X930394Y366464D02*
X929756Y366059D01*
X929003Y366494D01*
X929035Y367249D01*
X929122Y367401D01*
X930482Y366615D01*
X930394Y366464D01*
G37*
G36*
G01X927005Y368419D02*
X926367Y368014D01*
X925614Y368449D01*
X925646Y369204D01*
X925733Y369355D01*
X927093Y368570D01*
X927005Y368419D01*
G37*
G36*
G01X940519Y360623D02*
X939881Y360218D01*
X939128Y360653D01*
X939160Y361408D01*
X939247Y361560D01*
X940607Y360775D01*
X940519Y360623D01*
G37*
G36*
G01X937145Y362569D02*
X936507Y362164D01*
X935754Y362599D01*
X935786Y363354D01*
X935873Y363505D01*
X937233Y362720D01*
X937145Y362569D01*
G37*
G36*
G01X933759Y364523D02*
X933121Y364118D01*
X932368Y364553D01*
X932400Y365308D01*
X932487Y365460D01*
X933847Y364675D01*
X933759Y364523D01*
G37*
G36*
G01X943905Y358669D02*
X943267Y358264D01*
X942514Y358699D01*
X942546Y359454D01*
X942633Y359605D01*
X943993Y358820D01*
X943905Y358669D01*
G37*
G36*
G01X933759Y387923D02*
X933121Y387518D01*
X932368Y387953D01*
X932399Y388708D01*
X932486Y388859D01*
X933847Y388074D01*
X933759Y387923D01*
G37*
G36*
G01X940519Y384023D02*
X939881Y383618D01*
X939128Y384053D01*
X939160Y384808D01*
X939247Y384960D01*
X940607Y384175D01*
X940519Y384023D01*
G37*
G36*
G01X937145Y385969D02*
X936507Y385564D01*
X935754Y385999D01*
X935786Y386754D01*
X935873Y386905D01*
X937233Y386120D01*
X937145Y385969D01*
G37*
G36*
G01X932401Y401440D02*
X931641Y401790D01*
Y402690D01*
X932401Y403040D01*
X932576D01*
Y401440D01*
X932401D01*
G37*
G36*
G01X931865Y393599D02*
X931195Y393949D01*
Y394819D01*
X931865Y395169D01*
X932040D01*
Y393599D01*
X931865D01*
G37*
G36*
G01Y397451D02*
X931195Y397801D01*
Y398671D01*
X931865Y399021D01*
X932040D01*
Y397451D01*
X931865D01*
G37*
G36*
G01X931866Y389718D02*
X931196Y390068D01*
Y390938D01*
X931866Y391288D01*
X932040D01*
X932041Y389717D01*
X931866Y389718D01*
G37*
G36*
G01X950665Y378169D02*
X950027Y377764D01*
X949274Y378199D01*
X949306Y378954D01*
X949393Y379105D01*
X950753Y378320D01*
X950665Y378169D01*
G37*
G36*
G01X947279Y380123D02*
X946641Y379718D01*
X945888Y380153D01*
X945920Y380908D01*
X946007Y381060D01*
X947367Y380275D01*
X947279Y380123D01*
G37*
G36*
G01X943905Y382069D02*
X943267Y381664D01*
X942514Y382099D01*
X942546Y382854D01*
X942633Y383005D01*
X943993Y382220D01*
X943905Y382069D01*
G37*
G36*
G01X957424Y374269D02*
X956786Y373864D01*
X956033Y374299D01*
X956065Y375054D01*
X956152Y375205D01*
X957512Y374420D01*
X957424Y374269D01*
G37*
G36*
G01X954039Y376223D02*
X953401Y375818D01*
X952648Y376253D01*
X952680Y377008D01*
X952767Y377160D01*
X954127Y376375D01*
X954039Y376223D01*
G37*
G36*
G01X967831Y401541D02*
X967071Y401891D01*
Y402791D01*
X967831Y403141D01*
X968006D01*
Y401541D01*
X967831D01*
G37*
G36*
G01Y397641D02*
X967071Y397991D01*
Y398891D01*
X967831Y399241D01*
X968006D01*
Y397641D01*
X967831D01*
G37*
G36*
G01X971090Y393998D02*
X970305Y393708D01*
X969669Y394345D01*
X969959Y395130D01*
X970083Y395253D01*
X971214Y394122D01*
X971090Y393998D01*
G37*
G36*
G01X928209Y342300D02*
X928847Y342705D01*
X929600Y342270D01*
X929568Y341515D01*
X929481Y341363D01*
X928121Y342149D01*
X928209Y342300D01*
G37*
G36*
G01X924835Y344246D02*
X925473Y344651D01*
X926226Y344216D01*
X926194Y343461D01*
X926107Y343309D01*
X924747Y344095D01*
X924835Y344246D01*
G37*
G36*
G01X921449Y346200D02*
X922087Y346605D01*
X922840Y346170D01*
X922808Y345415D01*
X922721Y345263D01*
X921361Y346049D01*
X921449Y346200D01*
G37*
G36*
G01X918075Y348146D02*
X918713Y348551D01*
X919466Y348116D01*
X919434Y347361D01*
X919347Y347209D01*
X917987Y347995D01*
X918075Y348146D01*
G37*
G36*
G01X914682Y350104D02*
X915320Y350509D01*
X916073Y350074D01*
X916041Y349319D01*
X915954Y349167D01*
X914594Y349953D01*
X914682Y350104D01*
G37*
G36*
G01Y354004D02*
X915320Y354409D01*
X916073Y353974D01*
X916041Y353219D01*
X915954Y353067D01*
X914594Y353853D01*
X914682Y354004D01*
G37*
G36*
G01X918075Y352046D02*
X918713Y352451D01*
X919466Y352016D01*
X919434Y351261D01*
X919347Y351109D01*
X917987Y351895D01*
X918075Y352046D01*
G37*
G36*
G01X931595Y344246D02*
X932233Y344651D01*
X932986Y344216D01*
X932954Y343461D01*
X932867Y343309D01*
X931507Y344095D01*
X931595Y344246D01*
G37*
G36*
G01X928209Y346200D02*
X928847Y346605D01*
X929600Y346170D01*
X929568Y345415D01*
X929481Y345263D01*
X928121Y346049D01*
X928209Y346200D01*
G37*
G36*
G01X924835Y348146D02*
X925473Y348551D01*
X926226Y348116D01*
X926194Y347361D01*
X926107Y347209D01*
X924747Y347995D01*
X924835Y348146D01*
G37*
G36*
G01X921449Y350100D02*
X922087Y350505D01*
X922840Y350070D01*
X922808Y349315D01*
X922721Y349163D01*
X921361Y349949D01*
X921449Y350100D01*
G37*
G36*
G01X934969Y342300D02*
X935607Y342705D01*
X936360Y342270D01*
X936328Y341515D01*
X936241Y341363D01*
X934881Y342149D01*
X934969Y342300D01*
G37*
G36*
G01X940519Y356723D02*
X939881Y356318D01*
X939128Y356753D01*
X939160Y357508D01*
X939247Y357660D01*
X940607Y356875D01*
X940519Y356723D01*
G37*
G36*
G01X937145Y358669D02*
X936507Y358264D01*
X935754Y358699D01*
X935786Y359454D01*
X935873Y359605D01*
X937233Y358820D01*
X937145Y358669D01*
G37*
G36*
G01X916056Y370966D02*
X915706Y370206D01*
X914806D01*
X914456Y370966D01*
Y371141D01*
X916056D01*
Y370966D01*
G37*
G36*
G01X912441Y372408D02*
X911656Y372118D01*
X911020Y372755D01*
X911310Y373540D01*
X911434Y373663D01*
X912565Y372532D01*
X912441Y372408D01*
G37*
G36*
G01X930385Y362569D02*
X929747Y362164D01*
X928994Y362599D01*
X929026Y363354D01*
X929113Y363505D01*
X930473Y362720D01*
X930385Y362569D01*
G37*
G36*
G01X926999Y364523D02*
X926361Y364118D01*
X925608Y364553D01*
X925640Y365308D01*
X925727Y365460D01*
X927087Y364675D01*
X926999Y364523D01*
G37*
G36*
G01X920676Y367973D02*
X919892Y367683D01*
X919255Y368320D01*
X919545Y369104D01*
X919669Y369228D01*
X920800Y368097D01*
X920676Y367973D01*
G37*
G36*
G01X933759Y360623D02*
X933121Y360218D01*
X932368Y360653D01*
X932400Y361408D01*
X932487Y361560D01*
X933847Y360775D01*
X933759Y360623D01*
G37*
G36*
G01X949854Y357508D02*
X949886Y356753D01*
X949133Y356318D01*
X948495Y356723D01*
X948407Y356875D01*
X949767Y357660D01*
X949854Y357508D01*
G37*
G36*
G01X946439Y355537D02*
X946471Y354782D01*
X945718Y354347D01*
X945080Y354752D01*
X944992Y354903D01*
X946352Y355689D01*
X946439Y355537D01*
G37*
G36*
G01X943934Y354752D02*
X943296Y354347D01*
X942543Y354782D01*
X942575Y355537D01*
X942662Y355689D01*
X944022Y354903D01*
X943934Y354752D01*
G37*
G36*
G01X953189Y359466D02*
X953252Y358713D01*
X952517Y358248D01*
X951863Y358627D01*
X951769Y358774D01*
X953096Y359614D01*
X953189Y359466D01*
G37*
G36*
G01X928555Y387691D02*
X927885Y388041D01*
Y388910D01*
X928555Y389260D01*
X928729Y389261D01*
X928730Y387690D01*
X928555Y387691D01*
G37*
G36*
G01X930448Y385926D02*
X929810Y385521D01*
X929058Y385955D01*
X929090Y386710D01*
X929176Y386862D01*
X930537Y386077D01*
X930448Y385926D01*
G37*
G36*
G01X933759Y384023D02*
X933121Y383618D01*
X932368Y384053D01*
X932400Y384808D01*
X932487Y384960D01*
X933847Y384175D01*
X933759Y384023D01*
G37*
G36*
G01X940519Y380123D02*
X939881Y379718D01*
X939128Y380153D01*
X939160Y380908D01*
X939247Y381060D01*
X940607Y380275D01*
X940519Y380123D01*
G37*
G36*
G01X937145Y382069D02*
X936507Y381664D01*
X935754Y382099D01*
X935786Y382854D01*
X935873Y383005D01*
X937233Y382220D01*
X937145Y382069D01*
G37*
G36*
G01X928485Y391600D02*
X927815Y391950D01*
Y392820D01*
X928485Y393170D01*
X928660D01*
Y391600D01*
X928485D01*
G37*
G36*
G01Y395524D02*
X927815Y395874D01*
Y396744D01*
X928485Y397094D01*
X928660D01*
Y395524D01*
X928485D01*
G37*
G36*
G01X928451Y400451D02*
X927691Y400801D01*
Y401701D01*
X928451Y402051D01*
X928626D01*
Y400451D01*
X928451D01*
G37*
G36*
G01X950665Y374269D02*
X950027Y373864D01*
X949274Y374299D01*
X949306Y375054D01*
X949393Y375205D01*
X950753Y374420D01*
X950665Y374269D01*
G37*
G36*
G01X947279Y376223D02*
X946641Y375818D01*
X945888Y376253D01*
X945920Y377008D01*
X946007Y377160D01*
X947367Y376375D01*
X947279Y376223D01*
G37*
G36*
G01X943905Y378169D02*
X943267Y377764D01*
X942514Y378199D01*
X942546Y378954D01*
X942633Y379105D01*
X943993Y378320D01*
X943905Y378169D01*
G37*
G36*
G01X960804Y368419D02*
X960166Y368014D01*
X959413Y368449D01*
X959445Y369204D01*
X959532Y369355D01*
X960892Y368570D01*
X960804Y368419D01*
G37*
G36*
G01X957418Y370372D02*
X956780Y369967D01*
X956027Y370402D01*
X956059Y371157D01*
X956146Y371309D01*
X957506Y370523D01*
X957418Y370372D01*
G37*
G36*
G01X954054Y372314D02*
X953416Y371909D01*
X952663Y372344D01*
X952695Y373099D01*
X952782Y373251D01*
X954142Y372465D01*
X954054Y372314D01*
G37*
G36*
G01X964193Y366464D02*
X963555Y366059D01*
X962802Y366494D01*
X962834Y367249D01*
X962921Y367401D01*
X964281Y366615D01*
X964193Y366464D01*
G37*
G36*
G01X972432Y385297D02*
X971647Y385007D01*
X971011Y385644D01*
X971301Y386429D01*
X971425Y386552D01*
X972556Y385421D01*
X972432Y385297D01*
G37*
G36*
G01X964733Y396567D02*
X963973Y396917D01*
Y397817D01*
X964733Y398167D01*
X964908D01*
Y396567D01*
X964733D01*
G37*
G36*
G01Y400467D02*
X963973Y400817D01*
Y401717D01*
X964733Y402067D01*
X964908D01*
Y400467D01*
X964733D01*
G37*
G36*
G01X920662Y373582D02*
X921447Y373872D01*
X922083Y373236D01*
X921793Y372451D01*
X921670Y372327D01*
X920538Y373459D01*
X920662Y373582D01*
G37*
G36*
G01X916304Y375066D02*
X916654Y375826D01*
X917554D01*
X917904Y375066D01*
Y374891D01*
X916304D01*
Y375066D01*
G37*
G36*
G01X913363Y377523D02*
X914150Y377809D01*
X914783Y377170D01*
X914490Y376387D01*
X914366Y376263D01*
X913239Y377400D01*
X913363Y377523D01*
G37*
G36*
G01X912051Y381129D02*
X912811Y380779D01*
Y379879D01*
X912051Y379529D01*
X911876D01*
Y381129D01*
X912051D01*
G37*
G36*
G01X931580Y367655D02*
X932218Y368060D01*
X932971Y367625D01*
X932939Y366870D01*
X932852Y366718D01*
X931492Y367503D01*
X931580Y367655D01*
G37*
G36*
G01X928215Y369597D02*
X928853Y370002D01*
X929606Y369567D01*
X929574Y368812D01*
X929487Y368661D01*
X928127Y369445D01*
X928215Y369597D01*
G37*
G36*
G01X924829Y371550D02*
X925467Y371955D01*
X926220Y371520D01*
X926188Y370765D01*
X926101Y370613D01*
X924741Y371399D01*
X924829Y371550D01*
G37*
G36*
G01X938355Y363746D02*
X938993Y364151D01*
X939746Y363716D01*
X939714Y362961D01*
X939627Y362809D01*
X938267Y363595D01*
X938355Y363746D01*
G37*
G36*
G01X934969Y365700D02*
X935607Y366105D01*
X936360Y365670D01*
X936328Y364915D01*
X936241Y364763D01*
X934881Y365549D01*
X934969Y365700D01*
G37*
G36*
G01X941729Y361800D02*
X942367Y362205D01*
X943120Y361770D01*
X943088Y361015D01*
X943001Y360863D01*
X941641Y361649D01*
X941729Y361800D01*
G37*
G36*
G01X934969Y389100D02*
X935607Y389505D01*
X936360Y389070D01*
X936328Y388315D01*
X936241Y388163D01*
X934881Y388949D01*
X934969Y389100D01*
G37*
G36*
G01X938355Y387146D02*
X938993Y387551D01*
X939746Y387116D01*
X939714Y386361D01*
X939627Y386209D01*
X938267Y386995D01*
X938355Y387146D01*
G37*
G36*
G01X933501Y403040D02*
X934261Y402690D01*
Y401790D01*
X933501Y401440D01*
X933326D01*
Y403040D01*
X933501D01*
G37*
G36*
G01X933489Y393170D02*
X934159Y392820D01*
Y391950D01*
X933489Y391600D01*
X933314D01*
Y393170D01*
X933489D01*
G37*
G36*
G01Y397094D02*
X934159Y396744D01*
Y395874D01*
X933489Y395524D01*
X933314D01*
Y397094D01*
X933489D01*
G37*
G36*
G01X948489Y381300D02*
X949127Y381705D01*
X949880Y381270D01*
X949848Y380515D01*
X949761Y380363D01*
X948401Y381149D01*
X948489Y381300D01*
G37*
G36*
G01X945115Y383246D02*
X945753Y383651D01*
X946506Y383216D01*
X946474Y382461D01*
X946387Y382309D01*
X945027Y383095D01*
X945115Y383246D01*
G37*
G36*
G01X941729Y385200D02*
X942367Y385605D01*
X943120Y385170D01*
X943088Y384415D01*
X943001Y384263D01*
X941641Y385049D01*
X941729Y385200D01*
G37*
G36*
G01X958634Y375446D02*
X959272Y375851D01*
X960025Y375416D01*
X959993Y374661D01*
X959906Y374509D01*
X958546Y375295D01*
X958634Y375446D01*
G37*
G36*
G01X955249Y377400D02*
X955887Y377805D01*
X956640Y377370D01*
X956608Y376615D01*
X956521Y376463D01*
X955161Y377249D01*
X955249Y377400D01*
G37*
G36*
G01X951875Y379346D02*
X952513Y379751D01*
X953266Y379316D01*
X953234Y378561D01*
X953147Y378409D01*
X951787Y379195D01*
X951875Y379346D01*
G37*
G36*
G01X970737Y395908D02*
X971522Y396198D01*
X972158Y395561D01*
X971868Y394776D01*
X971744Y394653D01*
X970613Y395784D01*
X970737Y395908D01*
G37*
G36*
G01X968931Y400941D02*
X969691Y400591D01*
Y399691D01*
X968931Y399341D01*
X968756D01*
Y400941D01*
X968931D01*
G37*
G36*
G01X923625Y343069D02*
X922987Y342664D01*
X922234Y343099D01*
X922266Y343854D01*
X922353Y344005D01*
X923713Y343220D01*
X923625Y343069D01*
G37*
G36*
G01X920239Y345023D02*
X919601Y344618D01*
X918848Y345053D01*
X918880Y345808D01*
X918967Y345960D01*
X920327Y345175D01*
X920239Y345023D01*
G37*
G36*
G01X916865Y346969D02*
X916227Y346564D01*
X915474Y346999D01*
X915506Y347754D01*
X915593Y347905D01*
X916953Y347120D01*
X916865Y346969D01*
G37*
G36*
G01X921192Y403058D02*
X920407Y402768D01*
X919771Y403404D01*
X920061Y404189D01*
X920184Y404313D01*
X921316Y403181D01*
X921192Y403058D01*
G37*
G36*
G01X920837Y404965D02*
X921622Y405255D01*
X922258Y404619D01*
X921968Y403834D01*
X921845Y403710D01*
X920713Y404842D01*
X920837Y404965D01*
G37*
G36*
G01X941118Y411936D02*
X940333Y411646D01*
X939696Y412282D01*
X939986Y413067D01*
X940110Y413191D01*
X941241Y412060D01*
X941118Y411936D01*
G37*
G36*
G01X943876Y409178D02*
X943091Y408888D01*
X942454Y409524D01*
X942744Y410309D01*
X942868Y410433D01*
X943999Y409302D01*
X943876Y409178D01*
G37*
G36*
G01X946086Y404997D02*
X945326Y405347D01*
Y406247D01*
X946086Y406597D01*
X946261D01*
Y404997D01*
X946086D01*
G37*
G36*
G01X939444Y415158D02*
X940229Y415448D01*
X940865Y414812D01*
X940575Y414027D01*
X940452Y413903D01*
X939320Y415034D01*
X939444Y415158D01*
G37*
G36*
G01X942202Y412400D02*
X942987Y412690D01*
X943623Y412054D01*
X943333Y411269D01*
X943210Y411145D01*
X942078Y412276D01*
X942202Y412400D01*
G37*
G36*
G01X947184Y406097D02*
X947944Y405747D01*
Y404847D01*
X947184Y404497D01*
X947009D01*
Y406097D01*
X947184D01*
G37*
G36*
G01X944960Y409642D02*
X945745Y409932D01*
X946381Y409296D01*
X946091Y408511D01*
X945968Y408387D01*
X944836Y409518D01*
X944960Y409642D01*
G37*
G36*
G01X938129Y406568D02*
X937344Y406278D01*
X936708Y406914D01*
X936998Y407699D01*
X937121Y407823D01*
X938253Y406691D01*
X938129Y406568D01*
G37*
G36*
G01X935629Y409068D02*
X934844Y408778D01*
X934208Y409414D01*
X934498Y410199D01*
X934621Y410323D01*
X935753Y409191D01*
X935629Y409068D01*
G37*
G36*
G01X937774Y408475D02*
X938559Y408765D01*
X939195Y408129D01*
X938905Y407344D01*
X938782Y407220D01*
X937650Y408352D01*
X937774Y408475D01*
G37*
G36*
G01X935274Y410975D02*
X936059Y411265D01*
X936695Y410629D01*
X936405Y409844D01*
X936282Y409720D01*
X935150Y410852D01*
X935274Y410975D01*
G37*
G36*
G01X940283Y405783D02*
X941043Y405433D01*
Y404533D01*
X940283Y404183D01*
X940108D01*
Y405783D01*
X940283D01*
G37*
G36*
G01X928120Y404668D02*
X928905Y404958D01*
X929541Y404322D01*
X929251Y403537D01*
X929128Y403413D01*
X927996Y404545D01*
X928120Y404668D01*
G37*
G36*
G01X925362Y407426D02*
X926147Y407716D01*
X926783Y407080D01*
X926493Y406295D01*
X926370Y406171D01*
X925238Y407303D01*
X925362Y407426D01*
G37*
G36*
G01X932311Y404509D02*
X931526Y404219D01*
X930890Y404855D01*
X931180Y405640D01*
X931303Y405764D01*
X932435Y404632D01*
X932311Y404509D01*
G37*
G36*
G01X929553Y407267D02*
X928768Y406977D01*
X928132Y407613D01*
X928422Y408398D01*
X928545Y408522D01*
X929677Y407390D01*
X929553Y407267D01*
G37*
G36*
G01X968963Y405213D02*
X968203Y405563D01*
Y406463D01*
X968963Y406813D01*
X969138D01*
Y405213D01*
X968963D01*
G37*
G36*
G01X926715Y404517D02*
X925931Y404227D01*
X925294Y404864D01*
X925584Y405648D01*
X925708Y405772D01*
X926839Y404641D01*
X926715Y404517D01*
G37*
G36*
G01X931993Y406453D02*
X932778Y406743D01*
X933414Y406107D01*
X933124Y405322D01*
X933001Y405198D01*
X931869Y406330D01*
X931993Y406453D01*
G37*
G36*
G01X926477Y411969D02*
X927262Y412259D01*
X927898Y411623D01*
X927608Y410838D01*
X927485Y410714D01*
X926353Y411846D01*
X926477Y411969D01*
G37*
G36*
G01X929235Y409211D02*
X930020Y409501D01*
X930656Y408865D01*
X930366Y408080D01*
X930243Y407956D01*
X929111Y409088D01*
X929235Y409211D01*
G37*
G36*
G01X970063Y406813D02*
X970823Y406463D01*
Y405563D01*
X970063Y405213D01*
X969888D01*
Y406813D01*
X970063D01*
G37*
G36*
G01X1019072Y-11100D02*
G02X1018727Y-10497I0J400D01*
G03X1016589Y-8737I-1208J711D01*
G02X1016041Y-8721I-265J299D01*
G01X1013330Y-6010D01*
Y-3605D01*
G02X1013828Y-3217I400J0D01*
G03Y-499I345J1359D01*
G02X1013330Y-111I-98J388D01*
G01Y7367D01*
G02X1013828Y7755I400J0D01*
G03Y10473I345J1359D01*
G02X1013330Y10861I-98J388D01*
G01Y16096D01*
G03X1013437Y16238I-1064J913D01*
G02X1013768Y16241I167J-111D01*
G03X1015930Y16071I1151J801D01*
G02X1016508I289J-277D01*
G03Y18013I1011J971D01*
G02X1015930I-289J277D01*
G03X1013752Y17818I-1011J-971D01*
G02X1013421Y17815I-167J111D01*
G03X1013330Y17932I-1151J-801D01*
G01Y26267D01*
G02X1013828Y26655I400J0D01*
G03Y29373I345J1359D01*
G02X1013330Y29761I-98J388D01*
G01Y34195D01*
G02X1013828Y34583I400J0D01*
G03Y37301I345J1359D01*
G02X1013330Y37689I-98J388D01*
G01Y40320D01*
X1014820Y41810D01*
X1025970D01*
X1030694Y37086D01*
Y28593D01*
X1034220Y25067D01*
Y15948D01*
X1034219Y15936D01*
G03X1034196Y15528I3578J-406D01*
G01Y10628D01*
G03X1034219Y10220I3601J-2D01*
G01X1034220Y10208D01*
Y-2952D01*
X1034219Y-2964D01*
G03X1034196Y-3372I3578J-406D01*
G01Y-6844D01*
X1032397Y-8643D01*
G02X1031735Y-8489I-283J283D01*
G03X1030373Y-7536I-1328J-449D01*
G02X1029981Y-7021I-9J400D01*
G03X1028673Y-8017I-1342J406D01*
G02X1029065Y-8532I9J-400D01*
G03X1029958Y-10266I1342J-406D01*
G02X1030112Y-10928I-129J-379D01*
G01X1029940Y-11100D01*
X1028613D01*
X1028601Y-10913D01*
G03X1025803I-1399J-92D01*
G01X1025791Y-11100D01*
X1019072D01*
G37*
G36*
G01X973300Y214050D02*
X972540Y214400D01*
Y215300D01*
X973300Y215650D01*
X973475D01*
Y214050D01*
X973300D01*
G37*
G36*
G01X974034Y217244D02*
X973744Y218028D01*
X974380Y218665D01*
X975165Y218375D01*
X975289Y218251D01*
X974157Y217120D01*
X974034Y217244D01*
G37*
G36*
G01X974399Y215513D02*
X975160Y215163D01*
Y214263D01*
X974399Y213913D01*
X974225Y213912D01*
Y215513D01*
X974399D01*
G37*
G36*
G01X976157Y217813D02*
X976447Y217029D01*
X975810Y216392D01*
X975026Y216682D01*
X974902Y216806D01*
X976033Y217937D01*
X976157Y217813D01*
G37*
G36*
G01X983127Y201839D02*
X982837Y202624D01*
X983473Y203260D01*
X984258Y202970D01*
X984382Y202847D01*
X983250Y201715D01*
X983127Y201839D01*
G37*
G36*
G01X985911Y205886D02*
X985151Y206236D01*
Y207136D01*
X985911Y207486D01*
X986086D01*
Y205886D01*
X985911D01*
G37*
G36*
G01Y209786D02*
X985151Y210136D01*
Y211036D01*
X985911Y211386D01*
X986086D01*
Y209786D01*
X985911D01*
G37*
G36*
G01X989324Y216149D02*
X988654Y216499D01*
Y217369D01*
X989324Y217719D01*
X989499D01*
Y216149D01*
X989324D01*
G37*
G36*
G01X983042Y196408D02*
X982257Y196118D01*
X981621Y196754D01*
X981911Y197539D01*
X982034Y197663D01*
X983166Y196531D01*
X983042Y196408D01*
G37*
G36*
G01X985035Y202193D02*
X985325Y201408D01*
X984689Y200772D01*
X983904Y201062D01*
X983780Y201185D01*
X984912Y202317D01*
X985035Y202193D01*
G37*
G36*
G01X987011Y209893D02*
X987771Y209543D01*
Y208643D01*
X987011Y208293D01*
X986836D01*
Y209893D01*
X987011D01*
G37*
G36*
G01Y205993D02*
X987771Y205643D01*
Y204743D01*
X987011Y204393D01*
X986836D01*
Y205993D01*
X987011D01*
G37*
G36*
G01X990950Y215756D02*
X991619Y215404D01*
X991616Y214535D01*
X990946Y214187D01*
X990771D01*
X990774Y215757D01*
X990950Y215756D01*
G37*
G36*
G01X978530Y202891D02*
X978240Y203675D01*
X978877Y204312D01*
X979661Y204022D01*
X979785Y203898D01*
X978654Y202767D01*
X978530Y202891D01*
G37*
G36*
G01X978058Y199080D02*
X977298Y199429D01*
Y200330D01*
X978058Y200679D01*
X978233D01*
Y199080D01*
X978058D01*
G37*
G36*
G01X981330Y205691D02*
X981040Y206475D01*
X981677Y207112D01*
X982461Y206822D01*
X982585Y206698D01*
X981454Y205567D01*
X981330Y205691D01*
G37*
G36*
G01X982885Y209119D02*
X982125Y209469D01*
Y210369D01*
X982885Y210719D01*
X983060D01*
Y209119D01*
X982885D01*
G37*
G36*
G01X983996Y213847D02*
X983706Y214631D01*
X984343Y215268D01*
X985127Y214978D01*
X985251Y214854D01*
X984120Y213723D01*
X983996Y213847D01*
G37*
G36*
G01X981866Y204671D02*
X982156Y203887D01*
X981519Y203250D01*
X980735Y203540D01*
X980611Y203664D01*
X981742Y204795D01*
X981866Y204671D01*
G37*
G36*
G01X979157Y200228D02*
X979917Y199879D01*
Y198978D01*
X979157Y198628D01*
X978982D01*
Y200228D01*
X979157D01*
G37*
G36*
G01X985906Y214199D02*
X986196Y213415D01*
X985559Y212778D01*
X984775Y213068D01*
X984651Y213192D01*
X985782Y214323D01*
X985906Y214199D01*
G37*
G36*
G01X983985Y210719D02*
X984745Y210369D01*
Y209469D01*
X983985Y209119D01*
X983810D01*
Y210719D01*
X983985D01*
G37*
G36*
G01X987568Y217719D02*
X988238Y217369D01*
Y216499D01*
X987568Y216149D01*
X987393D01*
Y217719D01*
X987568D01*
G37*
G36*
G01X977333Y209081D02*
X977623Y208297D01*
X976986Y207660D01*
X976202Y207950D01*
X976078Y208074D01*
X977209Y209205D01*
X977333Y209081D01*
G37*
G36*
G01X977781Y214156D02*
X978541Y213806D01*
Y212906D01*
X977781Y212556D01*
X977606D01*
Y214156D01*
X977781D01*
G37*
G36*
G01X979889Y218493D02*
X980294Y217854D01*
X979859Y217101D01*
X979104Y217133D01*
X978952Y217220D01*
X979738Y218580D01*
X979889Y218493D01*
G37*
G36*
G01X974533Y206281D02*
X974823Y205497D01*
X974186Y204860D01*
X973402Y205150D01*
X973278Y205274D01*
X974409Y206405D01*
X974533Y206281D01*
G37*
G36*
G01X976308Y202347D02*
X977068Y201998D01*
Y201097D01*
X976308Y200748D01*
X976133D01*
Y202347D01*
X976308D01*
G37*
G36*
G01X979148Y206214D02*
X979438Y205430D01*
X978801Y204793D01*
X978017Y205083D01*
X977893Y205207D01*
X979024Y206338D01*
X979148Y206214D01*
G37*
G36*
G01X980959Y211363D02*
X981719Y211013D01*
Y210113D01*
X980959Y209763D01*
X980784D01*
Y211363D01*
X980959D01*
G37*
G36*
G01X974924Y208228D02*
X974634Y209013D01*
X975270Y209649D01*
X976055Y209359D01*
X976179Y209236D01*
X975047Y208104D01*
X974924Y208228D01*
G37*
G36*
G01X976681Y212056D02*
X975921Y212406D01*
Y213306D01*
X976681Y213656D01*
X976856D01*
Y212056D01*
X976681D01*
G37*
G36*
G01X978098Y217590D02*
X977693Y218228D01*
X978128Y218982D01*
X978883Y218950D01*
X979035Y218862D01*
X978250Y217503D01*
X978098Y217590D01*
G37*
G36*
G01X972024Y205328D02*
X971734Y206113D01*
X972370Y206749D01*
X973155Y206459D01*
X973279Y206336D01*
X972147Y205204D01*
X972024Y205328D01*
G37*
G36*
G01X975209Y198504D02*
X974449Y198854D01*
Y199753D01*
X975209Y200103D01*
X975384Y200104D01*
Y198503D01*
X975209Y198504D01*
G37*
G36*
G01X977239Y205861D02*
X976949Y206646D01*
X977585Y207282D01*
X978370Y206992D01*
X978494Y206869D01*
X977362Y205737D01*
X977239Y205861D01*
G37*
G36*
G01X979859Y209763D02*
X979099Y210113D01*
Y211013D01*
X979859Y211363D01*
X980034D01*
Y209763D01*
X979859D01*
G37*
G36*
G01X975788Y219315D02*
X975118Y219665D01*
Y220535D01*
X975788Y220885D01*
X975963D01*
Y219315D01*
X975788D01*
G37*
G36*
G01X975804Y223949D02*
X975134Y224299D01*
Y225169D01*
X975804Y225519D01*
X975979D01*
Y223949D01*
X975804D01*
G37*
G36*
G01Y227800D02*
X975134Y228150D01*
Y229020D01*
X975804Y229370D01*
X975979D01*
Y227800D01*
X975804D01*
G37*
G36*
G01Y231724D02*
X975134Y232074D01*
Y232944D01*
X975804Y233294D01*
X975979D01*
Y231724D01*
X975804D01*
G37*
G36*
G01Y235649D02*
X975134Y235999D01*
Y236869D01*
X975804Y237219D01*
X975979D01*
Y235649D01*
X975804D01*
G37*
G36*
G01Y239549D02*
X975134Y239899D01*
Y240769D01*
X975804Y241119D01*
X975979D01*
Y239549D01*
X975804D01*
G37*
G36*
G01Y243449D02*
X975134Y243799D01*
Y244669D01*
X975804Y245019D01*
X975979D01*
Y243449D01*
X975804D01*
G37*
G36*
G01Y247349D02*
X975134Y247699D01*
Y248569D01*
X975804Y248919D01*
X975979D01*
Y247349D01*
X975804D01*
G37*
G36*
G01Y251225D02*
X975134Y251575D01*
Y252445D01*
X975804Y252795D01*
X975979D01*
Y251225D01*
X975804D01*
G37*
G36*
G01X976564Y253971D02*
X976216Y254642D01*
X976715Y255355D01*
X977465Y255257D01*
X977608Y255157D01*
X976708Y253871D01*
X976564Y253971D01*
G37*
G36*
G01X977428Y223520D02*
X978098Y223170D01*
Y222300D01*
X977428Y221950D01*
X977253D01*
Y223520D01*
X977428D01*
G37*
G36*
G01Y235220D02*
X978098Y234870D01*
Y234000D01*
X977428Y233650D01*
X977253D01*
Y235220D01*
X977428D01*
G37*
G36*
G01Y231369D02*
X978098Y231019D01*
Y230149D01*
X977428Y229799D01*
X977253D01*
Y231369D01*
X977428D01*
G37*
G36*
G01Y227445D02*
X978098Y227095D01*
Y226225D01*
X977428Y225875D01*
X977253D01*
Y227445D01*
X977428D01*
G37*
G36*
G01X977427Y250845D02*
X978097Y250495D01*
Y249625D01*
X977427Y249275D01*
X977252D01*
Y250845D01*
X977427D01*
G37*
G36*
G01X977428Y246920D02*
X978098Y246570D01*
Y245700D01*
X977428Y245350D01*
X977253D01*
Y246920D01*
X977428D01*
G37*
G36*
G01Y243020D02*
X978098Y242670D01*
Y241800D01*
X977428Y241450D01*
X977253D01*
Y243020D01*
X977428D01*
G37*
G36*
G01Y239120D02*
X978098Y238770D01*
Y237900D01*
X977428Y237550D01*
X977253D01*
Y239120D01*
X977428D01*
G37*
G36*
G01X978346Y258283D02*
X979045Y258571D01*
X979711Y258012D01*
X979549Y257273D01*
X979436Y257139D01*
X978234Y258149D01*
X978346Y258283D01*
G37*
G36*
G01X976995Y261160D02*
X976522Y261750D01*
X976871Y262546D01*
X977626Y262599D01*
X977786Y262528D01*
X977155Y261090D01*
X976995Y261160D01*
G37*
G36*
G01X989324Y220049D02*
X988654Y220399D01*
Y221269D01*
X989324Y221619D01*
X989499D01*
Y220049D01*
X989324D01*
G37*
G36*
G01Y223949D02*
X988654Y224299D01*
Y225169D01*
X989324Y225519D01*
X989499D01*
Y223949D01*
X989324D01*
G37*
G36*
G01Y231724D02*
X988654Y232074D01*
Y232944D01*
X989324Y233294D01*
X989499D01*
Y231724D01*
X989324D01*
G37*
G36*
G01Y227800D02*
X988654Y228150D01*
Y229020D01*
X989324Y229370D01*
X989499D01*
Y227800D01*
X989324D01*
G37*
G36*
G01Y251249D02*
X988654Y251599D01*
Y252469D01*
X989324Y252819D01*
X989499D01*
Y251249D01*
X989324D01*
G37*
G36*
G01Y247349D02*
X988654Y247699D01*
Y248569D01*
X989324Y248919D01*
X989499D01*
Y247349D01*
X989324D01*
G37*
G36*
G01Y243449D02*
X988654Y243799D01*
Y244669D01*
X989324Y245019D01*
X989499D01*
Y243449D01*
X989324D01*
G37*
G36*
G01Y239549D02*
X988654Y239899D01*
Y240769D01*
X989324Y241119D01*
X989499D01*
Y239549D01*
X989324D01*
G37*
G36*
G01Y235649D02*
X988654Y235999D01*
Y236869D01*
X989324Y237219D01*
X989499D01*
Y235649D01*
X989324D01*
G37*
G36*
G01X990948Y219620D02*
X991618Y219270D01*
Y218400D01*
X990948Y218050D01*
X990773D01*
Y219620D01*
X990948D01*
G37*
G36*
G01Y223520D02*
X991618Y223170D01*
Y222300D01*
X990948Y221950D01*
X990773D01*
Y223520D01*
X990948D01*
G37*
G36*
G01Y227445D02*
X991618Y227095D01*
Y226225D01*
X990948Y225875D01*
X990773D01*
Y227445D01*
X990948D01*
G37*
G36*
G01Y231369D02*
X991618Y231019D01*
Y230149D01*
X990948Y229799D01*
X990773D01*
Y231369D01*
X990948D01*
G37*
G36*
G01Y235220D02*
X991618Y234870D01*
Y234000D01*
X990948Y233650D01*
X990773D01*
Y235220D01*
X990948D01*
G37*
G36*
G01Y239120D02*
X991618Y238770D01*
Y237900D01*
X990948Y237550D01*
X990773D01*
Y239120D01*
X990948D01*
G37*
G36*
G01Y243020D02*
X991618Y242670D01*
Y241800D01*
X990948Y241450D01*
X990773D01*
Y243020D01*
X990948D01*
G37*
G36*
G01Y246920D02*
X991618Y246570D01*
Y245700D01*
X990948Y245350D01*
X990773D01*
Y246920D01*
X990948D01*
G37*
G36*
G01Y250820D02*
X991618Y250470D01*
Y249600D01*
X990948Y249250D01*
X990773D01*
Y250820D01*
X990948D01*
G37*
G36*
G01Y254720D02*
X991618Y254370D01*
Y253500D01*
X990948Y253150D01*
X990773D01*
Y254720D01*
X990948D01*
G37*
G36*
G01Y258620D02*
X991618Y258270D01*
Y257400D01*
X990948Y257050D01*
X990773D01*
Y258620D01*
X990948D01*
G37*
G36*
G01X972424Y233650D02*
X971754Y234000D01*
Y234870D01*
X972424Y235220D01*
X972599D01*
Y233650D01*
X972424D01*
G37*
G36*
G01Y229799D02*
X971754Y230149D01*
Y231019D01*
X972424Y231369D01*
X972599D01*
Y229799D01*
X972424D01*
G37*
G36*
G01Y225875D02*
X971754Y226225D01*
Y227095D01*
X972424Y227445D01*
X972599D01*
Y225875D01*
X972424D01*
G37*
G36*
G01Y221950D02*
X971754Y222300D01*
Y223170D01*
X972424Y223520D01*
X972599D01*
Y221950D01*
X972424D01*
G37*
G36*
G01Y245350D02*
X971754Y245700D01*
Y246570D01*
X972424Y246920D01*
X972599D01*
Y245350D01*
X972424D01*
G37*
G36*
G01Y241450D02*
X971754Y241800D01*
Y242670D01*
X972424Y243020D01*
X972599D01*
Y241450D01*
X972424D01*
G37*
G36*
G01Y237550D02*
X971754Y237900D01*
Y238770D01*
X972424Y239120D01*
X972599D01*
Y237550D01*
X972424D01*
G37*
G36*
G01Y249250D02*
X971754Y249600D01*
Y250470D01*
X972424Y250820D01*
X972599D01*
Y249250D01*
X972424D01*
G37*
G36*
G01Y253150D02*
X971754Y253500D01*
Y254370D01*
X972424Y254720D01*
X972599D01*
Y253150D01*
X972424D01*
G37*
G36*
G01X974048Y221594D02*
X974718Y221244D01*
Y220374D01*
X974048Y220024D01*
X973873D01*
Y221594D01*
X974048D01*
G37*
G36*
G01Y225519D02*
X974718Y225169D01*
Y224299D01*
X974048Y223949D01*
X973873D01*
Y225519D01*
X974048D01*
G37*
G36*
G01Y233294D02*
X974718Y232944D01*
Y232074D01*
X974048Y231724D01*
X973873D01*
Y233294D01*
X974048D01*
G37*
G36*
G01Y229370D02*
X974718Y229020D01*
Y228150D01*
X974048Y227800D01*
X973873D01*
Y229370D01*
X974048D01*
G37*
G36*
G01Y237219D02*
X974718Y236869D01*
Y235999D01*
X974048Y235649D01*
X973873D01*
Y237219D01*
X974048D01*
G37*
G36*
G01Y241119D02*
X974718Y240769D01*
Y239899D01*
X974048Y239549D01*
X973873D01*
Y241119D01*
X974048D01*
G37*
G36*
G01Y245019D02*
X974718Y244669D01*
Y243799D01*
X974048Y243449D01*
X973873D01*
Y245019D01*
X974048D01*
G37*
G36*
G01Y248919D02*
X974718Y248569D01*
Y247699D01*
X974048Y247349D01*
X973873D01*
Y248919D01*
X974048D01*
G37*
G36*
G01Y252819D02*
X974718Y252469D01*
Y251599D01*
X974048Y251249D01*
X973873D01*
Y252819D01*
X974048D01*
G37*
G36*
G01X985944Y218099D02*
X985274Y218449D01*
Y219319D01*
X985944Y219669D01*
X986119D01*
Y218099D01*
X985944D01*
G37*
G36*
G01Y221950D02*
X985274Y222300D01*
Y223170D01*
X985944Y223520D01*
X986119D01*
Y221950D01*
X985944D01*
G37*
G36*
G01Y233650D02*
X985274Y234000D01*
Y234870D01*
X985944Y235220D01*
X986119D01*
Y233650D01*
X985944D01*
G37*
G36*
G01Y229799D02*
X985274Y230149D01*
Y231019D01*
X985944Y231369D01*
X986119D01*
Y229799D01*
X985944D01*
G37*
G36*
G01Y225875D02*
X985274Y226225D01*
Y227095D01*
X985944Y227445D01*
X986119D01*
Y225875D01*
X985944D01*
G37*
G36*
G01X985945Y249275D02*
X985275Y249625D01*
Y250495D01*
X985945Y250845D01*
X986120D01*
Y249275D01*
X985945D01*
G37*
G36*
G01X985944Y245350D02*
X985274Y245700D01*
Y246570D01*
X985944Y246920D01*
X986119D01*
Y245350D01*
X985944D01*
G37*
G36*
G01Y241450D02*
X985274Y241800D01*
Y242670D01*
X985944Y243020D01*
X986119D01*
Y241450D01*
X985944D01*
G37*
G36*
G01Y237550D02*
X985274Y237900D01*
Y238770D01*
X985944Y239120D01*
X986119D01*
Y237550D01*
X985944D01*
G37*
G36*
G01X987568Y221619D02*
X988238Y221269D01*
Y220399D01*
X987568Y220049D01*
X987393D01*
Y221619D01*
X987568D01*
G37*
G36*
G01Y225519D02*
X988238Y225169D01*
Y224299D01*
X987568Y223949D01*
X987393D01*
Y225519D01*
X987568D01*
G37*
G36*
G01Y233294D02*
X988238Y232944D01*
Y232074D01*
X987568Y231724D01*
X987393D01*
Y233294D01*
X987568D01*
G37*
G36*
G01Y229370D02*
X988238Y229020D01*
Y228150D01*
X987568Y227800D01*
X987393D01*
Y229370D01*
X987568D01*
G37*
G36*
G01Y252795D02*
X988238Y252445D01*
Y251575D01*
X987568Y251225D01*
X987393D01*
Y252795D01*
X987568D01*
G37*
G36*
G01Y248919D02*
X988238Y248569D01*
Y247699D01*
X987568Y247349D01*
X987393D01*
Y248919D01*
X987568D01*
G37*
G36*
G01Y245019D02*
X988238Y244669D01*
Y243799D01*
X987568Y243449D01*
X987393D01*
Y245019D01*
X987568D01*
G37*
G36*
G01Y241119D02*
X988238Y240769D01*
Y239899D01*
X987568Y239549D01*
X987393D01*
Y241119D01*
X987568D01*
G37*
G36*
G01Y237219D02*
X988238Y236869D01*
Y235999D01*
X987568Y235649D01*
X987393D01*
Y237219D01*
X987568D01*
G37*
G36*
G01Y256695D02*
X988238Y256345D01*
Y255475D01*
X987568Y255125D01*
X987393D01*
Y256695D01*
X987568D01*
G37*
G36*
G01X980808Y221619D02*
X981478Y221269D01*
Y220399D01*
X980808Y220049D01*
X980633D01*
Y221619D01*
X980808D01*
G37*
G36*
G01Y225519D02*
X981478Y225169D01*
Y224299D01*
X980808Y223949D01*
X980633D01*
Y225519D01*
X980808D01*
G37*
G36*
G01Y229370D02*
X981478Y229020D01*
Y228150D01*
X980808Y227800D01*
X980633D01*
Y229370D01*
X980808D01*
G37*
G36*
G01Y233294D02*
X981478Y232944D01*
Y232074D01*
X980808Y231724D01*
X980633D01*
Y233294D01*
X980808D01*
G37*
G36*
G01Y237219D02*
X981478Y236869D01*
Y235999D01*
X980808Y235649D01*
X980633D01*
Y237219D01*
X980808D01*
G37*
G36*
G01Y241119D02*
X981478Y240769D01*
Y239899D01*
X980808Y239549D01*
X980633D01*
Y241119D01*
X980808D01*
G37*
G36*
G01Y245019D02*
X981478Y244669D01*
Y243799D01*
X980808Y243449D01*
X980633D01*
Y245019D01*
X980808D01*
G37*
G36*
G01Y248919D02*
X981478Y248569D01*
Y247699D01*
X980808Y247349D01*
X980633D01*
Y248919D01*
X980808D01*
G37*
G36*
G01X984188Y219620D02*
X984858Y219270D01*
Y218400D01*
X984188Y218050D01*
X984013D01*
Y219620D01*
X984188D01*
G37*
G36*
G01Y223520D02*
X984858Y223170D01*
Y222300D01*
X984188Y221950D01*
X984013D01*
Y223520D01*
X984188D01*
G37*
G36*
G01Y235220D02*
X984858Y234870D01*
Y234000D01*
X984188Y233650D01*
X984013D01*
Y235220D01*
X984188D01*
G37*
G36*
G01Y231369D02*
X984858Y231019D01*
Y230149D01*
X984188Y229799D01*
X984013D01*
Y231369D01*
X984188D01*
G37*
G36*
G01Y227445D02*
X984858Y227095D01*
Y226225D01*
X984188Y225875D01*
X984013D01*
Y227445D01*
X984188D01*
G37*
G36*
G01Y250820D02*
X984858Y250470D01*
Y249600D01*
X984188Y249250D01*
X984013D01*
Y250820D01*
X984188D01*
G37*
G36*
G01Y246920D02*
X984858Y246570D01*
Y245700D01*
X984188Y245350D01*
X984013D01*
Y246920D01*
X984188D01*
G37*
G36*
G01Y243020D02*
X984858Y242670D01*
Y241800D01*
X984188Y241450D01*
X984013D01*
Y243020D01*
X984188D01*
G37*
G36*
G01Y239120D02*
X984858Y238770D01*
Y237900D01*
X984188Y237550D01*
X984013D01*
Y239120D01*
X984188D01*
G37*
G36*
G01Y254720D02*
X984858Y254370D01*
Y253500D01*
X984188Y253150D01*
X984013D01*
Y254720D01*
X984188D01*
G37*
G36*
G01X984172Y262559D02*
X984848Y262219D01*
X984862Y261350D01*
X984197Y260990D01*
X984023Y260987D01*
X983997Y262556D01*
X984172Y262559D01*
G37*
G36*
G01X984188Y258620D02*
X984858Y258270D01*
Y257400D01*
X984188Y257050D01*
X984013D01*
Y258620D01*
X984188D01*
G37*
G36*
G01X979184Y221950D02*
X978514Y222300D01*
Y223170D01*
X979184Y223520D01*
X979359D01*
Y221950D01*
X979184D01*
G37*
G36*
G01Y225875D02*
X978514Y226225D01*
Y227095D01*
X979184Y227445D01*
X979359D01*
Y225875D01*
X979184D01*
G37*
G36*
G01Y229799D02*
X978514Y230149D01*
Y231019D01*
X979184Y231369D01*
X979359D01*
Y229799D01*
X979184D01*
G37*
G36*
G01Y233650D02*
X978514Y234000D01*
Y234870D01*
X979184Y235220D01*
X979359D01*
Y233650D01*
X979184D01*
G37*
G36*
G01Y237550D02*
X978514Y237900D01*
Y238770D01*
X979184Y239120D01*
X979359D01*
Y237550D01*
X979184D01*
G37*
G36*
G01Y241450D02*
X978514Y241800D01*
Y242670D01*
X979184Y243020D01*
X979359D01*
Y241450D01*
X979184D01*
G37*
G36*
G01Y245350D02*
X978514Y245700D01*
Y246570D01*
X979184Y246920D01*
X979359D01*
Y245350D01*
X979184D01*
G37*
G36*
G01Y249250D02*
X978514Y249600D01*
Y250470D01*
X979184Y250820D01*
X979359D01*
Y249250D01*
X979184D01*
G37*
G36*
G01X982564Y220049D02*
X981894Y220399D01*
Y221269D01*
X982564Y221619D01*
X982739D01*
Y220049D01*
X982564D01*
G37*
G36*
G01Y223949D02*
X981894Y224299D01*
Y225169D01*
X982564Y225519D01*
X982739D01*
Y223949D01*
X982564D01*
G37*
G36*
G01Y231724D02*
X981894Y232074D01*
Y232944D01*
X982564Y233294D01*
X982739D01*
Y231724D01*
X982564D01*
G37*
G36*
G01Y227800D02*
X981894Y228150D01*
Y229020D01*
X982564Y229370D01*
X982739D01*
Y227800D01*
X982564D01*
G37*
G36*
G01Y251249D02*
X981894Y251599D01*
Y252469D01*
X982564Y252819D01*
X982739D01*
Y251249D01*
X982564D01*
G37*
G36*
G01Y247349D02*
X981894Y247699D01*
Y248569D01*
X982564Y248919D01*
X982739D01*
Y247349D01*
X982564D01*
G37*
G36*
G01Y243449D02*
X981894Y243799D01*
Y244669D01*
X982564Y245019D01*
X982739D01*
Y243449D01*
X982564D01*
G37*
G36*
G01Y239549D02*
X981894Y239899D01*
Y240769D01*
X982564Y241119D01*
X982739D01*
Y239549D01*
X982564D01*
G37*
G36*
G01Y235649D02*
X981894Y235999D01*
Y236869D01*
X982564Y237219D01*
X982739D01*
Y235649D01*
X982564D01*
G37*
G36*
G01Y255149D02*
X981894Y255499D01*
Y256369D01*
X982564Y256719D01*
X982739D01*
Y255149D01*
X982564D01*
G37*
G36*
G01Y259049D02*
X981894Y259399D01*
Y260269D01*
X982564Y260619D01*
X982739D01*
Y259049D01*
X982564D01*
G37*
G36*
G01X990075Y340944D02*
X989405Y341294D01*
Y342164D01*
X990075Y342514D01*
X990250D01*
Y340944D01*
X990075D01*
G37*
G36*
G01X975804Y340949D02*
X975134Y341299D01*
Y342169D01*
X975804Y342519D01*
X975979D01*
Y340949D01*
X975804D01*
G37*
G36*
G01X987568Y342519D02*
X988238Y342169D01*
Y341299D01*
X987568Y340949D01*
X987393D01*
Y342519D01*
X987568D01*
G37*
G36*
G01X986695Y338955D02*
X986025Y339305D01*
Y340175D01*
X986695Y340525D01*
X986870D01*
Y338955D01*
X986695D01*
G37*
G36*
G01X984188Y340520D02*
X984858Y340170D01*
Y339300D01*
X984188Y338950D01*
X984013D01*
Y340520D01*
X984188D01*
G37*
G36*
G01X982564Y340949D02*
X981894Y341299D01*
Y342169D01*
X982564Y342519D01*
X982739D01*
Y340949D01*
X982564D01*
G37*
G36*
G01Y337049D02*
X981894Y337399D01*
Y338269D01*
X982564Y338619D01*
X982739D01*
Y337049D01*
X982564D01*
G37*
G36*
G01X979184Y354576D02*
X978514Y354926D01*
Y355796D01*
X979184Y356146D01*
X979359D01*
Y354576D01*
X979184D01*
G37*
G36*
G01Y358476D02*
X978514Y358826D01*
Y359696D01*
X979184Y360046D01*
X979359D01*
Y358476D01*
X979184D01*
G37*
G36*
G01Y350676D02*
X978514Y351026D01*
Y351896D01*
X979184Y352246D01*
X979359D01*
Y350676D01*
X979184D01*
G37*
G36*
G01X975804Y372124D02*
X975134Y372474D01*
Y373344D01*
X975804Y373694D01*
X975979D01*
Y372124D01*
X975804D01*
G37*
G36*
G01X974339Y376210D02*
X973702Y375805D01*
X972948Y376239D01*
X972980Y376994D01*
X973068Y377147D01*
X974427Y376361D01*
X974339Y376210D01*
G37*
G36*
G01X972424Y377993D02*
X971755Y378343D01*
X971754Y379212D01*
X972424Y379562D01*
X972600Y379563D01*
X972599Y377993D01*
X972424D01*
G37*
G36*
G01X975804Y368200D02*
X975134Y368550D01*
Y369420D01*
X975804Y369770D01*
X975979D01*
Y368200D01*
X975804D01*
G37*
G36*
G01X977734Y362551D02*
X977096Y362146D01*
X976343Y362581D01*
X976375Y363336D01*
X976462Y363488D01*
X977822Y362703D01*
X977734Y362551D01*
G37*
G36*
G01X975805Y364325D02*
X975135Y364675D01*
Y365545D01*
X975805Y365895D01*
X975980D01*
Y364325D01*
X975805D01*
G37*
G36*
G01X979184Y342876D02*
X978514Y343226D01*
Y344096D01*
X979184Y344446D01*
X979359D01*
Y342876D01*
X979184D01*
G37*
G36*
G01Y346776D02*
X978514Y347126D01*
Y347996D01*
X979184Y348346D01*
X979359D01*
Y346776D01*
X979184D01*
G37*
G36*
G01X980808Y358096D02*
X981478Y357746D01*
Y356876D01*
X980808Y356526D01*
X980633D01*
Y358096D01*
X980808D01*
G37*
G36*
G01Y354196D02*
X981478Y353846D01*
Y352976D01*
X980808Y352626D01*
X980633D01*
Y354196D01*
X980808D01*
G37*
G36*
G01X977427Y375610D02*
X978097Y375260D01*
Y374391D01*
X977427Y374041D01*
X977252Y374040D01*
X977253Y375610D01*
X977427D01*
G37*
G36*
G01X975527Y377401D02*
X976165Y377806D01*
X976918Y377372D01*
X976886Y376616D01*
X976799Y376464D01*
X975440Y377250D01*
X975527Y377401D01*
G37*
G36*
G01X974048Y381476D02*
X974717Y381126D01*
X974718Y380257D01*
X974048Y379907D01*
X973872Y379906D01*
Y381477D01*
X974048Y381476D01*
G37*
G36*
G01X977427Y367846D02*
X978097Y367496D01*
Y366626D01*
X977427Y366276D01*
X977252D01*
Y367846D01*
X977427D01*
G37*
G36*
G01X977428Y371769D02*
X978098Y371419D01*
Y370549D01*
X977428Y370199D01*
X977253D01*
Y371769D01*
X977428D01*
G37*
G36*
G01X978877Y363767D02*
X979515Y364173D01*
X980268Y363738D01*
X980237Y362983D01*
X980150Y362831D01*
X978789Y363616D01*
X978877Y363767D01*
G37*
G36*
G01X980807Y361993D02*
X981477Y361644D01*
Y360774D01*
X980808Y360424D01*
X980633Y360423D01*
X980632Y361994D01*
X980807Y361993D01*
G37*
G36*
G01X980808Y350296D02*
X981478Y349946D01*
Y349076D01*
X980808Y348726D01*
X980633D01*
Y350296D01*
X980808D01*
G37*
G36*
G01X986448Y388378D02*
X985663Y388088D01*
X985026Y388724D01*
X985316Y389509D01*
X985440Y389633D01*
X986571Y388502D01*
X986448Y388378D01*
G37*
G36*
G01X988566Y385256D02*
X987733Y385180D01*
X987283Y385959D01*
X987767Y386642D01*
X987918Y386730D01*
X988717Y385344D01*
X988566Y385256D01*
G37*
G36*
G01X989324Y379949D02*
X988654Y380299D01*
Y381169D01*
X989324Y381519D01*
X989499D01*
Y379949D01*
X989324D01*
G37*
G36*
G01Y376049D02*
X988654Y376399D01*
Y377269D01*
X989324Y377619D01*
X989499D01*
Y376049D01*
X989324D01*
G37*
G36*
G01X989325Y372167D02*
X988655Y372517D01*
Y373387D01*
X989325Y373737D01*
X989500D01*
Y372166D01*
X989325Y372167D01*
G37*
G36*
G01X991218Y370372D02*
X990580Y369967D01*
X989827Y370402D01*
X989858Y371157D01*
X989946Y371309D01*
X991306Y370523D01*
X991218Y370372D01*
G37*
G36*
G01X980932Y393893D02*
X980147Y393603D01*
X979511Y394240D01*
X979801Y395025D01*
X979925Y395148D01*
X981056Y394017D01*
X980932Y393893D01*
G37*
G36*
G01X978981Y399608D02*
X978221Y399958D01*
Y400858D01*
X978981Y401208D01*
X979156D01*
Y399608D01*
X978981D01*
G37*
G36*
G01X983690Y391136D02*
X982905Y390846D01*
X982269Y391482D01*
X982559Y392267D01*
X982682Y392391D01*
X983814Y391259D01*
X983690Y391136D01*
G37*
G36*
G01X992704Y346750D02*
X992034Y347100D01*
Y347970D01*
X992704Y348320D01*
X992879D01*
Y346750D01*
X992704D01*
G37*
G36*
G01Y366275D02*
X992034Y366625D01*
Y367495D01*
X992704Y367845D01*
X992879D01*
Y366275D01*
X992704D01*
G37*
G36*
G01Y362350D02*
X992034Y362700D01*
Y363570D01*
X992704Y363920D01*
X992879D01*
Y362350D01*
X992704D01*
G37*
G36*
G01Y350650D02*
X992034Y351000D01*
Y351870D01*
X992704Y352220D01*
X992879D01*
Y350650D01*
X992704D01*
G37*
G36*
G01Y358450D02*
X992034Y358800D01*
Y359670D01*
X992704Y360020D01*
X992879D01*
Y358450D01*
X992704D01*
G37*
G36*
G01Y354550D02*
X992034Y354900D01*
Y355770D01*
X992704Y356120D01*
X992879D01*
Y354550D01*
X992704D01*
G37*
G36*
G01X994328Y350319D02*
X994998Y349969D01*
Y349099D01*
X994328Y348749D01*
X994153D01*
Y350319D01*
X994328D01*
G37*
G36*
G01Y346419D02*
X994998Y346069D01*
Y345199D01*
X994328Y344849D01*
X994153D01*
Y346419D01*
X994328D01*
G37*
G36*
G01X984335Y392043D02*
X985120Y392333D01*
X985756Y391697D01*
X985466Y390912D01*
X985343Y390788D01*
X984211Y391920D01*
X984335Y392043D01*
G37*
G36*
G01X981577Y394801D02*
X982362Y395091D01*
X982999Y394455D01*
X982709Y393670D01*
X982585Y393546D01*
X981454Y394677D01*
X981577Y394801D01*
G37*
G36*
G01X980079Y403708D02*
X980839Y403358D01*
Y402458D01*
X980079Y402108D01*
X979904D01*
Y403708D01*
X980079D01*
G37*
G36*
G01Y399808D02*
X980839Y399458D01*
Y398558D01*
X980079Y398208D01*
X979904D01*
Y399808D01*
X980079D01*
G37*
G36*
G01X994327Y369760D02*
X994997Y369410D01*
Y368541D01*
X994328Y368191D01*
X994152Y368190D01*
X994153Y369760D01*
X994327D01*
G37*
G36*
G01X992427Y371551D02*
X993065Y371956D01*
X993818Y371522D01*
X993786Y370767D01*
X993699Y370614D01*
X992340Y371400D01*
X992427Y371551D01*
G37*
G36*
G01X994328Y365919D02*
X994998Y365569D01*
Y364699D01*
X994328Y364349D01*
X994153D01*
Y365919D01*
X994328D01*
G37*
G36*
G01Y362019D02*
X994998Y361669D01*
Y360799D01*
X994328Y360449D01*
X994153D01*
Y362019D01*
X994328D01*
G37*
G36*
G01X990948Y375620D02*
X991618Y375270D01*
Y374400D01*
X990948Y374050D01*
X990773D01*
Y375620D01*
X990948D01*
G37*
G36*
G01Y379520D02*
X991618Y379170D01*
Y378300D01*
X990948Y377950D01*
X990773D01*
Y379520D01*
X990948D01*
G37*
G36*
G01Y383420D02*
X991618Y383070D01*
Y382200D01*
X990948Y381850D01*
X990773D01*
Y383420D01*
X990948D01*
G37*
G36*
G01X988719Y387191D02*
X989552Y387267D01*
X990001Y386488D01*
X989518Y385805D01*
X989366Y385717D01*
X988567Y387104D01*
X988719Y387191D01*
G37*
G36*
G01X994328Y354219D02*
X994998Y353869D01*
Y352999D01*
X994328Y352649D01*
X994153D01*
Y354219D01*
X994328D01*
G37*
G36*
G01Y358119D02*
X994998Y357769D01*
Y356899D01*
X994328Y356549D01*
X994153D01*
Y358119D01*
X994328D01*
G37*
G36*
G01X975804Y356549D02*
X975134Y356899D01*
Y357769D01*
X975804Y358119D01*
X975979D01*
Y356549D01*
X975804D01*
G37*
G36*
G01Y352649D02*
X975134Y352999D01*
Y353869D01*
X975804Y354219D01*
X975979D01*
Y352649D01*
X975804D01*
G37*
G36*
G01X974339Y360610D02*
X973702Y360205D01*
X972948Y360639D01*
X972980Y361394D01*
X973068Y361547D01*
X974427Y360761D01*
X974339Y360610D01*
G37*
G36*
G01X972424Y366275D02*
X971754Y366625D01*
Y367495D01*
X972424Y367845D01*
X972599D01*
Y366275D01*
X972424D01*
G37*
G36*
G01Y370199D02*
X971754Y370549D01*
Y371419D01*
X972424Y371769D01*
X972599D01*
Y370199D01*
X972424D01*
G37*
G36*
G01Y362393D02*
X971755Y362743D01*
X971754Y363612D01*
X972424Y363962D01*
X972600Y363963D01*
X972599Y362393D01*
X972424D01*
G37*
G36*
G01X975804Y344849D02*
X975134Y345199D01*
Y346069D01*
X975804Y346419D01*
X975979D01*
Y344849D01*
X975804D01*
G37*
G36*
G01Y348749D02*
X975134Y349099D01*
Y349969D01*
X975804Y350319D01*
X975979D01*
Y348749D01*
X975804D01*
G37*
G36*
G01X977428Y356120D02*
X978098Y355770D01*
Y354900D01*
X977428Y354550D01*
X977253D01*
Y356120D01*
X977428D01*
G37*
G36*
G01X977427Y360010D02*
X978097Y359660D01*
Y358791D01*
X977427Y358441D01*
X977252Y358440D01*
X977253Y360010D01*
X977427D01*
G37*
G36*
G01X977428Y352220D02*
X978098Y351870D01*
Y351000D01*
X977428Y350650D01*
X977253D01*
Y352220D01*
X977428D01*
G37*
G36*
G01X974047Y373651D02*
X974717Y373301D01*
Y372431D01*
X974047Y372081D01*
X973873D01*
Y373651D01*
X974047D01*
G37*
G36*
G01X972154Y375446D02*
X972792Y375851D01*
X973545Y375416D01*
X973514Y374661D01*
X973427Y374510D01*
X972067Y375295D01*
X972154Y375446D01*
G37*
G36*
G01X974048Y365919D02*
X974718Y365569D01*
Y364699D01*
X974048Y364349D01*
X973873D01*
Y365919D01*
X974048D01*
G37*
G36*
G01Y369770D02*
X974718Y369420D01*
Y368550D01*
X974048Y368200D01*
X973873D01*
Y369770D01*
X974048D01*
G37*
G36*
G01X975527Y361801D02*
X976165Y362206D01*
X976918Y361772D01*
X976886Y361016D01*
X976799Y360864D01*
X975440Y361650D01*
X975527Y361801D01*
G37*
G36*
G01X977428Y348320D02*
X978098Y347970D01*
Y347100D01*
X977428Y346750D01*
X977253D01*
Y348320D01*
X977428D01*
G37*
G36*
G01X989324Y348749D02*
X988654Y349099D01*
Y349969D01*
X989324Y350319D01*
X989499D01*
Y348749D01*
X989324D01*
G37*
G36*
G01X975124Y401626D02*
X974339Y401336D01*
X973703Y401972D01*
X973993Y402757D01*
X974116Y402881D01*
X975248Y401749D01*
X975124Y401626D01*
G37*
G36*
G01X975533Y397360D02*
X974773Y397710D01*
Y398610D01*
X975533Y398960D01*
X975708D01*
Y397360D01*
X975533D01*
G37*
G36*
G01X976910Y393581D02*
X976125Y393291D01*
X975489Y393928D01*
X975779Y394713D01*
X975903Y394836D01*
X977034Y393705D01*
X976910Y393581D01*
G37*
G36*
G01X979668Y390824D02*
X978883Y390534D01*
X978247Y391170D01*
X978537Y391955D01*
X978660Y392079D01*
X979792Y390947D01*
X979668Y390824D01*
G37*
G36*
G01X985944Y377950D02*
X985274Y378300D01*
Y379170D01*
X985944Y379520D01*
X986119D01*
Y377950D01*
X985944D01*
G37*
G36*
G01X987845Y368418D02*
X987207Y368013D01*
X986454Y368447D01*
X986486Y369203D01*
X986573Y369355D01*
X987932Y368569D01*
X987845Y368418D01*
G37*
G36*
G01X985945Y370209D02*
X985275Y370559D01*
Y371428D01*
X985945Y371778D01*
X986120Y371779D01*
X986119Y370209D01*
X985945D01*
G37*
G36*
G01X985944Y374050D02*
X985274Y374400D01*
Y375270D01*
X985944Y375620D01*
X986119D01*
Y374050D01*
X985944D01*
G37*
G36*
G01X989324Y364349D02*
X988654Y364699D01*
Y365569D01*
X989324Y365919D01*
X989499D01*
Y364349D01*
X989324D01*
G37*
G36*
G01Y360449D02*
X988654Y360799D01*
Y361669D01*
X989324Y362019D01*
X989499D01*
Y360449D01*
X989324D01*
G37*
G36*
G01X982569Y385021D02*
X981809Y385371D01*
Y386271D01*
X982569Y386621D01*
X982744D01*
Y385021D01*
X982569D01*
G37*
G36*
G01X982426Y388066D02*
X981641Y387776D01*
X981004Y388412D01*
X981294Y389197D01*
X981418Y389321D01*
X982549Y388190D01*
X982426Y388066D01*
G37*
G36*
G01X989324Y352649D02*
X988654Y352999D01*
Y353869D01*
X989324Y354219D01*
X989499D01*
Y352649D01*
X989324D01*
G37*
G36*
G01Y356549D02*
X988654Y356899D01*
Y357769D01*
X989324Y358119D01*
X989499D01*
Y356549D01*
X989324D01*
G37*
G36*
G01X976555Y395489D02*
X977340Y395779D01*
X977977Y395143D01*
X977687Y394358D01*
X977563Y394234D01*
X976432Y395365D01*
X976555Y395489D01*
G37*
G36*
G01X990948Y348320D02*
X991618Y347970D01*
Y347100D01*
X990948Y346750D01*
X990773D01*
Y348320D01*
X990948D01*
G37*
G36*
G01X974890Y403454D02*
X975675Y403744D01*
X976311Y403108D01*
X976021Y402323D01*
X975898Y402199D01*
X974766Y403331D01*
X974890Y403454D01*
G37*
G36*
G01X976631Y398960D02*
X977391Y398610D01*
Y397710D01*
X976631Y397360D01*
X976456D01*
Y398960D01*
X976631D01*
G37*
G36*
G01X979313Y392731D02*
X980098Y393021D01*
X980734Y392385D01*
X980444Y391600D01*
X980321Y391476D01*
X979189Y392608D01*
X979313Y392731D01*
G37*
G36*
G01X990947Y367802D02*
X991617Y367452D01*
Y366582D01*
X990947Y366233D01*
X990773Y366232D01*
Y367802D01*
X990947D01*
G37*
G36*
G01X990948Y363920D02*
X991618Y363570D01*
Y362700D01*
X990948Y362350D01*
X990773D01*
Y363920D01*
X990948D01*
G37*
G36*
G01X987568Y381476D02*
X988237Y381126D01*
X988238Y380257D01*
X987568Y379907D01*
X987393Y379906D01*
Y381476D01*
X987568D01*
G37*
G36*
G01Y377619D02*
X988238Y377269D01*
Y376399D01*
X987568Y376049D01*
X987393D01*
Y377619D01*
X987568D01*
G37*
G36*
G01X989054Y369597D02*
X989692Y370002D01*
X990445Y369567D01*
X990413Y368812D01*
X990327Y368661D01*
X988967Y369446D01*
X989054Y369597D01*
G37*
G36*
G01X987568Y373694D02*
X988238Y373344D01*
Y372474D01*
X987568Y372124D01*
X987393D01*
Y373694D01*
X987568D01*
G37*
G36*
G01X985653Y383259D02*
X986290Y383664D01*
X987044Y383230D01*
X987012Y382475D01*
X986925Y382323D01*
X985565Y383108D01*
X985653Y383259D01*
G37*
G36*
G01X983667Y387321D02*
X984427Y386971D01*
Y386071D01*
X983667Y385721D01*
X983492D01*
Y387321D01*
X983667D01*
G37*
G36*
G01X982071Y389974D02*
X982856Y390264D01*
X983492Y389627D01*
X983202Y388842D01*
X983078Y388719D01*
X981947Y389850D01*
X982071Y389974D01*
G37*
G36*
G01X990948Y352220D02*
X991618Y351870D01*
Y351000D01*
X990948Y350650D01*
X990773D01*
Y352220D01*
X990948D01*
G37*
G36*
G01Y360020D02*
X991618Y359670D01*
Y358800D01*
X990948Y358450D01*
X990773D01*
Y360020D01*
X990948D01*
G37*
G36*
G01Y356120D02*
X991618Y355770D01*
Y354900D01*
X990948Y354550D01*
X990773D01*
Y356120D01*
X990948D01*
G37*
G36*
G01X984188D02*
X984858Y355770D01*
Y354900D01*
X984188Y354550D01*
X984013D01*
Y356120D01*
X984188D01*
G37*
G36*
G01Y360020D02*
X984858Y359670D01*
Y358800D01*
X984188Y358450D01*
X984013D01*
Y360020D01*
X984188D01*
G37*
G36*
G01Y352220D02*
X984858Y351870D01*
Y351000D01*
X984188Y350650D01*
X984013D01*
Y352220D01*
X984188D01*
G37*
G36*
G01X980808Y373694D02*
X981478Y373344D01*
Y372474D01*
X980808Y372124D01*
X980633D01*
Y373694D01*
X980808D01*
G37*
G36*
G01Y377619D02*
X981478Y377269D01*
Y376399D01*
X980808Y376049D01*
X980633D01*
Y377619D01*
X980808D01*
G37*
G36*
G01X974837Y384449D02*
X975621Y384739D01*
X976258Y384102D01*
X975968Y383318D01*
X975844Y383194D01*
X974713Y384325D01*
X974837Y384449D01*
G37*
G36*
G01X977594Y381691D02*
X978379Y381981D01*
X979016Y381345D01*
X978726Y380560D01*
X978602Y380436D01*
X977471Y381567D01*
X977594Y381691D01*
G37*
G36*
G01X972079Y387207D02*
X972864Y387497D01*
X973500Y386860D01*
X973210Y386075D01*
X973086Y385952D01*
X971955Y387083D01*
X972079Y387207D01*
G37*
G36*
G01X980808Y369770D02*
X981478Y369420D01*
Y368550D01*
X980808Y368200D01*
X980633D01*
Y369770D01*
X980808D01*
G37*
G36*
G01X982287Y365701D02*
X982925Y366106D01*
X983678Y365672D01*
X983646Y364917D01*
X983559Y364764D01*
X982200Y365550D01*
X982287Y365701D01*
G37*
G36*
G01X984187Y363910D02*
X984857Y363560D01*
Y362691D01*
X984188Y362341D01*
X984012Y362340D01*
X984013Y363910D01*
X984187D01*
G37*
G36*
G01X984188Y344420D02*
X984858Y344070D01*
Y343200D01*
X984188Y342850D01*
X984013D01*
Y344420D01*
X984188D01*
G37*
G36*
G01Y348320D02*
X984858Y347970D01*
Y347100D01*
X984188Y346750D01*
X984013D01*
Y348320D01*
X984188D01*
G37*
G36*
G01X973848Y391241D02*
X973063Y390951D01*
X972427Y391587D01*
X972717Y392372D01*
X972840Y392496D01*
X973972Y391364D01*
X973848Y391241D01*
G37*
G36*
G01X984494Y366452D02*
X983857Y366046D01*
X983104Y366481D01*
X983135Y367236D01*
X983222Y367388D01*
X984583Y366603D01*
X984494Y366452D01*
G37*
G36*
G01X982565Y368226D02*
X981895Y368575D01*
Y369445D01*
X982564Y369795D01*
X982739Y369796D01*
X982740Y368225D01*
X982565Y368226D01*
G37*
G36*
G01X982564Y372124D02*
X981894Y372474D01*
Y373344D01*
X982564Y373694D01*
X982739D01*
Y372124D01*
X982564D01*
G37*
G36*
G01X985944Y362350D02*
X985274Y362700D01*
Y363570D01*
X985944Y363920D01*
X986119D01*
Y362350D01*
X985944D01*
G37*
G36*
G01X982564Y376049D02*
X981894Y376399D01*
Y377269D01*
X982564Y377619D01*
X982739D01*
Y376049D01*
X982564D01*
G37*
G36*
G01X978631Y384453D02*
X977871Y384803D01*
Y385703D01*
X978631Y386053D01*
X978806D01*
Y384453D01*
X978631D01*
G37*
G36*
G01X981246Y381288D02*
X980461Y380998D01*
X979825Y381634D01*
X980115Y382419D01*
X980238Y382543D01*
X981370Y381411D01*
X981246Y381288D01*
G37*
G36*
G01X976606Y388483D02*
X975821Y388193D01*
X975184Y388829D01*
X975474Y389614D01*
X975598Y389738D01*
X976729Y388607D01*
X976606Y388483D01*
G37*
G36*
G01X985944Y350650D02*
X985274Y351000D01*
Y351870D01*
X985944Y352220D01*
X986119D01*
Y350650D01*
X985944D01*
G37*
G36*
G01Y358450D02*
X985274Y358800D01*
Y359670D01*
X985944Y360020D01*
X986119D01*
Y358450D01*
X985944D01*
G37*
G36*
G01Y354550D02*
X985274Y354900D01*
Y355770D01*
X985944Y356120D01*
X986119D01*
Y354550D01*
X985944D01*
G37*
G36*
G01X982564Y356549D02*
X981894Y356899D01*
Y357769D01*
X982564Y358119D01*
X982739D01*
Y356549D01*
X982564D01*
G37*
G36*
G01Y352649D02*
X981894Y352999D01*
Y353869D01*
X982564Y354219D01*
X982739D01*
Y352649D01*
X982564D01*
G37*
G36*
G01X979184Y374050D02*
X978514Y374400D01*
Y375270D01*
X979184Y375620D01*
X979359D01*
Y374050D01*
X979184D01*
G37*
G36*
G01X977948Y379782D02*
X977163Y379492D01*
X976526Y380128D01*
X976816Y380913D01*
X976940Y381037D01*
X978071Y379906D01*
X977948Y379782D01*
G37*
G36*
G01X975190Y382540D02*
X974405Y382250D01*
X973769Y382886D01*
X974059Y383671D01*
X974182Y383795D01*
X975314Y382663D01*
X975190Y382540D01*
G37*
G36*
G01X982564Y360449D02*
X981894Y360799D01*
Y361669D01*
X982564Y362019D01*
X982739D01*
Y360449D01*
X982564D01*
G37*
G36*
G01X979184Y370199D02*
X978514Y370549D01*
Y371419D01*
X979184Y371769D01*
X979359D01*
Y370199D01*
X979184D01*
G37*
G36*
G01X979185Y366318D02*
X978515Y366668D01*
Y367538D01*
X979185Y367888D01*
X979360D01*
X979359Y366318D01*
X979185D01*
G37*
G36*
G01X981078Y364523D02*
X980440Y364118D01*
X979687Y364553D01*
X979718Y365308D01*
X979806Y365460D01*
X981165Y364674D01*
X981078Y364523D01*
G37*
G36*
G01X982564Y344849D02*
X981894Y345199D01*
Y346069D01*
X982564Y346419D01*
X982739D01*
Y344849D01*
X982564D01*
G37*
G36*
G01Y348749D02*
X981894Y349099D01*
Y349969D01*
X982564Y350319D01*
X982739D01*
Y348749D01*
X982564D01*
G37*
G36*
G01X987568Y358119D02*
X988238Y357769D01*
Y356899D01*
X987568Y356549D01*
X987393D01*
Y358119D01*
X987568D01*
G37*
G36*
G01Y354219D02*
X988238Y353869D01*
Y352999D01*
X987568Y352649D01*
X987393D01*
Y354219D01*
X987568D01*
G37*
G36*
G01X976252Y390392D02*
X977037Y390682D01*
X977674Y390046D01*
X977384Y389261D01*
X977260Y389137D01*
X976129Y390268D01*
X976252Y390392D01*
G37*
G36*
G01X980893Y383197D02*
X981677Y383487D01*
X982314Y382850D01*
X982024Y382066D01*
X981900Y381942D01*
X980769Y383073D01*
X980893Y383197D01*
G37*
G36*
G01X979731Y386053D02*
X980491Y385703D01*
Y384803D01*
X979731Y384453D01*
X979556D01*
Y386053D01*
X979731D01*
G37*
G36*
G01X984187Y379520D02*
X984857Y379170D01*
Y378300D01*
X984187Y377950D01*
X984012D01*
Y379520D01*
X984187D01*
G37*
G36*
G01X987568Y362019D02*
X988238Y361669D01*
Y360799D01*
X987568Y360449D01*
X987393D01*
Y362019D01*
X987568D01*
G37*
G36*
G01X984188Y371769D02*
X984858Y371419D01*
Y370549D01*
X984188Y370199D01*
X984013D01*
Y371769D01*
X984188D01*
G37*
G36*
G01Y375620D02*
X984858Y375270D01*
Y374400D01*
X984188Y374050D01*
X984013D01*
Y375620D01*
X984188D01*
G37*
G36*
G01X985638Y367668D02*
X986276Y368073D01*
X987029Y367639D01*
X986998Y366884D01*
X986911Y366732D01*
X985551Y367517D01*
X985638Y367668D01*
G37*
G36*
G01X987568Y365893D02*
X988238Y365543D01*
X988239Y364674D01*
X987569Y364323D01*
X987394D01*
Y365893D01*
X987568D01*
G37*
G36*
G01X973495Y393150D02*
X974279Y393440D01*
X974916Y392803D01*
X974626Y392019D01*
X974502Y391895D01*
X973371Y393026D01*
X973495Y393150D01*
G37*
G36*
G01X987568Y350319D02*
X988238Y349969D01*
Y349099D01*
X987568Y348749D01*
X987393D01*
Y350319D01*
X987568D01*
G37*
G36*
G01X1027100Y575600D02*
X1026721Y575979D01*
X1026896Y576154D01*
X1026941Y576169D01*
G03X1025265Y578164I-441J1331D01*
G02X1024630Y578070I-352J189D01*
G01X1019069Y583631D01*
G02X1019335Y584313I283J282D01*
G03X1018186Y586595I-58J1401D01*
G02X1017564I-311J251D01*
G03X1015462Y586685I-1091J-881D01*
G02X1014884I-289J277D01*
G03X1012804Y586622I-1012J-971D01*
G02X1012195I-305J258D01*
G03X1009757Y586014I-1068J-908D01*
G02X1009083Y585817I-391J86D01*
G01X1007466Y587434D01*
X1007561Y587571D01*
G03X1007377Y589377I-1155J795D01*
G02Y589955I277J289D01*
G03X1007426Y591928I-971J1011D01*
G02X1007477Y592522I291J274D01*
G03X1007042Y594983I-843J1120D01*
G01X1006900Y595026D01*
Y602821D01*
G02X1007340Y603219I400J0D01*
G03X1007588Y606012I140J1395D01*
G02X1007218Y606411I30J399D01*
G01Y608794D01*
X1006900Y609112D01*
Y610449D01*
G02X1007340Y610847I400J0D01*
G03Y613637I140J1395D01*
G02X1006900Y614035I-40J398D01*
G01Y614400D01*
X1008500Y616000D01*
X1032000D01*
X1033300Y614700D01*
Y580024D01*
X1028876Y575600D01*
X1027100D01*
G37*
G36*
G01X1075091Y189972D02*
X1074331Y190322D01*
Y191222D01*
X1075091Y191572D01*
X1075266D01*
Y189972D01*
X1075091D01*
G37*
G36*
G01X1075703Y199797D02*
X1074943Y200147D01*
Y201047D01*
X1075703Y201397D01*
X1075878D01*
Y199797D01*
X1075703D01*
G37*
G36*
G01X1075195Y202792D02*
X1074411Y202502D01*
X1073774Y203139D01*
X1074064Y203923D01*
X1074188Y204047D01*
X1075319Y202916D01*
X1075195Y202792D01*
G37*
G36*
G01X1075703Y195897D02*
X1074943Y196247D01*
Y197147D01*
X1075703Y197497D01*
X1075878D01*
Y195897D01*
X1075703D01*
G37*
G36*
G01X1073080Y217337D02*
X1072410Y217687D01*
Y218557D01*
X1073080Y218907D01*
X1073255D01*
Y217337D01*
X1073080D01*
G37*
G36*
G01X1073242Y209103D02*
X1072482Y209453D01*
Y210353D01*
X1073242Y210703D01*
X1073417D01*
Y209103D01*
X1073242D01*
G37*
G36*
G01Y213003D02*
X1072482Y213353D01*
Y214253D01*
X1073242Y214603D01*
X1073417D01*
Y213003D01*
X1073242D01*
G37*
G36*
G01X1076191Y191572D02*
X1076951Y191222D01*
Y190322D01*
X1076191Y189972D01*
X1076016D01*
Y191572D01*
X1076191D01*
G37*
G36*
G01X1074841Y204700D02*
X1075625Y204990D01*
X1076262Y204353D01*
X1075972Y203569D01*
X1075848Y203445D01*
X1074717Y204576D01*
X1074841Y204700D01*
G37*
G36*
G01X1076803Y201397D02*
X1077563Y201047D01*
Y200147D01*
X1076803Y199797D01*
X1076628D01*
Y201397D01*
X1076803D01*
G37*
G36*
G01Y197497D02*
X1077563Y197147D01*
Y196247D01*
X1076803Y195897D01*
X1076628D01*
Y197497D01*
X1076803D01*
G37*
G36*
G01X1074342Y214603D02*
X1075102Y214253D01*
Y213353D01*
X1074342Y213003D01*
X1074167D01*
Y214603D01*
X1074342D01*
G37*
G36*
G01Y210703D02*
X1075102Y210353D01*
Y209453D01*
X1074342Y209103D01*
X1074167D01*
Y210703D01*
X1074342D01*
G37*
G36*
G01X1088841Y195943D02*
X1088081Y196293D01*
Y197193D01*
X1088841Y197543D01*
X1089016D01*
Y195943D01*
X1088841D01*
G37*
G36*
G01Y199843D02*
X1088081Y200193D01*
Y201093D01*
X1088841Y201443D01*
X1089016D01*
Y199843D01*
X1088841D01*
G37*
G36*
G01Y203743D02*
X1088081Y204093D01*
Y204993D01*
X1088841Y205343D01*
X1089016D01*
Y203743D01*
X1088841D01*
G37*
G36*
G01X1091820Y191447D02*
X1091035Y191157D01*
X1090399Y191793D01*
X1090689Y192578D01*
X1090812Y192702D01*
X1091944Y191570D01*
X1091820Y191447D01*
G37*
G36*
G01X1086599Y217337D02*
X1085929Y217687D01*
Y218557D01*
X1086599Y218907D01*
X1086774D01*
Y217337D01*
X1086599D01*
G37*
G36*
G01X1088439Y206625D02*
X1087654Y206335D01*
X1087018Y206971D01*
X1087308Y207756D01*
X1087431Y207880D01*
X1088563Y206748D01*
X1088439Y206625D01*
G37*
G36*
G01X1086599Y213437D02*
X1085929Y213787D01*
Y214657D01*
X1086599Y215007D01*
X1086774D01*
Y213437D01*
X1086599D01*
G37*
G36*
G01Y209437D02*
X1085929Y209787D01*
Y210657D01*
X1086599Y211007D01*
X1086774D01*
Y209437D01*
X1086599D01*
G37*
G36*
G01X1089941Y202443D02*
X1090701Y202093D01*
Y201193D01*
X1089941Y200843D01*
X1089766D01*
Y202443D01*
X1089941D01*
G37*
G36*
G01X1091467Y193356D02*
X1092252Y193646D01*
X1092888Y193010D01*
X1092598Y192225D01*
X1092475Y192101D01*
X1091343Y193233D01*
X1091467Y193356D01*
G37*
G36*
G01X1089941Y198543D02*
X1090701Y198193D01*
Y197293D01*
X1089941Y196943D01*
X1089766D01*
Y198543D01*
X1089941D01*
G37*
G36*
G01X1088287Y208335D02*
X1089071Y208625D01*
X1089708Y207988D01*
X1089418Y207204D01*
X1089294Y207080D01*
X1088163Y208211D01*
X1088287Y208335D01*
G37*
G36*
G01X1088223Y213081D02*
X1088893Y212731D01*
Y211861D01*
X1088223Y211511D01*
X1088048D01*
Y213081D01*
X1088223D01*
G37*
G36*
G01Y217006D02*
X1088893Y216656D01*
Y215786D01*
X1088223Y215436D01*
X1088048D01*
Y217006D01*
X1088223D01*
G37*
G36*
G01X1071466Y202253D02*
X1070681Y201963D01*
X1070045Y202600D01*
X1070335Y203385D01*
X1070459Y203508D01*
X1071590Y202377D01*
X1071466Y202253D01*
G37*
G36*
G01X1071262Y192745D02*
X1070972Y193529D01*
X1071609Y194166D01*
X1072393Y193876D01*
X1072517Y193752D01*
X1071386Y192621D01*
X1071262Y192745D01*
G37*
G36*
G01X1072683Y196800D02*
X1071923Y197150D01*
Y198050D01*
X1072683Y198400D01*
X1072858D01*
Y196800D01*
X1072683D01*
G37*
G36*
G01X1069991Y208437D02*
X1069231Y208787D01*
Y209687D01*
X1069991Y210037D01*
X1070166D01*
Y208437D01*
X1069991D01*
G37*
G36*
G01X1069700Y215436D02*
X1069030Y215786D01*
Y216656D01*
X1069700Y217006D01*
X1069875D01*
Y215436D01*
X1069700D01*
G37*
G36*
G01X1069991Y204537D02*
X1069231Y204887D01*
Y205787D01*
X1069991Y206137D01*
X1070166D01*
Y204537D01*
X1069991D01*
G37*
G36*
G01X1073171Y193098D02*
X1073461Y192313D01*
X1072825Y191677D01*
X1072040Y191967D01*
X1071916Y192090D01*
X1073048Y193222D01*
X1073171Y193098D01*
G37*
G36*
G01X1073783Y197000D02*
X1074543Y196650D01*
Y195750D01*
X1073783Y195400D01*
X1073608D01*
Y197000D01*
X1073783D01*
G37*
G36*
G01X1071820Y203455D02*
X1072604Y203745D01*
X1073241Y203108D01*
X1072951Y202324D01*
X1072827Y202200D01*
X1071696Y203331D01*
X1071820Y203455D01*
G37*
G36*
G01X1073783Y200900D02*
X1074543Y200550D01*
Y199650D01*
X1073783Y199300D01*
X1073608D01*
Y200900D01*
X1073783D01*
G37*
G36*
G01X1071324Y218907D02*
X1071994Y218557D01*
Y217687D01*
X1071324Y217337D01*
X1071149D01*
Y218907D01*
X1071324D01*
G37*
G36*
G01X1071090Y210037D02*
X1071850Y209687D01*
Y208787D01*
X1071090Y208437D01*
X1070915D01*
Y210037D01*
X1071090D01*
G37*
G36*
G01Y206137D02*
X1071850Y205787D01*
Y204887D01*
X1071090Y204537D01*
X1070915D01*
Y206137D01*
X1071090D01*
G37*
G36*
G01X1085991Y199888D02*
X1085231Y200238D01*
Y201138D01*
X1085991Y201488D01*
X1086166D01*
Y199888D01*
X1085991D01*
G37*
G36*
G01Y195988D02*
X1085231Y196338D01*
Y197238D01*
X1085991Y197588D01*
X1086166D01*
Y195988D01*
X1085991D01*
G37*
G36*
G01Y192088D02*
X1085231Y192438D01*
Y193338D01*
X1085991Y193688D01*
X1086166D01*
Y192088D01*
X1085991D01*
G37*
G36*
G01X1085243Y205552D02*
X1084458Y205262D01*
X1083822Y205898D01*
X1084112Y206683D01*
X1084235Y206807D01*
X1085367Y205675D01*
X1085243Y205552D01*
G37*
G36*
G01X1083219Y215436D02*
X1082549Y215786D01*
Y216656D01*
X1083219Y217006D01*
X1083394D01*
Y215436D01*
X1083219D01*
G37*
G36*
G01X1083221Y208427D02*
X1082461Y208777D01*
Y209677D01*
X1083221Y210027D01*
X1083396D01*
Y208427D01*
X1083221D01*
G37*
G36*
G01X1087089Y203988D02*
X1087849Y203638D01*
Y202738D01*
X1087089Y202388D01*
X1086914D01*
Y203988D01*
X1087089D01*
G37*
G36*
G01Y200088D02*
X1087849Y199738D01*
Y198838D01*
X1087089Y198488D01*
X1086914D01*
Y200088D01*
X1087089D01*
G37*
G36*
G01Y196188D02*
X1087849Y195838D01*
Y194938D01*
X1087089Y194588D01*
X1086914D01*
Y196188D01*
X1087089D01*
G37*
G36*
G01X1084843Y218907D02*
X1085513Y218557D01*
Y217687D01*
X1084843Y217337D01*
X1084668D01*
Y218907D01*
X1084843D01*
G37*
G36*
G01X1085088Y207259D02*
X1085873Y207549D01*
X1086509Y206913D01*
X1086219Y206128D01*
X1086096Y206004D01*
X1084964Y207136D01*
X1085088Y207259D01*
G37*
G36*
G01X1084321Y210927D02*
X1085081Y210577D01*
Y209677D01*
X1084321Y209327D01*
X1084146D01*
Y210927D01*
X1084321D01*
G37*
G36*
G01X1084843Y215007D02*
X1085513Y214657D01*
Y213787D01*
X1084843Y213437D01*
X1084668D01*
Y215007D01*
X1084843D01*
G37*
G36*
G01X1079822Y203531D02*
X1080582Y203181D01*
Y202281D01*
X1079822Y201931D01*
X1079647D01*
Y203531D01*
X1079822D01*
G37*
G36*
G01Y199631D02*
X1080582Y199281D01*
Y198381D01*
X1079822Y198031D01*
X1079647D01*
Y199631D01*
X1079822D01*
G37*
G36*
G01Y195731D02*
X1080582Y195381D01*
Y194481D01*
X1079822Y194131D01*
X1079647D01*
Y195731D01*
X1079822D01*
G37*
G36*
G01Y191831D02*
X1080582Y191481D01*
Y190581D01*
X1079822Y190231D01*
X1079647D01*
Y191831D01*
X1079822D01*
G37*
G36*
G01X1078084Y218907D02*
X1078754Y218557D01*
Y217687D01*
X1078084Y217337D01*
X1077909D01*
Y218907D01*
X1078084D01*
G37*
G36*
G01X1078280Y207662D02*
X1079040Y207312D01*
Y206412D01*
X1078280Y206062D01*
X1078105D01*
Y207662D01*
X1078280D01*
G37*
G36*
G01X1077486Y211162D02*
X1078246Y210812D01*
Y209912D01*
X1077486Y209562D01*
X1077311D01*
Y211162D01*
X1077486D01*
G37*
G36*
G01Y215062D02*
X1078246Y214712D01*
Y213812D01*
X1077486Y213462D01*
X1077311D01*
Y215062D01*
X1077486D01*
G37*
G36*
G01X1082843Y194057D02*
X1083603Y193707D01*
Y192807D01*
X1082843Y192457D01*
X1082668D01*
Y194057D01*
X1082843D01*
G37*
G36*
G01Y197957D02*
X1083603Y197607D01*
Y196707D01*
X1082843Y196357D01*
X1082668D01*
Y197957D01*
X1082843D01*
G37*
G36*
G01Y201857D02*
X1083603Y201507D01*
Y200607D01*
X1082843Y200257D01*
X1082668D01*
Y201857D01*
X1082843D01*
G37*
G36*
G01X1081464Y217017D02*
X1082134Y216667D01*
Y215797D01*
X1081464Y215447D01*
X1081289D01*
Y217017D01*
X1081464D01*
G37*
G36*
G01X1081463Y213045D02*
X1082133Y212695D01*
Y211825D01*
X1081463Y211475D01*
X1081288D01*
Y213045D01*
X1081463D01*
G37*
G36*
G01X1078723Y201431D02*
X1077963Y201781D01*
Y202681D01*
X1078723Y203031D01*
X1078898D01*
Y201431D01*
X1078723D01*
G37*
G36*
G01Y197531D02*
X1077963Y197881D01*
Y198781D01*
X1078723Y199131D01*
X1078898D01*
Y197531D01*
X1078723D01*
G37*
G36*
G01Y193631D02*
X1077963Y193981D01*
Y194881D01*
X1078723Y195231D01*
X1078898D01*
Y193631D01*
X1078723D01*
G37*
G36*
G01Y189731D02*
X1077963Y190081D01*
Y190981D01*
X1078723Y191331D01*
X1078898D01*
Y189731D01*
X1078723D01*
G37*
G36*
G01X1076386Y209562D02*
X1075626Y209912D01*
Y210812D01*
X1076386Y211162D01*
X1076561D01*
Y209562D01*
X1076386D01*
G37*
G36*
G01Y213462D02*
X1075626Y213812D01*
Y214712D01*
X1076386Y215062D01*
X1076561D01*
Y213462D01*
X1076386D01*
G37*
G36*
G01X1081743Y192457D02*
X1080983Y192807D01*
Y193707D01*
X1081743Y194057D01*
X1081918D01*
Y192457D01*
X1081743D01*
G37*
G36*
G01Y196357D02*
X1080983Y196707D01*
Y197607D01*
X1081743Y197957D01*
X1081918D01*
Y196357D01*
X1081743D01*
G37*
G36*
G01Y200257D02*
X1080983Y200607D01*
Y201507D01*
X1081743Y201857D01*
X1081918D01*
Y200257D01*
X1081743D01*
G37*
G36*
G01X1079839Y217326D02*
X1079169Y217676D01*
Y218546D01*
X1079839Y218896D01*
X1080014D01*
Y217326D01*
X1079839D01*
G37*
G36*
G01Y213437D02*
X1079169Y213787D01*
Y214657D01*
X1079839Y215007D01*
X1080014D01*
Y213437D01*
X1079839D01*
G37*
G36*
G01Y209593D02*
X1079169Y209943D01*
Y210813D01*
X1079839Y211163D01*
X1080014D01*
Y209593D01*
X1079839D01*
G37*
G36*
G01X1080000Y244900D02*
X1077400D01*
X1075444Y242944D01*
X1075378Y242934D01*
G03X1074554Y242500I204J-1387D01*
G01X1071500D01*
X1069820Y244180D01*
G02X1069819Y244462I142J142D01*
G03X1069700Y246540I-997J985D01*
G01Y248254D01*
G03Y250440I-878J1093D01*
G01Y254211D01*
G02X1070316Y254547I400J0D01*
G03Y256909I756J1181D01*
G02X1069700Y257245I-216J336D01*
G01Y257800D01*
X1075100Y263200D01*
X1075527D01*
X1075546Y263196D01*
G03X1076184I319J1570D01*
G01X1076203Y263200D01*
X1076600D01*
X1077069Y263669D01*
Y263707D01*
X1077113Y263762D01*
G03X1077069Y265823I-1248J1004D01*
G01Y266980D01*
X1077574Y267485D01*
X1083315D01*
X1084500Y266300D01*
Y265464D01*
X1084489Y265431D01*
G03Y264369I1511J-531D01*
G01X1084500Y264336D01*
Y262661D01*
X1084495Y262640D01*
G03Y261960I1566J-340D01*
G01X1084500Y261939D01*
Y256906D01*
X1084336Y256876D01*
G03Y254118I255J-1379D01*
G01X1084500Y254088D01*
Y253600D01*
X1085200Y252900D01*
X1086650D01*
X1087100Y252450D01*
Y250450D01*
X1086400Y249750D01*
X1085400D01*
X1084500Y248850D01*
Y248087D01*
X1084477Y248043D01*
G03Y246749I1244J-647D01*
G01X1084500Y246705D01*
Y245600D01*
X1083200Y244300D01*
X1080600D01*
X1080000Y244900D01*
G37*
G36*
G01X1073079Y229061D02*
X1072409Y229411D01*
Y230281D01*
X1073079Y230631D01*
X1073254D01*
Y229061D01*
X1073079D01*
G37*
G36*
G01X1073080Y225137D02*
X1072410Y225487D01*
Y226357D01*
X1073080Y226707D01*
X1073255D01*
Y225137D01*
X1073080D01*
G37*
G36*
G01Y221237D02*
X1072410Y221587D01*
Y222457D01*
X1073080Y222807D01*
X1073255D01*
Y221237D01*
X1073080D01*
G37*
G36*
G01X1074704Y224806D02*
X1075374Y224456D01*
Y223586D01*
X1074704Y223236D01*
X1074529D01*
Y224806D01*
X1074704D01*
G37*
G36*
G01X1074703Y228706D02*
X1075373Y228356D01*
Y227486D01*
X1074703Y227136D01*
X1074528D01*
Y228706D01*
X1074703D01*
G37*
G36*
G01X1075965Y235887D02*
X1076687Y236113D01*
X1077302Y235499D01*
X1077075Y234777D01*
X1076952Y234653D01*
X1075842Y235764D01*
X1075965Y235887D01*
G37*
G36*
G01X1074704Y220906D02*
X1075374Y220556D01*
Y219686D01*
X1074704Y219336D01*
X1074529D01*
Y220906D01*
X1074704D01*
G37*
G36*
G01X1074195Y238866D02*
X1073719Y239454D01*
X1074062Y240252D01*
X1074817Y240308D01*
X1074977Y240239D01*
X1074354Y238797D01*
X1074195Y238866D01*
G37*
G36*
G01X1086599Y229062D02*
X1085929Y229412D01*
Y230282D01*
X1086599Y230632D01*
X1086774D01*
Y229062D01*
X1086599D01*
G37*
G36*
G01Y225137D02*
X1085929Y225487D01*
Y226357D01*
X1086599Y226707D01*
X1086774D01*
Y225137D01*
X1086599D01*
G37*
G36*
G01Y221237D02*
X1085929Y221587D01*
Y222457D01*
X1086599Y222807D01*
X1086774D01*
Y221237D01*
X1086599D01*
G37*
G36*
G01X1088223Y220906D02*
X1088893Y220556D01*
Y219686D01*
X1088223Y219336D01*
X1088048D01*
Y220906D01*
X1088223D01*
G37*
G36*
G01Y224806D02*
X1088893Y224456D01*
Y223586D01*
X1088223Y223236D01*
X1088048D01*
Y224806D01*
X1088223D01*
G37*
G36*
G01Y228706D02*
X1088893Y228356D01*
Y227486D01*
X1088223Y227136D01*
X1088048D01*
Y228706D01*
X1088223D01*
G37*
G36*
G01Y232557D02*
X1088893Y232207D01*
Y231337D01*
X1088223Y230987D01*
X1088048D01*
Y232557D01*
X1088223D01*
G37*
G36*
G01Y236481D02*
X1088893Y236131D01*
Y235261D01*
X1088223Y234911D01*
X1088048D01*
Y236481D01*
X1088223D01*
G37*
G36*
G01X1069699Y231011D02*
X1069029Y231361D01*
Y232231D01*
X1069699Y232581D01*
X1069874D01*
Y231011D01*
X1069699D01*
G37*
G36*
G01X1069700Y227136D02*
X1069030Y227486D01*
Y228356D01*
X1069700Y228706D01*
X1069875D01*
Y227136D01*
X1069700D01*
G37*
G36*
G01Y223236D02*
X1069030Y223586D01*
Y224456D01*
X1069700Y224806D01*
X1069875D01*
Y223236D01*
X1069700D01*
G37*
G36*
G01Y219336D02*
X1069030Y219686D01*
Y220556D01*
X1069700Y220906D01*
X1069875D01*
Y219336D01*
X1069700D01*
G37*
G36*
G01X1073536Y234449D02*
X1073591Y233695D01*
X1072851Y233237D01*
X1072201Y233623D01*
X1072108Y233771D01*
X1073444Y234598D01*
X1073536Y234449D01*
G37*
G36*
G01X1071324Y222807D02*
X1071994Y222457D01*
Y221587D01*
X1071324Y221237D01*
X1071149D01*
Y222807D01*
X1071324D01*
G37*
G36*
G01Y226707D02*
X1071994Y226357D01*
Y225487D01*
X1071324Y225137D01*
X1071149D01*
Y226707D01*
X1071324D01*
G37*
G36*
G01Y230631D02*
X1071994Y230281D01*
Y229411D01*
X1071324Y229061D01*
X1071149D01*
Y230631D01*
X1071324D01*
G37*
G36*
G01X1083220Y231036D02*
X1082550Y231386D01*
Y232256D01*
X1083220Y232606D01*
X1083395D01*
Y231036D01*
X1083220D01*
G37*
G36*
G01Y227136D02*
X1082550Y227486D01*
Y228356D01*
X1083220Y228706D01*
X1083395D01*
Y227136D01*
X1083220D01*
G37*
G36*
G01X1083219Y223236D02*
X1082549Y223586D01*
Y224456D01*
X1083219Y224806D01*
X1083394D01*
Y223236D01*
X1083219D01*
G37*
G36*
G01Y219336D02*
X1082549Y219686D01*
Y220556D01*
X1083219Y220906D01*
X1083394D01*
Y219336D01*
X1083219D01*
G37*
G36*
G01X1084843Y222807D02*
X1085513Y222457D01*
Y221587D01*
X1084843Y221237D01*
X1084668D01*
Y222807D01*
X1084843D01*
G37*
G36*
G01Y226707D02*
X1085513Y226357D01*
Y225487D01*
X1084843Y225137D01*
X1084668D01*
Y226707D01*
X1084843D01*
G37*
G36*
G01Y230631D02*
X1085513Y230281D01*
Y229411D01*
X1084843Y229061D01*
X1084668D01*
Y230631D01*
X1084843D01*
G37*
G36*
G01X1083878Y235300D02*
X1083157Y235528D01*
X1083006Y236385D01*
X1083605Y236846D01*
X1083778Y236876D01*
X1084050Y235330D01*
X1083878Y235300D01*
G37*
G36*
G01X1078084Y222831D02*
X1078754Y222481D01*
Y221611D01*
X1078084Y221261D01*
X1077909D01*
Y222831D01*
X1078084D01*
G37*
G36*
G01Y226756D02*
X1078754Y226406D01*
Y225536D01*
X1078084Y225186D01*
X1077909D01*
Y226756D01*
X1078084D01*
G37*
G36*
G01X1081464Y232557D02*
X1082134Y232207D01*
Y231337D01*
X1081464Y230987D01*
X1081289D01*
Y232557D01*
X1081464D01*
G37*
G36*
G01Y228717D02*
X1082134Y228367D01*
Y227497D01*
X1081464Y227147D01*
X1081289D01*
Y228717D01*
X1081464D01*
G37*
G36*
G01Y224817D02*
X1082134Y224467D01*
Y223597D01*
X1081464Y223247D01*
X1081289D01*
Y224817D01*
X1081464D01*
G37*
G36*
G01Y220917D02*
X1082134Y220567D01*
Y219697D01*
X1081464Y219347D01*
X1081289D01*
Y220917D01*
X1081464D01*
G37*
G36*
G01Y236506D02*
X1082134Y236156D01*
Y235286D01*
X1081464Y234936D01*
X1081289D01*
Y236506D01*
X1081464D01*
G37*
G36*
G01X1081462Y240338D02*
X1082132Y239988D01*
Y239118D01*
X1081462Y238768D01*
X1081286D01*
X1081288Y240338D01*
X1081462D01*
G37*
G36*
G01X1076460Y227087D02*
X1075790Y227437D01*
Y228307D01*
X1076460Y228657D01*
X1076635D01*
Y227087D01*
X1076460D01*
G37*
G36*
G01Y223187D02*
X1075790Y223537D01*
Y224407D01*
X1076460Y224757D01*
X1076635D01*
Y223187D01*
X1076460D01*
G37*
G36*
G01Y219287D02*
X1075790Y219637D01*
Y220507D01*
X1076460Y220857D01*
X1076635D01*
Y219287D01*
X1076460D01*
G37*
G36*
G01X1079839Y232986D02*
X1079169Y233336D01*
Y234206D01*
X1079839Y234556D01*
X1080014D01*
Y232986D01*
X1079839D01*
G37*
G36*
G01Y229037D02*
X1079169Y229387D01*
Y230257D01*
X1079839Y230607D01*
X1080014D01*
Y229037D01*
X1079839D01*
G37*
G36*
G01Y225126D02*
X1079169Y225476D01*
Y226346D01*
X1079839Y226696D01*
X1080014D01*
Y225126D01*
X1079839D01*
G37*
G36*
G01Y221226D02*
X1079169Y221576D01*
Y222446D01*
X1079839Y222796D01*
X1080014D01*
Y221226D01*
X1079839D01*
G37*
G36*
G01Y236826D02*
X1079169Y237176D01*
Y238046D01*
X1079839Y238396D01*
X1080014D01*
Y236826D01*
X1079839D01*
G37*
G36*
G01X1070820Y392837D02*
X1070150Y393187D01*
Y394057D01*
X1070820Y394407D01*
X1070995D01*
Y392837D01*
X1070820D01*
G37*
G36*
G01X1071386Y395418D02*
X1071355Y396173D01*
X1072108Y396608D01*
X1072746Y396203D01*
X1072833Y396052D01*
X1071474Y395266D01*
X1071386Y395418D01*
G37*
G36*
G01X1074723Y398611D02*
X1073963Y398961D01*
Y399861D01*
X1074723Y400211D01*
X1074898D01*
Y398611D01*
X1074723D01*
G37*
G36*
G01Y402511D02*
X1073963Y402861D01*
Y403761D01*
X1074723Y404111D01*
X1074898D01*
Y402511D01*
X1074723D01*
G37*
G36*
G01X1070820Y385037D02*
X1070150Y385387D01*
Y386257D01*
X1070820Y386607D01*
X1070995D01*
Y385037D01*
X1070820D01*
G37*
G36*
G01Y381137D02*
X1070150Y381487D01*
Y382357D01*
X1070820Y382707D01*
X1070995D01*
Y381137D01*
X1070820D01*
G37*
G36*
G01Y377237D02*
X1070150Y377587D01*
Y378457D01*
X1070820Y378807D01*
X1070995D01*
Y377237D01*
X1070820D01*
G37*
G36*
G01Y373386D02*
X1070150Y373736D01*
Y374606D01*
X1070820Y374956D01*
X1070995D01*
Y373386D01*
X1070820D01*
G37*
G36*
G01Y369486D02*
X1070150Y369836D01*
Y370706D01*
X1070820Y371056D01*
X1070995D01*
Y369486D01*
X1070820D01*
G37*
G36*
G01X1073537Y368244D02*
X1074175Y368649D01*
X1074928Y368214D01*
X1074896Y367459D01*
X1074809Y367307D01*
X1073449Y368093D01*
X1073537Y368244D01*
G37*
G36*
G01X1070820Y388937D02*
X1070150Y389287D01*
Y390157D01*
X1070820Y390507D01*
X1070995D01*
Y388937D01*
X1070820D01*
G37*
G36*
G01X1072444Y392506D02*
X1073114Y392156D01*
Y391286D01*
X1072444Y390936D01*
X1072269D01*
Y392506D01*
X1072444D01*
G37*
G36*
G01X1075253Y395772D02*
X1075284Y395017D01*
X1074531Y394583D01*
X1073893Y394988D01*
X1073806Y395139D01*
X1075166Y395924D01*
X1075253Y395772D01*
G37*
G36*
G01X1075825Y399711D02*
X1076585Y399361D01*
Y398461D01*
X1075825Y398111D01*
X1075650D01*
Y399711D01*
X1075825D01*
G37*
G36*
G01Y403611D02*
X1076585Y403261D01*
Y402361D01*
X1075825Y402011D01*
X1075650D01*
Y403611D01*
X1075825D01*
G37*
G36*
G01X1072444Y384706D02*
X1073114Y384356D01*
Y383486D01*
X1072444Y383136D01*
X1072269D01*
Y384706D01*
X1072444D01*
G37*
G36*
G01Y380806D02*
X1073114Y380456D01*
Y379586D01*
X1072444Y379236D01*
X1072269D01*
Y380806D01*
X1072444D01*
G37*
G36*
G01Y376881D02*
X1073114Y376531D01*
Y375661D01*
X1072444Y375311D01*
X1072269D01*
Y376881D01*
X1072444D01*
G37*
G36*
G01Y372957D02*
X1073114Y372607D01*
Y371737D01*
X1072444Y371387D01*
X1072269D01*
Y372957D01*
X1072444D01*
G37*
G36*
G01Y388606D02*
X1073114Y388256D01*
Y387386D01*
X1072444Y387036D01*
X1072269D01*
Y388606D01*
X1072444D01*
G37*
G36*
G01X1088254Y389548D02*
X1088222Y390303D01*
X1088975Y390738D01*
X1089613Y390333D01*
X1089701Y390181D01*
X1088341Y389397D01*
X1088254Y389548D01*
G37*
G36*
G01X1084880Y387603D02*
X1084848Y388358D01*
X1085602Y388792D01*
X1086239Y388387D01*
X1086328Y388236D01*
X1084967Y387451D01*
X1084880Y387603D01*
G37*
G36*
G01X1086232Y367685D02*
X1085561Y367337D01*
X1084848Y367836D01*
X1084946Y368585D01*
X1085046Y368728D01*
X1086332Y367829D01*
X1086232Y367685D01*
G37*
G36*
G01X1084339Y369486D02*
X1083669Y369836D01*
Y370706D01*
X1084339Y371056D01*
X1084514D01*
Y369486D01*
X1084339D01*
G37*
G36*
G01Y377226D02*
X1083669Y377576D01*
Y378446D01*
X1084339Y378796D01*
X1084514D01*
Y377226D01*
X1084339D01*
G37*
G36*
G01Y373386D02*
X1083669Y373736D01*
Y374606D01*
X1084339Y374956D01*
X1084514D01*
Y373386D01*
X1084339D01*
G37*
G36*
G01Y385026D02*
X1083669Y385376D01*
Y386246D01*
X1084339Y386596D01*
X1084514D01*
Y385026D01*
X1084339D01*
G37*
G36*
G01Y381126D02*
X1083669Y381476D01*
Y382346D01*
X1084339Y382696D01*
X1084514D01*
Y381126D01*
X1084339D01*
G37*
G36*
G01X1094479Y402651D02*
X1093809Y403001D01*
Y403871D01*
X1094479Y404221D01*
X1094654D01*
Y402651D01*
X1094479D01*
G37*
G36*
G01Y398709D02*
X1093809Y399059D01*
Y399929D01*
X1094479Y400279D01*
X1094654D01*
Y398709D01*
X1094479D01*
G37*
G36*
G01Y394785D02*
X1093809Y395135D01*
Y396005D01*
X1094479Y396355D01*
X1094654D01*
Y394785D01*
X1094479D01*
G37*
G36*
G01X1091668Y391495D02*
X1091636Y392250D01*
X1092389Y392685D01*
X1093027Y392280D01*
X1093115Y392129D01*
X1091755Y391343D01*
X1091668Y391495D01*
G37*
G36*
G01X1092182Y389941D02*
X1092214Y389186D01*
X1091461Y388751D01*
X1090823Y389156D01*
X1090735Y389307D01*
X1092095Y390093D01*
X1092182Y389941D01*
G37*
G36*
G01X1085964Y372957D02*
X1086634Y372607D01*
Y371737D01*
X1085964Y371387D01*
X1085789D01*
Y372957D01*
X1085964D01*
G37*
G36*
G01Y376906D02*
X1086634Y376556D01*
Y375686D01*
X1085964Y375336D01*
X1085789D01*
Y376906D01*
X1085964D01*
G37*
G36*
G01Y380817D02*
X1086634Y380467D01*
Y379597D01*
X1085964Y379247D01*
X1085789D01*
Y380817D01*
X1085964D01*
G37*
G36*
G01Y384717D02*
X1086634Y384367D01*
Y383497D01*
X1085964Y383147D01*
X1085789D01*
Y384717D01*
X1085964D01*
G37*
G36*
G01X1088808Y387995D02*
X1088840Y387240D01*
X1088087Y386805D01*
X1087449Y387210D01*
X1087361Y387361D01*
X1088721Y388147D01*
X1088808Y387995D01*
G37*
G36*
G01X1095562Y391891D02*
X1095594Y391136D01*
X1094841Y390701D01*
X1094203Y391106D01*
X1094115Y391257D01*
X1095475Y392043D01*
X1095562Y391891D01*
G37*
G36*
G01X1067440Y387036D02*
X1066770Y387386D01*
Y388256D01*
X1067440Y388606D01*
X1067615D01*
Y387036D01*
X1067440D01*
G37*
G36*
G01X1068147Y366404D02*
X1067392Y366372D01*
X1066957Y367125D01*
X1067362Y367763D01*
X1067514Y367851D01*
X1068298Y366491D01*
X1068147Y366404D01*
G37*
G36*
G01X1067440Y371387D02*
X1066770Y371737D01*
Y372607D01*
X1067440Y372957D01*
X1067615D01*
Y371387D01*
X1067440D01*
G37*
G36*
G01Y375311D02*
X1066770Y375661D01*
Y376531D01*
X1067440Y376881D01*
X1067615D01*
Y375311D01*
X1067440D01*
G37*
G36*
G01Y379236D02*
X1066770Y379586D01*
Y380456D01*
X1067440Y380806D01*
X1067615D01*
Y379236D01*
X1067440D01*
G37*
G36*
G01Y383136D02*
X1066770Y383486D01*
Y384356D01*
X1067440Y384706D01*
X1067615D01*
Y383136D01*
X1067440D01*
G37*
G36*
G01X1071419Y360611D02*
X1070664Y360645D01*
X1070296Y361433D01*
X1070756Y362033D01*
X1070914Y362107D01*
X1071578Y360685D01*
X1071419Y360611D01*
G37*
G36*
G01X1070805Y398859D02*
X1070045Y399209D01*
Y400109D01*
X1070805Y400459D01*
X1070980D01*
Y398859D01*
X1070805D01*
G37*
G36*
G01Y402759D02*
X1070045Y403109D01*
Y404009D01*
X1070805Y404359D01*
X1070980D01*
Y402759D01*
X1070805D01*
G37*
G36*
G01X1068698Y396465D02*
X1068408Y397249D01*
X1069045Y397886D01*
X1069829Y397596D01*
X1069953Y397472D01*
X1068822Y396341D01*
X1068698Y396465D01*
G37*
G36*
G01X1067440Y390936D02*
X1066770Y391286D01*
Y392156D01*
X1067440Y392506D01*
X1067615D01*
Y390936D01*
X1067440D01*
G37*
G36*
G01X1069064Y390507D02*
X1069734Y390157D01*
Y389287D01*
X1069064Y388937D01*
X1068889D01*
Y390507D01*
X1069064D01*
G37*
G36*
G01X1069853Y366941D02*
X1070260Y367578D01*
X1071127Y367502D01*
X1071417Y366804D01*
X1071402Y366630D01*
X1069838Y366766D01*
X1069853Y366941D01*
G37*
G36*
G01X1069064Y378807D02*
X1069734Y378457D01*
Y377587D01*
X1069064Y377237D01*
X1068889D01*
Y378807D01*
X1069064D01*
G37*
G36*
G01Y374956D02*
X1069734Y374606D01*
Y373736D01*
X1069064Y373386D01*
X1068889D01*
Y374956D01*
X1069064D01*
G37*
G36*
G01Y371032D02*
X1069734Y370682D01*
Y369812D01*
X1069064Y369462D01*
X1068889D01*
Y371032D01*
X1069064D01*
G37*
G36*
G01Y386607D02*
X1069734Y386257D01*
Y385387D01*
X1069064Y385037D01*
X1068889D01*
Y386607D01*
X1069064D01*
G37*
G36*
G01Y382707D02*
X1069734Y382357D01*
Y381487D01*
X1069064Y381137D01*
X1068889D01*
Y382707D01*
X1069064D01*
G37*
G36*
G01X1071922Y400459D02*
X1072682Y400109D01*
Y399209D01*
X1071922Y398859D01*
X1071747D01*
Y400459D01*
X1071922D01*
G37*
G36*
G01Y404359D02*
X1072682Y404009D01*
Y403109D01*
X1071922Y402759D01*
X1071747D01*
Y404359D01*
X1071922D01*
G37*
G36*
G01X1070607Y396818D02*
X1070897Y396033D01*
X1070261Y395397D01*
X1069476Y395687D01*
X1069352Y395810D01*
X1070484Y396942D01*
X1070607Y396818D01*
G37*
G36*
G01X1080960Y387036D02*
X1080290Y387386D01*
Y388256D01*
X1080960Y388606D01*
X1081135D01*
Y387036D01*
X1080960D01*
G37*
G36*
G01X1081516Y389562D02*
X1081484Y390317D01*
X1082238Y390751D01*
X1082875Y390346D01*
X1082964Y390195D01*
X1081604Y389409D01*
X1081516Y389562D01*
G37*
G36*
G01X1080960Y367536D02*
X1080290Y367886D01*
Y368756D01*
X1080960Y369106D01*
X1081135D01*
Y367536D01*
X1080960D01*
G37*
G36*
G01Y375311D02*
X1080290Y375661D01*
Y376531D01*
X1080960Y376881D01*
X1081135D01*
Y375311D01*
X1080960D01*
G37*
G36*
G01Y383136D02*
X1080290Y383486D01*
Y384356D01*
X1080960Y384706D01*
X1081135D01*
Y383136D01*
X1080960D01*
G37*
G36*
G01Y379236D02*
X1080290Y379586D01*
Y380456D01*
X1080960Y380806D01*
X1081135D01*
Y379236D01*
X1080960D01*
G37*
G36*
G01X1081833Y371012D02*
X1082503Y370662D01*
Y369792D01*
X1081833Y369442D01*
X1081658D01*
Y371012D01*
X1081833D01*
G37*
G36*
G01X1091099Y400660D02*
X1090429Y401010D01*
Y401880D01*
X1091099Y402230D01*
X1091274D01*
Y400660D01*
X1091099D01*
G37*
G36*
G01Y396784D02*
X1090429Y397134D01*
Y398004D01*
X1091099Y398354D01*
X1091274D01*
Y396784D01*
X1091099D01*
G37*
G36*
G01X1088254Y393448D02*
X1088222Y394203D01*
X1088975Y394638D01*
X1089613Y394233D01*
X1089701Y394081D01*
X1088341Y393297D01*
X1088254Y393448D01*
G37*
G36*
G01X1084880Y391502D02*
X1084848Y392257D01*
X1085601Y392692D01*
X1086239Y392287D01*
X1086327Y392135D01*
X1084967Y391351D01*
X1084880Y391502D01*
G37*
G36*
G01X1085423Y389941D02*
X1085455Y389186D01*
X1084702Y388751D01*
X1084064Y389156D01*
X1083976Y389307D01*
X1085336Y390093D01*
X1085423Y389941D01*
G37*
G36*
G01X1082584Y374956D02*
X1083254Y374606D01*
Y373736D01*
X1082584Y373386D01*
X1082409D01*
Y374956D01*
X1082584D01*
G37*
G36*
G01Y378807D02*
X1083254Y378457D01*
Y377587D01*
X1082584Y377237D01*
X1082409D01*
Y378807D01*
X1082584D01*
G37*
G36*
G01Y382707D02*
X1083254Y382357D01*
Y381487D01*
X1082584Y381137D01*
X1082409D01*
Y382707D01*
X1082584D01*
G37*
G36*
G01Y386607D02*
X1083254Y386257D01*
Y385387D01*
X1082584Y385037D01*
X1082409D01*
Y386607D01*
X1082584D01*
G37*
G36*
G01X1092723Y396380D02*
X1093393Y396030D01*
Y395160D01*
X1092723Y394810D01*
X1092548D01*
Y396380D01*
X1092723D01*
G37*
G36*
G01Y400280D02*
X1093393Y399930D01*
Y399060D01*
X1092723Y398710D01*
X1092548D01*
Y400280D01*
X1092723D01*
G37*
G36*
G01Y404205D02*
X1093393Y403855D01*
Y402985D01*
X1092723Y402635D01*
X1092548D01*
Y404205D01*
X1092723D01*
G37*
G36*
G01X1092188Y393845D02*
X1092220Y393090D01*
X1091467Y392655D01*
X1090829Y393060D01*
X1090741Y393211D01*
X1092101Y393997D01*
X1092188Y393845D01*
G37*
G36*
G01X1088808Y391895D02*
X1088840Y391140D01*
X1088087Y390705D01*
X1087449Y391110D01*
X1087361Y391261D01*
X1088721Y392047D01*
X1088808Y391895D01*
G37*
G36*
G01X1091099Y361637D02*
X1090429Y361987D01*
Y362857D01*
X1091099Y363207D01*
X1091274D01*
Y361637D01*
X1091099D01*
G37*
G36*
G01Y365537D02*
X1090429Y365887D01*
Y366757D01*
X1091099Y367107D01*
X1091274D01*
Y365537D01*
X1091099D01*
G37*
G36*
G01Y369462D02*
X1090429Y369812D01*
Y370682D01*
X1091099Y371032D01*
X1091274D01*
Y369462D01*
X1091099D01*
G37*
G36*
G01Y373386D02*
X1090429Y373736D01*
Y374606D01*
X1091099Y374956D01*
X1091274D01*
Y373386D01*
X1091099D01*
G37*
G36*
G01Y377237D02*
X1090429Y377587D01*
Y378457D01*
X1091099Y378807D01*
X1091274D01*
Y377237D01*
X1091099D01*
G37*
G36*
G01Y381137D02*
X1090429Y381487D01*
Y382357D01*
X1091099Y382707D01*
X1091274D01*
Y381137D01*
X1091099D01*
G37*
G36*
G01X1091641Y383704D02*
X1091609Y384459D01*
X1092362Y384893D01*
X1093000Y384488D01*
X1093088Y384337D01*
X1091727Y383552D01*
X1091641Y383704D01*
G37*
G36*
G01X1091099Y357737D02*
X1090429Y358087D01*
Y358957D01*
X1091099Y359307D01*
X1091274D01*
Y357737D01*
X1091099D01*
G37*
G36*
G01X1095568Y384095D02*
X1095600Y383340D01*
X1094847Y382905D01*
X1094209Y383310D01*
X1094121Y383461D01*
X1095481Y384247D01*
X1095568Y384095D01*
G37*
G36*
G01X1092723Y376881D02*
X1093393Y376531D01*
Y375661D01*
X1092723Y375311D01*
X1092548D01*
Y376881D01*
X1092723D01*
G37*
G36*
G01Y372957D02*
X1093393Y372607D01*
Y371737D01*
X1092723Y371387D01*
X1092548D01*
Y372957D01*
X1092723D01*
G37*
G36*
G01Y369106D02*
X1093393Y368756D01*
Y367886D01*
X1092723Y367536D01*
X1092548D01*
Y369106D01*
X1092723D01*
G37*
G36*
G01Y380806D02*
X1093393Y380456D01*
Y379586D01*
X1092723Y379236D01*
X1092548D01*
Y380806D01*
X1092723D01*
G37*
G36*
G01X1091640Y387602D02*
X1091608Y388357D01*
X1092361Y388792D01*
X1092999Y388387D01*
X1093087Y388235D01*
X1091727Y387451D01*
X1091640Y387602D01*
G37*
G36*
G01X1087719Y375311D02*
X1087049Y375661D01*
Y376531D01*
X1087719Y376881D01*
X1087894D01*
Y375311D01*
X1087719D01*
G37*
G36*
G01Y371387D02*
X1087049Y371737D01*
Y372607D01*
X1087719Y372957D01*
X1087894D01*
Y371387D01*
X1087719D01*
G37*
G36*
G01Y359736D02*
X1087049Y360086D01*
Y360956D01*
X1087719Y361306D01*
X1087894D01*
Y359736D01*
X1087719D01*
G37*
G36*
G01Y363636D02*
X1087049Y363986D01*
Y364856D01*
X1087719Y365206D01*
X1087894D01*
Y363636D01*
X1087719D01*
G37*
G36*
G01X1088275Y385662D02*
X1088243Y386417D01*
X1088997Y386851D01*
X1089634Y386446D01*
X1089723Y386295D01*
X1088362Y385510D01*
X1088275Y385662D01*
G37*
G36*
G01X1087719Y379236D02*
X1087049Y379586D01*
Y380456D01*
X1087719Y380806D01*
X1087894D01*
Y379236D01*
X1087719D01*
G37*
G36*
G01Y383136D02*
X1087049Y383486D01*
Y384356D01*
X1087719Y384706D01*
X1087894D01*
Y383136D01*
X1087719D01*
G37*
G36*
G01X1095568Y387995D02*
X1095600Y387240D01*
X1094847Y386805D01*
X1094209Y387210D01*
X1094121Y387361D01*
X1095481Y388147D01*
X1095568Y387995D01*
G37*
G36*
G01X1089343Y378807D02*
X1090013Y378457D01*
Y377587D01*
X1089343Y377237D01*
X1089168D01*
Y378807D01*
X1089343D01*
G37*
G36*
G01Y374956D02*
X1090013Y374606D01*
Y373736D01*
X1089343Y373386D01*
X1089168D01*
Y374956D01*
X1089343D01*
G37*
G36*
G01Y371032D02*
X1090013Y370682D01*
Y369812D01*
X1089343Y369462D01*
X1089168D01*
Y371032D01*
X1089343D01*
G37*
G36*
G01Y367107D02*
X1090013Y366757D01*
Y365887D01*
X1089343Y365537D01*
X1089168D01*
Y367107D01*
X1089343D01*
G37*
G36*
G01X1092182Y386041D02*
X1092214Y385286D01*
X1091461Y384851D01*
X1090823Y385256D01*
X1090735Y385407D01*
X1092095Y386193D01*
X1092182Y386041D01*
G37*
G36*
G01X1089343Y382707D02*
X1090013Y382357D01*
Y381487D01*
X1089343Y381137D01*
X1089168D01*
Y382707D01*
X1089343D01*
G37*
G36*
G01X1075824Y390507D02*
X1076494Y390157D01*
Y389287D01*
X1075824Y388937D01*
X1075649D01*
Y390507D01*
X1075824D01*
G37*
G36*
G01X1079203Y369080D02*
X1079873Y368731D01*
Y367861D01*
X1079204Y367511D01*
X1079029Y367510D01*
X1079028Y369081D01*
X1079203Y369080D01*
G37*
G36*
G01X1075824Y378807D02*
X1076494Y378457D01*
Y377587D01*
X1075824Y377237D01*
X1075649D01*
Y378807D01*
X1075824D01*
G37*
G36*
G01Y374956D02*
X1076494Y374606D01*
Y373736D01*
X1075824Y373386D01*
X1075649D01*
Y374956D01*
X1075824D01*
G37*
G36*
G01X1077273Y370854D02*
X1077911Y371260D01*
X1078664Y370825D01*
X1078633Y370070D01*
X1078546Y369918D01*
X1077185Y370703D01*
X1077273Y370854D01*
G37*
G36*
G01X1075824Y386607D02*
X1076494Y386257D01*
Y385387D01*
X1075824Y385037D01*
X1075649D01*
Y386607D01*
X1075824D01*
G37*
G36*
G01Y382707D02*
X1076494Y382357D01*
Y381487D01*
X1075824Y381137D01*
X1075649D01*
Y382707D01*
X1075824D01*
G37*
G36*
G01X1081240Y397181D02*
X1081530Y396396D01*
X1080893Y395759D01*
X1080108Y396049D01*
X1079985Y396173D01*
X1081116Y397305D01*
X1081240Y397181D01*
G37*
G36*
G01X1082205Y401130D02*
X1082965Y400780D01*
Y399880D01*
X1082205Y399530D01*
X1082030D01*
Y401130D01*
X1082205D01*
G37*
G36*
G01X1078654Y393837D02*
X1078686Y393082D01*
X1077933Y392647D01*
X1077295Y393052D01*
X1077207Y393203D01*
X1078567Y393989D01*
X1078654Y393837D01*
G37*
G36*
G01X1084855Y401414D02*
X1084095Y401764D01*
Y402664D01*
X1084855Y403014D01*
X1085030D01*
Y401414D01*
X1084855D01*
G37*
G36*
G01X1078122Y391504D02*
X1078090Y392259D01*
X1078843Y392693D01*
X1079481Y392288D01*
X1079568Y392137D01*
X1078209Y391351D01*
X1078122Y391504D01*
G37*
G36*
G01X1084855Y397514D02*
X1084095Y397864D01*
Y398764D01*
X1084855Y399114D01*
X1085030D01*
Y397514D01*
X1084855D01*
G37*
G36*
G01X1082895Y395062D02*
X1082605Y395846D01*
X1083242Y396483D01*
X1084026Y396193D01*
X1084150Y396069D01*
X1083019Y394938D01*
X1082895Y395062D01*
G37*
G36*
G01X1077580Y385037D02*
X1076910Y385387D01*
Y386257D01*
X1077580Y386607D01*
X1077755D01*
Y385037D01*
X1077580D01*
G37*
G36*
G01Y381137D02*
X1076910Y381487D01*
Y382357D01*
X1077580Y382707D01*
X1077755D01*
Y381137D01*
X1077580D01*
G37*
G36*
G01Y377237D02*
X1076910Y377587D01*
Y378457D01*
X1077580Y378807D01*
X1077755D01*
Y377237D01*
X1077580D01*
G37*
G36*
G01X1077581Y373381D02*
X1076911Y373731D01*
Y374601D01*
X1077581Y374951D01*
X1077756D01*
Y373381D01*
X1077581D01*
G37*
G36*
G01X1077580Y388937D02*
X1076910Y389287D01*
Y390157D01*
X1077580Y390507D01*
X1077755D01*
Y388937D01*
X1077580D01*
G37*
G36*
G01X1074200Y387036D02*
X1073530Y387386D01*
Y388256D01*
X1074200Y388606D01*
X1074375D01*
Y387036D01*
X1074200D01*
G37*
G36*
G01X1077581Y365533D02*
X1076911Y365883D01*
Y366753D01*
X1077581Y367103D01*
X1077756D01*
Y365533D01*
X1077581D01*
G37*
G36*
G01X1076130Y369638D02*
X1075492Y369233D01*
X1074739Y369667D01*
X1074770Y370422D01*
X1074858Y370575D01*
X1076218Y369789D01*
X1076130Y369638D01*
G37*
G36*
G01X1074200Y371411D02*
X1073530Y371761D01*
Y372631D01*
X1074200Y372981D01*
X1074375D01*
Y371411D01*
X1074200D01*
G37*
G36*
G01Y375311D02*
X1073530Y375661D01*
Y376531D01*
X1074200Y376881D01*
X1074375D01*
Y375311D01*
X1074200D01*
G37*
G36*
G01Y383136D02*
X1073530Y383486D01*
Y384356D01*
X1074200Y384706D01*
X1074375D01*
Y383136D01*
X1074200D01*
G37*
G36*
G01Y379236D02*
X1073530Y379586D01*
Y380456D01*
X1074200Y380806D01*
X1074375D01*
Y379236D01*
X1074200D01*
G37*
G36*
G01X1081105Y399530D02*
X1080345Y399880D01*
Y400780D01*
X1081105Y401130D01*
X1081280D01*
Y399530D01*
X1081105D01*
G37*
G36*
G01X1074771Y393470D02*
X1074740Y394225D01*
X1075493Y394660D01*
X1076131Y394254D01*
X1076219Y394103D01*
X1074858Y393318D01*
X1074771Y393470D01*
G37*
G36*
G01X1074200Y390936D02*
X1073530Y391286D01*
Y392156D01*
X1074200Y392506D01*
X1074375D01*
Y390936D01*
X1074200D01*
G37*
G36*
G01X1094479Y359736D02*
X1093809Y360086D01*
Y360956D01*
X1094479Y361306D01*
X1094654D01*
Y359736D01*
X1094479D01*
G37*
G36*
G01Y363636D02*
X1093809Y363986D01*
Y364856D01*
X1094479Y365206D01*
X1094654D01*
Y363636D01*
X1094479D01*
G37*
G36*
G01Y367536D02*
X1093809Y367886D01*
Y368756D01*
X1094479Y369106D01*
X1094654D01*
Y367536D01*
X1094479D01*
G37*
G36*
G01Y371387D02*
X1093809Y371737D01*
Y372607D01*
X1094479Y372957D01*
X1094654D01*
Y371387D01*
X1094479D01*
G37*
G36*
G01Y375311D02*
X1093809Y375661D01*
Y376531D01*
X1094479Y376881D01*
X1094654D01*
Y375311D01*
X1094479D01*
G37*
G36*
G01Y379211D02*
X1093809Y379561D01*
Y380431D01*
X1094479Y380781D01*
X1094654D01*
Y379211D01*
X1094479D01*
G37*
G36*
G01Y355836D02*
X1093809Y356186D01*
Y357056D01*
X1094479Y357406D01*
X1094654D01*
Y355836D01*
X1094479D01*
G37*
G36*
G01X1085955Y403014D02*
X1086715Y402664D01*
Y401764D01*
X1085955Y401414D01*
X1085780D01*
Y403014D01*
X1085955D01*
G37*
G36*
G01X1082049Y391895D02*
X1082081Y391140D01*
X1081328Y390705D01*
X1080690Y391110D01*
X1080602Y391261D01*
X1081962Y392047D01*
X1082049Y391895D01*
G37*
G36*
G01X1085955Y399114D02*
X1086715Y398764D01*
Y397864D01*
X1085955Y397514D01*
X1085780D01*
Y399114D01*
X1085955D01*
G37*
G36*
G01X1084805Y395414D02*
X1085095Y394630D01*
X1084458Y393993D01*
X1083674Y394283D01*
X1083550Y394407D01*
X1084681Y395538D01*
X1084805Y395414D01*
G37*
G36*
G01X1079204Y380806D02*
X1079874Y380456D01*
Y379586D01*
X1079204Y379236D01*
X1079029D01*
Y380806D01*
X1079204D01*
G37*
G36*
G01Y384706D02*
X1079874Y384356D01*
Y383486D01*
X1079204Y383136D01*
X1079029D01*
Y384706D01*
X1079204D01*
G37*
G36*
G01Y376881D02*
X1079874Y376531D01*
Y375661D01*
X1079204Y375311D01*
X1079029D01*
Y376881D01*
X1079204D01*
G37*
G36*
G01Y388606D02*
X1079874Y388256D01*
Y387386D01*
X1079204Y387036D01*
X1079029D01*
Y388606D01*
X1079204D01*
G37*
G36*
G01X1074723Y406411D02*
X1073963Y406761D01*
Y407661D01*
X1074723Y408011D01*
X1074898D01*
Y406411D01*
X1074723D01*
G37*
G36*
G01X1075825Y407511D02*
X1076585Y407161D01*
Y406261D01*
X1075825Y405911D01*
X1075650D01*
Y407511D01*
X1075825D01*
G37*
G36*
G01X1070805Y406659D02*
X1070045Y407009D01*
Y407909D01*
X1070805Y408259D01*
X1070980D01*
Y406659D01*
X1070805D01*
G37*
G36*
G01X1071922Y408259D02*
X1072682Y407909D01*
Y407009D01*
X1071922Y406659D01*
X1071747D01*
Y408259D01*
X1071922D01*
G37*
G36*
G01X1082205Y405030D02*
X1082965Y404680D01*
Y403780D01*
X1082205Y403430D01*
X1082030D01*
Y405030D01*
X1082205D01*
G37*
G36*
G01Y408930D02*
X1082965Y408580D01*
Y407680D01*
X1082205Y407330D01*
X1082030D01*
Y408930D01*
X1082205D01*
G37*
G36*
G01X1084855Y409214D02*
X1084095Y409564D01*
Y410464D01*
X1084855Y410814D01*
X1085030D01*
Y409214D01*
X1084855D01*
G37*
G36*
G01Y405314D02*
X1084095Y405664D01*
Y406564D01*
X1084855Y406914D01*
X1085030D01*
Y405314D01*
X1084855D01*
G37*
G36*
G01X1081105Y403430D02*
X1080345Y403780D01*
Y404680D01*
X1081105Y405030D01*
X1081280D01*
Y403430D01*
X1081105D01*
G37*
G36*
G01Y407330D02*
X1080345Y407680D01*
Y408580D01*
X1081105Y408930D01*
X1081280D01*
Y407330D01*
X1081105D01*
G37*
G36*
G01X1085955Y410814D02*
X1086715Y410464D01*
Y409564D01*
X1085955Y409214D01*
X1085780D01*
Y410814D01*
X1085955D01*
G37*
G36*
G01Y406914D02*
X1086715Y406564D01*
Y405664D01*
X1085955Y405314D01*
X1085780D01*
Y406914D01*
X1085955D01*
G37*
G36*
G01X1102371Y199397D02*
X1101611Y199747D01*
Y200647D01*
X1102371Y200997D01*
X1102546D01*
Y199397D01*
X1102371D01*
G37*
G36*
G01Y195497D02*
X1101611Y195847D01*
Y196747D01*
X1102371Y197097D01*
X1102546D01*
Y195497D01*
X1102371D01*
G37*
G36*
G01Y203297D02*
X1101611Y203647D01*
Y204547D01*
X1102371Y204897D01*
X1102546D01*
Y203297D01*
X1102371D01*
G37*
G36*
G01Y191597D02*
X1101611Y191947D01*
Y192847D01*
X1102371Y193197D01*
X1102546D01*
Y191597D01*
X1102371D01*
G37*
G36*
G01X1103499Y215436D02*
X1102829Y215786D01*
Y216656D01*
X1103499Y217006D01*
X1103674D01*
Y215436D01*
X1103499D01*
G37*
G36*
G01X1102371Y207197D02*
X1101611Y207547D01*
Y208447D01*
X1102371Y208797D01*
X1102546D01*
Y207197D01*
X1102371D01*
G37*
G36*
G01X1103471Y200997D02*
X1104231Y200647D01*
Y199747D01*
X1103471Y199397D01*
X1103296D01*
Y200997D01*
X1103471D01*
G37*
G36*
G01Y197097D02*
X1104231Y196747D01*
Y195847D01*
X1103471Y195497D01*
X1103296D01*
Y197097D01*
X1103471D01*
G37*
G36*
G01Y204897D02*
X1104231Y204547D01*
Y203647D01*
X1103471Y203297D01*
X1103296D01*
Y204897D01*
X1103471D01*
G37*
G36*
G01Y193197D02*
X1104231Y192847D01*
Y191947D01*
X1103471Y191597D01*
X1103296D01*
Y193197D01*
X1103471D01*
G37*
G36*
G01X1105123Y218907D02*
X1105793Y218557D01*
Y217687D01*
X1105123Y217337D01*
X1104948D01*
Y218907D01*
X1105123D01*
G37*
G36*
G01Y215007D02*
X1105793Y214657D01*
Y213787D01*
X1105123Y213437D01*
X1104948D01*
Y215007D01*
X1105123D01*
G37*
G36*
G01X1103471Y208797D02*
X1104231Y208447D01*
Y207547D01*
X1103471Y207197D01*
X1103296D01*
Y208797D01*
X1103471D01*
G37*
G36*
G01X1117593Y196333D02*
X1116833Y196683D01*
Y197583D01*
X1117593Y197933D01*
X1117768D01*
Y196333D01*
X1117593D01*
G37*
G36*
G01Y200233D02*
X1116833Y200583D01*
Y201483D01*
X1117593Y201833D01*
X1117768D01*
Y200233D01*
X1117593D01*
G37*
G36*
G01Y203833D02*
X1116833Y204183D01*
Y205083D01*
X1117593Y205433D01*
X1117768D01*
Y203833D01*
X1117593D01*
G37*
G36*
G01X1120790Y190852D02*
X1120005Y190562D01*
X1119369Y191198D01*
X1119659Y191983D01*
X1119782Y192107D01*
X1120914Y190975D01*
X1120790Y190852D01*
G37*
G36*
G01X1117021Y209524D02*
X1116261Y209874D01*
Y210774D01*
X1117021Y211124D01*
X1117196D01*
Y209524D01*
X1117021D01*
G37*
G36*
G01Y213424D02*
X1116261Y213774D01*
Y214674D01*
X1117021Y215024D01*
X1117196D01*
Y213424D01*
X1117021D01*
G37*
G36*
G01X1118693Y197933D02*
X1119453Y197583D01*
Y196683D01*
X1118693Y196333D01*
X1118518D01*
Y197933D01*
X1118693D01*
G37*
G36*
G01Y201833D02*
X1119453Y201483D01*
Y200583D01*
X1118693Y200233D01*
X1118518D01*
Y201833D01*
X1118693D01*
G37*
G36*
G01X1120437Y192761D02*
X1121221Y193051D01*
X1121858Y192414D01*
X1121568Y191630D01*
X1121444Y191506D01*
X1120313Y192637D01*
X1120437Y192761D01*
G37*
G36*
G01X1118643Y218907D02*
X1119313Y218557D01*
Y217687D01*
X1118643Y217337D01*
X1118468D01*
Y218907D01*
X1118643D01*
G37*
G36*
G01X1118693Y205733D02*
X1119453Y205383D01*
Y204483D01*
X1118693Y204133D01*
X1118518D01*
Y205733D01*
X1118693D01*
G37*
G36*
G01X1118121Y211124D02*
X1118881Y210774D01*
Y209874D01*
X1118121Y209524D01*
X1117946D01*
Y211124D01*
X1118121D01*
G37*
G36*
G01Y215024D02*
X1118881Y214674D01*
Y213774D01*
X1118121Y213424D01*
X1117946D01*
Y215024D01*
X1118121D01*
G37*
G36*
G01X1099351Y201183D02*
X1098591Y201533D01*
Y202433D01*
X1099351Y202783D01*
X1099526D01*
Y201183D01*
X1099351D01*
G37*
G36*
G01Y197283D02*
X1098591Y197633D01*
Y198533D01*
X1099351Y198883D01*
X1099526D01*
Y197283D01*
X1099351D01*
G37*
G36*
G01Y189483D02*
X1098591Y189833D01*
Y190733D01*
X1099351Y191083D01*
X1099526D01*
Y189483D01*
X1099351D01*
G37*
G36*
G01Y193383D02*
X1098591Y193733D01*
Y194633D01*
X1099351Y194983D01*
X1099526D01*
Y193383D01*
X1099351D01*
G37*
G36*
G01X1100119Y217337D02*
X1099449Y217687D01*
Y218557D01*
X1100119Y218907D01*
X1100294D01*
Y217337D01*
X1100119D01*
G37*
G36*
G01Y213437D02*
X1099449Y213787D01*
Y214657D01*
X1100119Y215007D01*
X1100294D01*
Y213437D01*
X1100119D01*
G37*
G36*
G01X1099351Y205083D02*
X1098591Y205433D01*
Y206333D01*
X1099351Y206683D01*
X1099526D01*
Y205083D01*
X1099351D01*
G37*
G36*
G01X1100451Y202783D02*
X1101211Y202433D01*
Y201533D01*
X1100451Y201183D01*
X1100276D01*
Y202783D01*
X1100451D01*
G37*
G36*
G01Y198883D02*
X1101211Y198533D01*
Y197633D01*
X1100451Y197283D01*
X1100276D01*
Y198883D01*
X1100451D01*
G37*
G36*
G01Y191083D02*
X1101211Y190733D01*
Y189833D01*
X1100451Y189483D01*
X1100276D01*
Y191083D01*
X1100451D01*
G37*
G36*
G01Y194983D02*
X1101211Y194633D01*
Y193733D01*
X1100451Y193383D01*
X1100276D01*
Y194983D01*
X1100451D01*
G37*
G36*
G01X1101743Y217006D02*
X1102413Y216656D01*
Y215786D01*
X1101743Y215436D01*
X1101568D01*
Y217006D01*
X1101743D01*
G37*
G36*
G01X1100451Y206683D02*
X1101211Y206333D01*
Y205433D01*
X1100451Y205083D01*
X1100276D01*
Y206683D01*
X1100451D01*
G37*
G36*
G01X1114567Y198259D02*
X1113807Y198609D01*
Y199509D01*
X1114567Y199859D01*
X1114742D01*
Y198259D01*
X1114567D01*
G37*
G36*
G01X1113442Y203765D02*
X1112682Y204115D01*
Y205015D01*
X1113442Y205365D01*
X1113617D01*
Y203765D01*
X1113442D01*
G37*
G36*
G01X1114567Y194359D02*
X1113807Y194709D01*
Y195609D01*
X1114567Y195959D01*
X1114742D01*
Y194359D01*
X1114567D01*
G37*
G36*
G01X1116737Y190631D02*
X1115952Y190341D01*
X1115315Y190977D01*
X1115605Y191762D01*
X1115729Y191886D01*
X1116861Y190754D01*
X1116737Y190631D01*
G37*
G36*
G01X1113639Y217337D02*
X1112969Y217687D01*
Y218557D01*
X1113639Y218907D01*
X1113814D01*
Y217337D01*
X1113639D01*
G37*
G36*
G01X1113442Y207665D02*
X1112682Y208015D01*
Y208915D01*
X1113442Y209265D01*
X1113617D01*
Y207665D01*
X1113442D01*
G37*
G36*
G01Y211565D02*
X1112682Y211915D01*
Y212815D01*
X1113442Y213165D01*
X1113617D01*
Y211565D01*
X1113442D01*
G37*
G36*
G01X1115667Y195959D02*
X1116427Y195609D01*
Y194709D01*
X1115667Y194359D01*
X1115492D01*
Y195959D01*
X1115667D01*
G37*
G36*
G01X1114542Y205365D02*
X1115302Y205015D01*
Y204115D01*
X1114542Y203765D01*
X1114367D01*
Y205365D01*
X1114542D01*
G37*
G36*
G01X1115667Y199859D02*
X1116427Y199509D01*
Y198609D01*
X1115667Y198259D01*
X1115492D01*
Y199859D01*
X1115667D01*
G37*
G36*
G01X1116337Y192587D02*
X1117122Y192876D01*
X1117758Y192240D01*
X1117468Y191455D01*
X1117345Y191331D01*
X1116213Y192463D01*
X1116337Y192587D01*
G37*
G36*
G01X1114542Y209265D02*
X1115302Y208915D01*
Y208015D01*
X1114542Y207665D01*
X1114367D01*
Y209265D01*
X1114542D01*
G37*
G36*
G01Y213165D02*
X1115302Y212815D01*
Y211915D01*
X1114542Y211565D01*
X1114367D01*
Y213165D01*
X1114542D01*
G37*
G36*
G01X1123778Y215436D02*
X1123108Y215786D01*
Y216656D01*
X1123778Y217006D01*
X1123953D01*
Y215436D01*
X1123778D01*
G37*
G36*
G01Y211536D02*
X1123108Y211886D01*
Y212756D01*
X1123778Y213106D01*
X1123953D01*
Y211536D01*
X1123778D01*
G37*
G36*
G01X1129624Y194943D02*
X1128840Y194653D01*
X1128203Y195290D01*
X1128493Y196074D01*
X1128617Y196198D01*
X1129748Y195067D01*
X1129624Y194943D01*
G37*
G36*
G01X1124142Y208920D02*
X1123382Y209270D01*
Y210170D01*
X1124142Y210520D01*
X1124317D01*
Y208920D01*
X1124142D01*
G37*
G36*
G01X1125402Y218907D02*
X1126072Y218557D01*
Y217687D01*
X1125402Y217337D01*
X1125227D01*
Y218907D01*
X1125402D01*
G37*
G36*
G01X1125241Y209720D02*
X1126001Y209370D01*
Y208470D01*
X1125241Y208120D01*
X1125066D01*
Y209720D01*
X1125241D01*
G37*
G36*
G01X1125402Y215007D02*
X1126072Y214657D01*
Y213787D01*
X1125402Y213437D01*
X1125227D01*
Y215007D01*
X1125402D01*
G37*
G36*
G01X1129273Y196854D02*
X1130058Y197144D01*
X1130694Y196508D01*
X1130404Y195723D01*
X1130281Y195599D01*
X1129149Y196731D01*
X1129273Y196854D01*
G37*
G36*
G01X1137298Y211536D02*
X1136628Y211886D01*
Y212756D01*
X1137298Y213106D01*
X1137473D01*
Y211536D01*
X1137298D01*
G37*
G36*
G01Y215436D02*
X1136628Y215786D01*
Y216656D01*
X1137298Y217006D01*
X1137473D01*
Y215436D01*
X1137298D01*
G37*
G36*
G01X1141305Y206963D02*
X1140520Y206673D01*
X1139884Y207309D01*
X1140174Y208094D01*
X1140297Y208218D01*
X1141429Y207086D01*
X1141305Y206963D01*
G37*
G36*
G01X1138922Y218907D02*
X1139592Y218557D01*
Y217687D01*
X1138922Y217337D01*
X1138747D01*
Y218907D01*
X1138922D01*
G37*
G36*
G01Y215007D02*
X1139592Y214657D01*
Y213787D01*
X1138922Y213437D01*
X1138747D01*
Y215007D01*
X1138922D01*
G37*
G36*
G01X1140952Y208872D02*
X1141736Y209162D01*
X1142373Y208525D01*
X1142083Y207741D01*
X1141959Y207617D01*
X1140828Y208748D01*
X1140952Y208872D01*
G37*
G36*
G01X1125911Y194284D02*
X1125127Y193994D01*
X1124490Y194631D01*
X1124780Y195415D01*
X1124904Y195539D01*
X1126035Y194408D01*
X1125911Y194284D01*
G37*
G36*
G01X1123154Y197042D02*
X1122369Y196752D01*
X1121732Y197388D01*
X1122022Y198173D01*
X1122146Y198297D01*
X1123277Y197166D01*
X1123154Y197042D01*
G37*
G36*
G01X1121123Y202977D02*
X1120363Y203327D01*
Y204227D01*
X1121123Y204577D01*
X1121298D01*
Y202977D01*
X1121123D01*
G37*
G36*
G01X1120398Y217326D02*
X1119728Y217676D01*
Y218546D01*
X1120398Y218896D01*
X1120573D01*
Y217326D01*
X1120398D01*
G37*
G36*
G01Y213419D02*
X1119728Y213769D01*
Y214639D01*
X1120398Y214989D01*
X1120573D01*
Y213419D01*
X1120398D01*
G37*
G36*
G01X1120921Y209743D02*
X1120251Y210093D01*
Y210963D01*
X1120921Y211313D01*
X1121096D01*
Y209743D01*
X1120921D01*
G37*
G36*
G01X1122800Y198951D02*
X1123585Y199241D01*
X1124222Y198605D01*
X1123932Y197820D01*
X1123808Y197696D01*
X1122677Y198827D01*
X1122800Y198951D01*
G37*
G36*
G01X1125558Y196193D02*
X1126343Y196483D01*
X1126979Y195847D01*
X1126689Y195062D01*
X1126566Y194938D01*
X1125434Y196070D01*
X1125558Y196193D01*
G37*
G36*
G01X1122223Y204577D02*
X1122983Y204227D01*
Y203327D01*
X1122223Y202977D01*
X1122048D01*
Y204577D01*
X1122223D01*
G37*
G36*
G01X1122023Y217017D02*
X1122693Y216667D01*
Y215797D01*
X1122023Y215447D01*
X1121848D01*
Y217017D01*
X1122023D01*
G37*
G36*
G01X1122024Y211726D02*
X1122694Y211376D01*
Y210506D01*
X1122024Y210156D01*
X1121849D01*
Y211726D01*
X1122024D01*
G37*
G36*
G01X1138149Y203462D02*
X1137365Y203172D01*
X1136728Y203809D01*
X1137018Y204593D01*
X1137142Y204717D01*
X1138273Y203586D01*
X1138149Y203462D01*
G37*
G36*
G01X1133918Y217337D02*
X1133248Y217687D01*
Y218557D01*
X1133918Y218907D01*
X1134093D01*
Y217337D01*
X1133918D01*
G37*
G36*
G01X1133919Y209581D02*
X1133249Y209931D01*
Y210801D01*
X1133919Y211151D01*
X1134094D01*
Y209581D01*
X1133919D01*
G37*
G36*
G01X1133918Y213437D02*
X1133248Y213787D01*
Y214657D01*
X1133918Y215007D01*
X1134093D01*
Y213437D01*
X1133918D01*
G37*
G36*
G01X1135542Y217006D02*
X1136212Y216656D01*
Y215786D01*
X1135542Y215436D01*
X1135367D01*
Y217006D01*
X1135542D01*
G37*
G36*
G01Y213081D02*
X1136212Y212731D01*
Y211861D01*
X1135542Y211511D01*
X1135367D01*
Y213081D01*
X1135542D01*
G37*
G36*
G01X1137894Y205282D02*
X1138678Y205572D01*
X1139315Y204935D01*
X1139025Y204151D01*
X1138901Y204027D01*
X1137770Y205158D01*
X1137894Y205282D01*
G37*
G36*
G01X1110646Y186322D02*
X1111406Y185972D01*
Y185072D01*
X1110646Y184722D01*
X1110471D01*
Y186322D01*
X1110646D01*
G37*
G36*
G01X1107391Y197193D02*
X1108061Y196843D01*
Y195973D01*
X1107391Y195623D01*
X1107216D01*
Y197193D01*
X1107391D01*
G37*
G36*
G01X1108502Y204685D02*
X1109262Y204335D01*
Y203435D01*
X1108502Y203085D01*
X1108327D01*
Y204685D01*
X1108502D01*
G37*
G36*
G01X1107391Y193293D02*
X1108061Y192943D01*
Y192073D01*
X1107391Y191723D01*
X1107216D01*
Y193293D01*
X1107391D01*
G37*
G36*
G01X1108413Y189463D02*
X1109134Y189689D01*
X1109749Y189074D01*
X1109523Y188353D01*
X1109399Y188229D01*
X1108289Y189339D01*
X1108413Y189463D01*
G37*
G36*
G01X1108503Y217006D02*
X1109173Y216656D01*
Y215786D01*
X1108503Y215436D01*
X1108328D01*
Y217006D01*
X1108503D01*
G37*
G36*
G01X1108502Y208585D02*
X1109262Y208235D01*
Y207335D01*
X1108502Y206985D01*
X1108327D01*
Y208585D01*
X1108502D01*
G37*
G36*
G01Y212485D02*
X1109262Y212135D01*
Y211235D01*
X1108502Y210885D01*
X1108327D01*
Y212485D01*
X1108502D01*
G37*
G36*
G01X1130772Y200135D02*
X1131557Y200425D01*
X1132193Y199789D01*
X1131904Y199004D01*
X1131780Y198880D01*
X1130648Y200012D01*
X1130772Y200135D01*
G37*
G36*
G01X1128781Y213037D02*
X1129451Y212687D01*
Y211817D01*
X1128781Y211467D01*
X1128606D01*
Y213037D01*
X1128781D01*
G37*
G36*
G01X1128782Y217006D02*
X1129452Y216656D01*
Y215786D01*
X1128782Y215436D01*
X1128607D01*
Y217006D01*
X1128782D01*
G37*
G36*
G01X1128261Y209193D02*
X1128931Y208843D01*
Y207973D01*
X1128261Y207623D01*
X1128086D01*
Y209193D01*
X1128261D01*
G37*
G36*
G01X1134278Y197851D02*
X1135063Y198141D01*
X1135699Y197505D01*
X1135410Y196720D01*
X1135286Y196596D01*
X1134154Y197728D01*
X1134278Y197851D01*
G37*
G36*
G01X1111522Y204357D02*
X1112282Y204007D01*
Y203107D01*
X1111522Y202757D01*
X1111347D01*
Y204357D01*
X1111522D01*
G37*
G36*
G01X1110231Y197350D02*
X1110901Y197000D01*
Y196129D01*
X1110231Y195779D01*
X1110056D01*
Y197350D01*
X1110231D01*
G37*
G36*
G01X1111603Y193041D02*
X1112387Y193331D01*
X1113024Y192694D01*
X1112734Y191910D01*
X1112610Y191786D01*
X1111479Y192917D01*
X1111603Y193041D01*
G37*
G36*
G01X1111522Y208257D02*
X1112282Y207907D01*
Y207007D01*
X1111522Y206657D01*
X1111347D01*
Y208257D01*
X1111522D01*
G37*
G36*
G01X1111883Y218907D02*
X1112553Y218557D01*
Y217687D01*
X1111883Y217337D01*
X1111708D01*
Y218907D01*
X1111883D01*
G37*
G36*
G01X1111522Y212157D02*
X1112282Y211807D01*
Y210907D01*
X1111522Y210557D01*
X1111347D01*
Y212157D01*
X1111522D01*
G37*
G36*
G01X1132162Y218907D02*
X1132832Y218557D01*
Y217687D01*
X1132162Y217337D01*
X1131987D01*
Y218907D01*
X1132162D01*
G37*
G36*
G01Y215007D02*
X1132832Y214657D01*
Y213787D01*
X1132162Y213437D01*
X1131987D01*
Y215007D01*
X1132162D01*
G37*
G36*
G01X1132430Y209772D02*
X1133190Y209422D01*
Y208522D01*
X1132430Y208172D01*
X1132255D01*
Y209772D01*
X1132430D01*
G37*
G36*
G01Y205872D02*
X1133190Y205522D01*
Y204622D01*
X1132430Y204272D01*
X1132255D01*
Y205872D01*
X1132430D01*
G37*
G36*
G01X1106291Y195623D02*
X1105621Y195973D01*
Y196843D01*
X1106291Y197193D01*
X1106466D01*
Y195623D01*
X1106291D01*
G37*
G36*
G01X1109546Y184522D02*
X1108786Y184872D01*
Y185772D01*
X1109546Y186122D01*
X1109721D01*
Y184522D01*
X1109546D01*
G37*
G36*
G01X1106036Y201987D02*
X1105746Y202772D01*
X1106382Y203408D01*
X1107167Y203118D01*
X1107291Y202995D01*
X1106159Y201863D01*
X1106036Y201987D01*
G37*
G36*
G01X1106291Y191723D02*
X1105621Y192073D01*
Y192943D01*
X1106291Y193293D01*
X1106466D01*
Y191723D01*
X1106291D01*
G37*
G36*
G01X1108525Y187795D02*
X1107804Y187569D01*
X1107189Y188184D01*
X1107415Y188905D01*
X1107539Y189029D01*
X1108649Y187919D01*
X1108525Y187795D01*
G37*
G36*
G01X1106879Y217337D02*
X1106209Y217687D01*
Y218557D01*
X1106879Y218907D01*
X1107054D01*
Y217337D01*
X1106879D01*
G37*
G36*
G01Y213437D02*
X1106209Y213787D01*
Y214657D01*
X1106879Y215007D01*
X1107054D01*
Y213437D01*
X1106879D01*
G37*
G36*
G01X1107402Y209485D02*
X1106642Y209835D01*
Y210735D01*
X1107402Y211085D01*
X1107577D01*
Y209485D01*
X1107402D01*
G37*
G36*
G01Y205585D02*
X1106642Y205935D01*
Y206835D01*
X1107402Y207185D01*
X1107577D01*
Y205585D01*
X1107402D01*
G37*
G36*
G01X1127161Y205323D02*
X1126401Y205673D01*
Y206573D01*
X1127161Y206923D01*
X1127336D01*
Y205323D01*
X1127161D01*
G37*
G36*
G01X1128886Y203006D02*
X1128101Y202716D01*
X1127465Y203352D01*
X1127754Y204137D01*
X1127878Y204261D01*
X1129010Y203129D01*
X1128886Y203006D01*
G37*
G36*
G01X1131058Y198294D02*
X1130273Y198004D01*
X1129637Y198640D01*
X1129926Y199425D01*
X1130050Y199549D01*
X1131182Y198417D01*
X1131058Y198294D01*
G37*
G36*
G01X1127158Y217337D02*
X1126488Y217687D01*
Y218557D01*
X1127158Y218907D01*
X1127333D01*
Y217337D01*
X1127158D01*
G37*
G36*
G01Y213437D02*
X1126488Y213787D01*
Y214657D01*
X1127158Y215007D01*
X1127333D01*
Y213437D01*
X1127158D01*
G37*
G36*
G01X1127161Y209019D02*
X1126491Y209369D01*
Y210239D01*
X1127161Y210589D01*
X1127336D01*
Y209019D01*
X1127161D01*
G37*
G36*
G01X1109131Y195779D02*
X1108461Y196129D01*
Y197000D01*
X1109131Y197350D01*
X1109306D01*
Y195779D01*
X1109131D01*
G37*
G36*
G01X1110422Y202757D02*
X1109662Y203107D01*
Y204007D01*
X1110422Y204357D01*
X1110597D01*
Y202757D01*
X1110422D01*
G37*
G36*
G01X1111956Y191132D02*
X1111171Y190842D01*
X1110535Y191478D01*
X1110825Y192263D01*
X1110948Y192387D01*
X1112080Y191255D01*
X1111956Y191132D01*
G37*
G36*
G01X1110422Y210557D02*
X1109662Y210907D01*
Y211807D01*
X1110422Y212157D01*
X1110597D01*
Y210557D01*
X1110422D01*
G37*
G36*
G01Y206657D02*
X1109662Y207007D01*
Y207907D01*
X1110422Y208257D01*
X1110597D01*
Y206657D01*
X1110422D01*
G37*
G36*
G01X1110259Y215436D02*
X1109589Y215786D01*
Y216656D01*
X1110259Y217006D01*
X1110434D01*
Y215436D01*
X1110259D01*
G37*
G36*
G01X1131330Y203772D02*
X1130570Y204122D01*
Y205022D01*
X1131330Y205372D01*
X1131505D01*
Y203772D01*
X1131330D01*
G37*
G36*
G01X1130538Y215436D02*
X1129868Y215786D01*
Y216656D01*
X1130538Y217006D01*
X1130713D01*
Y215436D01*
X1130538D01*
G37*
G36*
G01Y211511D02*
X1129868Y211861D01*
Y212731D01*
X1130538Y213081D01*
X1130713D01*
Y211511D01*
X1130538D01*
G37*
G36*
G01X1131330Y207672D02*
X1130570Y208022D01*
Y208922D01*
X1131330Y209272D01*
X1131505D01*
Y207672D01*
X1131330D01*
G37*
G36*
G01X1103499Y219336D02*
X1102829Y219686D01*
Y220556D01*
X1103499Y220906D01*
X1103674D01*
Y219336D01*
X1103499D01*
G37*
G36*
G01Y223236D02*
X1102829Y223586D01*
Y224456D01*
X1103499Y224806D01*
X1103674D01*
Y223236D01*
X1103499D01*
G37*
G36*
G01Y227136D02*
X1102829Y227486D01*
Y228356D01*
X1103499Y228706D01*
X1103674D01*
Y227136D01*
X1103499D01*
G37*
G36*
G01Y230987D02*
X1102829Y231337D01*
Y232207D01*
X1103499Y232557D01*
X1103674D01*
Y230987D01*
X1103499D01*
G37*
G36*
G01Y238836D02*
X1102829Y239186D01*
Y240056D01*
X1103499Y240406D01*
X1103674D01*
Y238836D01*
X1103499D01*
G37*
G36*
G01Y234911D02*
X1102829Y235261D01*
Y236131D01*
X1103499Y236481D01*
X1103674D01*
Y234911D01*
X1103499D01*
G37*
G36*
G01Y242736D02*
X1102829Y243086D01*
Y243956D01*
X1103499Y244306D01*
X1103674D01*
Y242736D01*
X1103499D01*
G37*
G36*
G01X1105123Y222807D02*
X1105793Y222457D01*
Y221587D01*
X1105123Y221237D01*
X1104948D01*
Y222807D01*
X1105123D01*
G37*
G36*
G01Y226707D02*
X1105793Y226357D01*
Y225487D01*
X1105123Y225137D01*
X1104948D01*
Y226707D01*
X1105123D01*
G37*
G36*
G01Y230632D02*
X1105793Y230282D01*
Y229412D01*
X1105123Y229062D01*
X1104948D01*
Y230632D01*
X1105123D01*
G37*
G36*
G01Y234556D02*
X1105793Y234206D01*
Y233336D01*
X1105123Y232986D01*
X1104948D01*
Y234556D01*
X1105123D01*
G37*
G36*
G01Y238407D02*
X1105793Y238057D01*
Y237187D01*
X1105123Y236837D01*
X1104948D01*
Y238407D01*
X1105123D01*
G37*
G36*
G01Y242307D02*
X1105793Y241957D01*
Y241087D01*
X1105123Y240737D01*
X1104948D01*
Y242307D01*
X1105123D01*
G37*
G36*
G01X1106142Y249616D02*
X1106839Y249907D01*
X1107508Y249350D01*
X1107348Y248611D01*
X1107236Y248477D01*
X1106030Y249482D01*
X1106142Y249616D01*
G37*
G36*
G01X1117019Y219336D02*
X1116349Y219686D01*
Y220556D01*
X1117019Y220906D01*
X1117194D01*
Y219336D01*
X1117019D01*
G37*
G36*
G01Y223236D02*
X1116349Y223586D01*
Y224456D01*
X1117019Y224806D01*
X1117194D01*
Y223236D01*
X1117019D01*
G37*
G36*
G01Y227136D02*
X1116349Y227486D01*
Y228356D01*
X1117019Y228706D01*
X1117194D01*
Y227136D01*
X1117019D01*
G37*
G36*
G01Y230987D02*
X1116349Y231337D01*
Y232207D01*
X1117019Y232557D01*
X1117194D01*
Y230987D01*
X1117019D01*
G37*
G36*
G01Y234911D02*
X1116349Y235261D01*
Y236131D01*
X1117019Y236481D01*
X1117194D01*
Y234911D01*
X1117019D01*
G37*
G36*
G01Y238836D02*
X1116349Y239186D01*
Y240056D01*
X1117019Y240406D01*
X1117194D01*
Y238836D01*
X1117019D01*
G37*
G36*
G01Y246636D02*
X1116349Y246986D01*
Y247856D01*
X1117019Y248206D01*
X1117194D01*
Y246636D01*
X1117019D01*
G37*
G36*
G01Y242736D02*
X1116349Y243086D01*
Y243956D01*
X1117019Y244306D01*
X1117194D01*
Y242736D01*
X1117019D01*
G37*
G36*
G01X1118643Y222807D02*
X1119313Y222457D01*
Y221587D01*
X1118643Y221237D01*
X1118468D01*
Y222807D01*
X1118643D01*
G37*
G36*
G01Y226707D02*
X1119313Y226357D01*
Y225487D01*
X1118643Y225137D01*
X1118468D01*
Y226707D01*
X1118643D01*
G37*
G36*
G01Y230632D02*
X1119313Y230282D01*
Y229412D01*
X1118643Y229062D01*
X1118468D01*
Y230632D01*
X1118643D01*
G37*
G36*
G01Y234556D02*
X1119313Y234206D01*
Y233336D01*
X1118643Y232986D01*
X1118468D01*
Y234556D01*
X1118643D01*
G37*
G36*
G01Y242307D02*
X1119313Y241957D01*
Y241087D01*
X1118643Y240737D01*
X1118468D01*
Y242307D01*
X1118643D01*
G37*
G36*
G01Y238407D02*
X1119313Y238057D01*
Y237187D01*
X1118643Y236837D01*
X1118468D01*
Y238407D01*
X1118643D01*
G37*
G36*
G01Y250107D02*
X1119313Y249757D01*
Y248887D01*
X1118643Y248537D01*
X1118468D01*
Y250107D01*
X1118643D01*
G37*
G36*
G01Y246207D02*
X1119313Y245857D01*
Y244987D01*
X1118643Y244637D01*
X1118468D01*
Y246207D01*
X1118643D01*
G37*
G36*
G01X1100119Y232986D02*
X1099449Y233336D01*
Y234206D01*
X1100119Y234556D01*
X1100294D01*
Y232986D01*
X1100119D01*
G37*
G36*
G01Y229062D02*
X1099449Y229412D01*
Y230282D01*
X1100119Y230632D01*
X1100294D01*
Y229062D01*
X1100119D01*
G37*
G36*
G01Y225137D02*
X1099449Y225487D01*
Y226357D01*
X1100119Y226707D01*
X1100294D01*
Y225137D01*
X1100119D01*
G37*
G36*
G01Y221237D02*
X1099449Y221587D01*
Y222457D01*
X1100119Y222807D01*
X1100294D01*
Y221237D01*
X1100119D01*
G37*
G36*
G01Y240737D02*
X1099449Y241087D01*
Y241957D01*
X1100119Y242307D01*
X1100294D01*
Y240737D01*
X1100119D01*
G37*
G36*
G01Y236837D02*
X1099449Y237187D01*
Y238057D01*
X1100119Y238407D01*
X1100294D01*
Y236837D01*
X1100119D01*
G37*
G36*
G01Y244637D02*
X1099449Y244987D01*
Y245857D01*
X1100119Y246207D01*
X1100294D01*
Y244637D01*
X1100119D01*
G37*
G36*
G01X1101743Y220906D02*
X1102413Y220556D01*
Y219686D01*
X1101743Y219336D01*
X1101568D01*
Y220906D01*
X1101743D01*
G37*
G36*
G01Y224806D02*
X1102413Y224456D01*
Y223586D01*
X1101743Y223236D01*
X1101568D01*
Y224806D01*
X1101743D01*
G37*
G36*
G01Y228706D02*
X1102413Y228356D01*
Y227486D01*
X1101743Y227136D01*
X1101568D01*
Y228706D01*
X1101743D01*
G37*
G36*
G01Y232557D02*
X1102413Y232207D01*
Y231337D01*
X1101743Y230987D01*
X1101568D01*
Y232557D01*
X1101743D01*
G37*
G36*
G01Y236481D02*
X1102413Y236131D01*
Y235261D01*
X1101743Y234911D01*
X1101568D01*
Y236481D01*
X1101743D01*
G37*
G36*
G01Y240406D02*
X1102413Y240056D01*
Y239186D01*
X1101743Y238836D01*
X1101568D01*
Y240406D01*
X1101743D01*
G37*
G36*
G01Y244306D02*
X1102413Y243956D01*
Y243086D01*
X1101743Y242736D01*
X1101568D01*
Y244306D01*
X1101743D01*
G37*
G36*
G01X1103906Y248084D02*
X1104020Y247337D01*
X1103318Y246823D01*
X1102640Y247157D01*
X1102536Y247298D01*
X1103803Y248225D01*
X1103906Y248084D01*
G37*
G36*
G01X1113639Y232987D02*
X1112969Y233337D01*
Y234207D01*
X1113639Y234557D01*
X1113814D01*
Y232987D01*
X1113639D01*
G37*
G36*
G01Y229087D02*
X1112969Y229437D01*
Y230307D01*
X1113639Y230657D01*
X1113814D01*
Y229087D01*
X1113639D01*
G37*
G36*
G01Y225162D02*
X1112969Y225512D01*
Y226382D01*
X1113639Y226732D01*
X1113814D01*
Y225162D01*
X1113639D01*
G37*
G36*
G01Y221260D02*
X1112969Y221610D01*
Y222480D01*
X1113639Y222830D01*
X1113814D01*
Y221260D01*
X1113639D01*
G37*
G36*
G01Y236887D02*
X1112969Y237237D01*
Y238107D01*
X1113639Y238457D01*
X1113814D01*
Y236887D01*
X1113639D01*
G37*
G36*
G01X1113640Y240787D02*
X1112970Y241137D01*
Y242007D01*
X1113640Y242357D01*
X1113815D01*
Y240787D01*
X1113640D01*
G37*
G36*
G01Y244687D02*
X1112970Y245037D01*
Y245907D01*
X1113640Y246257D01*
X1113815D01*
Y244687D01*
X1113640D01*
G37*
G36*
G01X1115263Y232558D02*
X1115933Y232208D01*
Y231338D01*
X1115263Y230988D01*
X1115088D01*
Y232558D01*
X1115263D01*
G37*
G36*
G01Y228658D02*
X1115933Y228308D01*
Y227438D01*
X1115263Y227088D01*
X1115088D01*
Y228658D01*
X1115263D01*
G37*
G36*
G01Y224781D02*
X1115933Y224431D01*
Y223561D01*
X1115263Y223211D01*
X1115088D01*
Y224781D01*
X1115263D01*
G37*
G36*
G01Y220879D02*
X1115933Y220529D01*
Y219659D01*
X1115263Y219309D01*
X1115088D01*
Y220879D01*
X1115263D01*
G37*
G36*
G01Y240358D02*
X1115933Y240008D01*
Y239138D01*
X1115263Y238788D01*
X1115088D01*
Y240358D01*
X1115263D01*
G37*
G36*
G01Y236458D02*
X1115933Y236108D01*
Y235238D01*
X1115263Y234888D01*
X1115088D01*
Y236458D01*
X1115263D01*
G37*
G36*
G01Y248182D02*
X1115933Y247832D01*
Y246962D01*
X1115263Y246612D01*
X1115088D01*
Y248182D01*
X1115263D01*
G37*
G36*
G01Y244282D02*
X1115933Y243932D01*
Y243062D01*
X1115263Y242712D01*
X1115088D01*
Y244282D01*
X1115263D01*
G37*
G36*
G01X1114432Y252077D02*
X1115116Y251756D01*
X1115153Y250887D01*
X1114498Y250509D01*
X1114323Y250501D01*
X1114257Y252070D01*
X1114432Y252077D01*
G37*
G36*
G01X1123778Y230987D02*
X1123108Y231337D01*
Y232207D01*
X1123778Y232557D01*
X1123953D01*
Y230987D01*
X1123778D01*
G37*
G36*
G01Y227136D02*
X1123108Y227486D01*
Y228356D01*
X1123778Y228706D01*
X1123953D01*
Y227136D01*
X1123778D01*
G37*
G36*
G01Y223236D02*
X1123108Y223586D01*
Y224456D01*
X1123778Y224806D01*
X1123953D01*
Y223236D01*
X1123778D01*
G37*
G36*
G01Y219336D02*
X1123108Y219686D01*
Y220556D01*
X1123778Y220906D01*
X1123953D01*
Y219336D01*
X1123778D01*
G37*
G36*
G01Y238836D02*
X1123108Y239186D01*
Y240056D01*
X1123778Y240406D01*
X1123953D01*
Y238836D01*
X1123778D01*
G37*
G36*
G01Y234911D02*
X1123108Y235261D01*
Y236131D01*
X1123778Y236481D01*
X1123953D01*
Y234911D01*
X1123778D01*
G37*
G36*
G01X1124476Y245440D02*
X1124133Y246114D01*
X1124637Y246823D01*
X1125386Y246720D01*
X1125528Y246619D01*
X1124619Y245339D01*
X1124476Y245440D01*
G37*
G36*
G01X1123778Y242712D02*
X1123108Y243062D01*
Y243932D01*
X1123778Y244282D01*
X1123953D01*
Y242712D01*
X1123778D01*
G37*
G36*
G01X1125402Y234556D02*
X1126072Y234206D01*
Y233336D01*
X1125402Y232986D01*
X1125227D01*
Y234556D01*
X1125402D01*
G37*
G36*
G01Y230632D02*
X1126072Y230282D01*
Y229412D01*
X1125402Y229062D01*
X1125227D01*
Y230632D01*
X1125402D01*
G37*
G36*
G01Y226707D02*
X1126072Y226357D01*
Y225487D01*
X1125402Y225137D01*
X1125227D01*
Y226707D01*
X1125402D01*
G37*
G36*
G01Y222807D02*
X1126072Y222457D01*
Y221587D01*
X1125402Y221237D01*
X1125227D01*
Y222807D01*
X1125402D01*
G37*
G36*
G01X1126376Y249755D02*
X1127075Y250043D01*
X1127741Y249484D01*
X1127579Y248745D01*
X1127466Y248611D01*
X1126264Y249621D01*
X1126376Y249755D01*
G37*
G36*
G01X1125401Y242332D02*
X1126071Y241982D01*
Y241112D01*
X1125401Y240762D01*
X1125226D01*
Y242332D01*
X1125401D01*
G37*
G36*
G01X1125402Y238407D02*
X1126072Y238057D01*
Y237187D01*
X1125402Y236837D01*
X1125227D01*
Y238407D01*
X1125402D01*
G37*
G36*
G01X1124924Y252552D02*
X1124455Y253144D01*
X1124809Y253939D01*
X1125563Y253986D01*
X1125723Y253915D01*
X1125084Y252481D01*
X1124924Y252552D01*
G37*
G36*
G01X1137298Y219336D02*
X1136628Y219686D01*
Y220556D01*
X1137298Y220906D01*
X1137473D01*
Y219336D01*
X1137298D01*
G37*
G36*
G01Y223236D02*
X1136628Y223586D01*
Y224456D01*
X1137298Y224806D01*
X1137473D01*
Y223236D01*
X1137298D01*
G37*
G36*
G01Y227136D02*
X1136628Y227486D01*
Y228356D01*
X1137298Y228706D01*
X1137473D01*
Y227136D01*
X1137298D01*
G37*
G36*
G01Y230987D02*
X1136628Y231337D01*
Y232207D01*
X1137298Y232557D01*
X1137473D01*
Y230987D01*
X1137298D01*
G37*
G36*
G01Y234911D02*
X1136628Y235261D01*
Y236131D01*
X1137298Y236481D01*
X1137473D01*
Y234911D01*
X1137298D01*
G37*
G36*
G01X1137317Y238836D02*
X1136647Y239186D01*
Y240056D01*
X1137317Y240406D01*
X1137492D01*
Y238836D01*
X1137317D01*
G37*
G36*
G01X1137313Y246610D02*
X1136643Y246960D01*
Y247830D01*
X1137313Y248180D01*
X1137488D01*
Y246610D01*
X1137313D01*
G37*
G36*
G01Y242710D02*
X1136643Y243060D01*
Y243930D01*
X1137313Y244280D01*
X1137488D01*
Y242710D01*
X1137313D01*
G37*
G36*
G01X1138922Y234556D02*
X1139592Y234206D01*
Y233336D01*
X1138922Y232986D01*
X1138747D01*
Y234556D01*
X1138922D01*
G37*
G36*
G01Y230632D02*
X1139592Y230282D01*
Y229412D01*
X1138922Y229062D01*
X1138747D01*
Y230632D01*
X1138922D01*
G37*
G36*
G01Y226707D02*
X1139592Y226357D01*
Y225487D01*
X1138922Y225137D01*
X1138747D01*
Y226707D01*
X1138922D01*
G37*
G36*
G01Y222807D02*
X1139592Y222457D01*
Y221587D01*
X1138922Y221237D01*
X1138747D01*
Y222807D01*
X1138922D01*
G37*
G36*
G01X1139008Y242283D02*
X1139678Y241933D01*
Y241063D01*
X1139008Y240713D01*
X1138833D01*
Y242283D01*
X1139008D01*
G37*
G36*
G01X1138922Y238407D02*
X1139592Y238057D01*
Y237187D01*
X1138922Y236837D01*
X1138747D01*
Y238407D01*
X1138922D01*
G37*
G36*
G01X1138962Y250143D02*
X1139632Y249793D01*
Y248923D01*
X1138962Y248573D01*
X1138787D01*
Y250143D01*
X1138962D01*
G37*
G36*
G01Y246243D02*
X1139632Y245893D01*
Y245023D01*
X1138962Y244673D01*
X1138787D01*
Y246243D01*
X1138962D01*
G37*
G36*
G01X1120398Y232986D02*
X1119728Y233336D01*
Y234206D01*
X1120398Y234556D01*
X1120573D01*
Y232986D01*
X1120398D01*
G37*
G36*
G01Y229037D02*
X1119728Y229387D01*
Y230257D01*
X1120398Y230607D01*
X1120573D01*
Y229037D01*
X1120398D01*
G37*
G36*
G01Y225126D02*
X1119728Y225476D01*
Y226346D01*
X1120398Y226696D01*
X1120573D01*
Y225126D01*
X1120398D01*
G37*
G36*
G01Y221226D02*
X1119728Y221576D01*
Y222446D01*
X1120398Y222796D01*
X1120573D01*
Y221226D01*
X1120398D01*
G37*
G36*
G01Y240762D02*
X1119728Y241112D01*
Y241982D01*
X1120398Y242332D01*
X1120573D01*
Y240762D01*
X1120398D01*
G37*
G36*
G01Y236826D02*
X1119728Y237176D01*
Y238046D01*
X1120398Y238396D01*
X1120573D01*
Y236826D01*
X1120398D01*
G37*
G36*
G01Y244662D02*
X1119728Y245012D01*
Y245882D01*
X1120398Y246232D01*
X1120573D01*
Y244662D01*
X1120398D01*
G37*
G36*
G01X1122023Y220917D02*
X1122693Y220567D01*
Y219697D01*
X1122023Y219347D01*
X1121848D01*
Y220917D01*
X1122023D01*
G37*
G36*
G01Y224817D02*
X1122693Y224467D01*
Y223597D01*
X1122023Y223247D01*
X1121848D01*
Y224817D01*
X1122023D01*
G37*
G36*
G01Y228717D02*
X1122693Y228367D01*
Y227497D01*
X1122023Y227147D01*
X1121848D01*
Y228717D01*
X1122023D01*
G37*
G36*
G01Y232557D02*
X1122693Y232207D01*
Y231337D01*
X1122023Y230987D01*
X1121848D01*
Y232557D01*
X1122023D01*
G37*
G36*
G01Y236506D02*
X1122693Y236156D01*
Y235286D01*
X1122023Y234936D01*
X1121848D01*
Y236506D01*
X1122023D01*
G37*
G36*
G01Y240417D02*
X1122693Y240067D01*
Y239197D01*
X1122023Y238847D01*
X1121848D01*
Y240417D01*
X1122023D01*
G37*
G36*
G01X1124257Y248093D02*
X1124342Y247342D01*
X1123621Y246855D01*
X1122956Y247214D01*
X1122858Y247359D01*
X1124159Y248238D01*
X1124257Y248093D01*
G37*
G36*
G01X1122023Y244282D02*
X1122693Y243932D01*
Y243062D01*
X1122023Y242712D01*
X1121848D01*
Y244282D01*
X1122023D01*
G37*
G36*
G01X1133918Y221237D02*
X1133248Y221587D01*
Y222457D01*
X1133918Y222807D01*
X1134093D01*
Y221237D01*
X1133918D01*
G37*
G36*
G01Y225137D02*
X1133248Y225487D01*
Y226357D01*
X1133918Y226707D01*
X1134093D01*
Y225137D01*
X1133918D01*
G37*
G36*
G01Y229062D02*
X1133248Y229412D01*
Y230282D01*
X1133918Y230632D01*
X1134093D01*
Y229062D01*
X1133918D01*
G37*
G36*
G01Y232986D02*
X1133248Y233336D01*
Y234206D01*
X1133918Y234556D01*
X1134093D01*
Y232986D01*
X1133918D01*
G37*
G36*
G01Y236837D02*
X1133248Y237187D01*
Y238057D01*
X1133918Y238407D01*
X1134093D01*
Y236837D01*
X1133918D01*
G37*
G36*
G01X1133919Y240762D02*
X1133249Y241112D01*
Y241982D01*
X1133919Y242332D01*
X1134094D01*
Y240762D01*
X1133919D01*
G37*
G36*
G01Y244662D02*
X1133249Y245012D01*
Y245882D01*
X1133919Y246232D01*
X1134094D01*
Y244662D01*
X1133919D01*
G37*
G36*
G01X1135542Y232557D02*
X1136212Y232207D01*
Y231337D01*
X1135542Y230987D01*
X1135367D01*
Y232557D01*
X1135542D01*
G37*
G36*
G01Y228706D02*
X1136212Y228356D01*
Y227486D01*
X1135542Y227136D01*
X1135367D01*
Y228706D01*
X1135542D01*
G37*
G36*
G01Y224806D02*
X1136212Y224456D01*
Y223586D01*
X1135542Y223236D01*
X1135367D01*
Y224806D01*
X1135542D01*
G37*
G36*
G01Y220906D02*
X1136212Y220556D01*
Y219686D01*
X1135542Y219336D01*
X1135367D01*
Y220906D01*
X1135542D01*
G37*
G36*
G01Y240406D02*
X1136212Y240056D01*
Y239186D01*
X1135542Y238836D01*
X1135367D01*
Y240406D01*
X1135542D01*
G37*
G36*
G01Y236481D02*
X1136212Y236131D01*
Y235261D01*
X1135542Y234911D01*
X1135367D01*
Y236481D01*
X1135542D01*
G37*
G36*
G01Y244282D02*
X1136212Y243932D01*
Y243062D01*
X1135542Y242712D01*
X1135367D01*
Y244282D01*
X1135542D01*
G37*
G36*
G01Y248182D02*
X1136212Y247832D01*
Y246962D01*
X1135542Y246612D01*
X1135367D01*
Y248182D01*
X1135542D01*
G37*
G36*
G01X1108503Y220906D02*
X1109173Y220556D01*
Y219686D01*
X1108503Y219336D01*
X1108328D01*
Y220906D01*
X1108503D01*
G37*
G36*
G01Y224806D02*
X1109173Y224456D01*
Y223586D01*
X1108503Y223236D01*
X1108328D01*
Y224806D01*
X1108503D01*
G37*
G36*
G01Y228706D02*
X1109173Y228356D01*
Y227486D01*
X1108503Y227136D01*
X1108328D01*
Y228706D01*
X1108503D01*
G37*
G36*
G01Y232557D02*
X1109173Y232207D01*
Y231337D01*
X1108503Y230987D01*
X1108328D01*
Y232557D01*
X1108503D01*
G37*
G36*
G01Y236481D02*
X1109173Y236131D01*
Y235261D01*
X1108503Y234911D01*
X1108328D01*
Y236481D01*
X1108503D01*
G37*
G36*
G01Y240406D02*
X1109173Y240056D01*
Y239186D01*
X1108503Y238836D01*
X1108328D01*
Y240406D01*
X1108503D01*
G37*
G36*
G01X1128782Y232557D02*
X1129452Y232207D01*
Y231337D01*
X1128782Y230987D01*
X1128607D01*
Y232557D01*
X1128782D01*
G37*
G36*
G01Y228706D02*
X1129452Y228356D01*
Y227486D01*
X1128782Y227136D01*
X1128607D01*
Y228706D01*
X1128782D01*
G37*
G36*
G01Y224806D02*
X1129452Y224456D01*
Y223586D01*
X1128782Y223236D01*
X1128607D01*
Y224806D01*
X1128782D01*
G37*
G36*
G01Y220906D02*
X1129452Y220556D01*
Y219686D01*
X1128782Y219336D01*
X1128607D01*
Y220906D01*
X1128782D01*
G37*
G36*
G01Y240406D02*
X1129452Y240056D01*
Y239186D01*
X1128782Y238836D01*
X1128607D01*
Y240406D01*
X1128782D01*
G37*
G36*
G01Y236481D02*
X1129452Y236131D01*
Y235261D01*
X1128782Y234911D01*
X1128607D01*
Y236481D01*
X1128782D01*
G37*
G36*
G01X1111883Y234556D02*
X1112553Y234206D01*
Y233336D01*
X1111883Y232986D01*
X1111708D01*
Y234556D01*
X1111883D01*
G37*
G36*
G01Y230632D02*
X1112553Y230282D01*
Y229412D01*
X1111883Y229062D01*
X1111708D01*
Y230632D01*
X1111883D01*
G37*
G36*
G01Y226707D02*
X1112553Y226357D01*
Y225487D01*
X1111883Y225137D01*
X1111708D01*
Y226707D01*
X1111883D01*
G37*
G36*
G01Y222807D02*
X1112553Y222457D01*
Y221587D01*
X1111883Y221237D01*
X1111708D01*
Y222807D01*
X1111883D01*
G37*
G36*
G01X1111881Y254076D02*
X1112551Y253726D01*
X1112552Y252856D01*
X1111881Y252507D01*
X1111707D01*
X1111706Y254076D01*
X1111881D01*
G37*
G36*
G01X1111883Y250107D02*
X1112553Y249757D01*
Y248887D01*
X1111883Y248537D01*
X1111708D01*
Y250107D01*
X1111883D01*
G37*
G36*
G01Y246207D02*
X1112553Y245857D01*
Y244987D01*
X1111883Y244637D01*
X1111708D01*
Y246207D01*
X1111883D01*
G37*
G36*
G01Y242307D02*
X1112553Y241957D01*
Y241087D01*
X1111883Y240737D01*
X1111708D01*
Y242307D01*
X1111883D01*
G37*
G36*
G01Y238407D02*
X1112553Y238057D01*
Y237187D01*
X1111883Y236837D01*
X1111708D01*
Y238407D01*
X1111883D01*
G37*
G36*
G01X1132162Y234556D02*
X1132832Y234206D01*
Y233336D01*
X1132162Y232986D01*
X1131987D01*
Y234556D01*
X1132162D01*
G37*
G36*
G01Y230632D02*
X1132832Y230282D01*
Y229412D01*
X1132162Y229062D01*
X1131987D01*
Y230632D01*
X1132162D01*
G37*
G36*
G01Y226707D02*
X1132832Y226357D01*
Y225487D01*
X1132162Y225137D01*
X1131987D01*
Y226707D01*
X1132162D01*
G37*
G36*
G01Y222807D02*
X1132832Y222457D01*
Y221587D01*
X1132162Y221237D01*
X1131987D01*
Y222807D01*
X1132162D01*
G37*
G36*
G01X1132160Y254056D02*
X1132830Y253706D01*
X1132831Y252836D01*
X1132160Y252487D01*
X1131986D01*
X1131985Y254056D01*
X1132160D01*
G37*
G36*
G01X1132162Y250107D02*
X1132832Y249757D01*
Y248887D01*
X1132162Y248537D01*
X1131987D01*
Y250107D01*
X1132162D01*
G37*
G36*
G01Y246207D02*
X1132832Y245857D01*
Y244987D01*
X1132162Y244637D01*
X1131987D01*
Y246207D01*
X1132162D01*
G37*
G36*
G01Y242307D02*
X1132832Y241957D01*
Y241087D01*
X1132162Y240737D01*
X1131987D01*
Y242307D01*
X1132162D01*
G37*
G36*
G01Y238407D02*
X1132832Y238057D01*
Y237187D01*
X1132162Y236837D01*
X1131987D01*
Y238407D01*
X1132162D01*
G37*
G36*
G01X1106879Y232937D02*
X1106209Y233287D01*
Y234157D01*
X1106879Y234507D01*
X1107054D01*
Y232937D01*
X1106879D01*
G37*
G36*
G01Y229062D02*
X1106209Y229412D01*
Y230282D01*
X1106879Y230632D01*
X1107054D01*
Y229062D01*
X1106879D01*
G37*
G36*
G01Y225137D02*
X1106209Y225487D01*
Y226357D01*
X1106879Y226707D01*
X1107054D01*
Y225137D01*
X1106879D01*
G37*
G36*
G01Y221237D02*
X1106209Y221587D01*
Y222457D01*
X1106879Y222807D01*
X1107054D01*
Y221237D01*
X1106879D01*
G37*
G36*
G01Y240762D02*
X1106209Y241112D01*
Y241982D01*
X1106879Y242332D01*
X1107054D01*
Y240762D01*
X1106879D01*
G37*
G36*
G01Y236837D02*
X1106209Y237187D01*
Y238057D01*
X1106879Y238407D01*
X1107054D01*
Y236837D01*
X1106879D01*
G37*
G36*
G01X1127158Y221237D02*
X1126488Y221587D01*
Y222457D01*
X1127158Y222807D01*
X1127333D01*
Y221237D01*
X1127158D01*
G37*
G36*
G01Y225137D02*
X1126488Y225487D01*
Y226357D01*
X1127158Y226707D01*
X1127333D01*
Y225137D01*
X1127158D01*
G37*
G36*
G01Y229062D02*
X1126488Y229412D01*
Y230282D01*
X1127158Y230632D01*
X1127333D01*
Y229062D01*
X1127158D01*
G37*
G36*
G01Y232986D02*
X1126488Y233336D01*
Y234206D01*
X1127158Y234556D01*
X1127333D01*
Y232986D01*
X1127158D01*
G37*
G36*
G01Y236837D02*
X1126488Y237187D01*
Y238057D01*
X1127158Y238407D01*
X1127333D01*
Y236837D01*
X1127158D01*
G37*
G36*
G01Y240762D02*
X1126488Y241112D01*
Y241982D01*
X1127158Y242332D01*
X1127333D01*
Y240762D01*
X1127158D01*
G37*
G36*
G01X1110259Y230987D02*
X1109589Y231337D01*
Y232207D01*
X1110259Y232557D01*
X1110434D01*
Y230987D01*
X1110259D01*
G37*
G36*
G01Y227136D02*
X1109589Y227486D01*
Y228356D01*
X1110259Y228706D01*
X1110434D01*
Y227136D01*
X1110259D01*
G37*
G36*
G01Y223236D02*
X1109589Y223586D01*
Y224456D01*
X1110259Y224806D01*
X1110434D01*
Y223236D01*
X1110259D01*
G37*
G36*
G01Y219336D02*
X1109589Y219686D01*
Y220556D01*
X1110259Y220906D01*
X1110434D01*
Y219336D01*
X1110259D01*
G37*
G36*
G01Y250536D02*
X1109589Y250886D01*
Y251756D01*
X1110259Y252106D01*
X1110434D01*
Y250536D01*
X1110259D01*
G37*
G36*
G01Y246636D02*
X1109589Y246986D01*
Y247856D01*
X1110259Y248206D01*
X1110434D01*
Y246636D01*
X1110259D01*
G37*
G36*
G01Y242736D02*
X1109589Y243086D01*
Y243956D01*
X1110259Y244306D01*
X1110434D01*
Y242736D01*
X1110259D01*
G37*
G36*
G01Y238836D02*
X1109589Y239186D01*
Y240056D01*
X1110259Y240406D01*
X1110434D01*
Y238836D01*
X1110259D01*
G37*
G36*
G01Y234911D02*
X1109589Y235261D01*
Y236131D01*
X1110259Y236481D01*
X1110434D01*
Y234911D01*
X1110259D01*
G37*
G36*
G01X1130538Y230987D02*
X1129868Y231337D01*
Y232207D01*
X1130538Y232557D01*
X1130713D01*
Y230987D01*
X1130538D01*
G37*
G36*
G01Y227136D02*
X1129868Y227486D01*
Y228356D01*
X1130538Y228706D01*
X1130713D01*
Y227136D01*
X1130538D01*
G37*
G36*
G01Y223236D02*
X1129868Y223586D01*
Y224456D01*
X1130538Y224806D01*
X1130713D01*
Y223236D01*
X1130538D01*
G37*
G36*
G01Y219336D02*
X1129868Y219686D01*
Y220556D01*
X1130538Y220906D01*
X1130713D01*
Y219336D01*
X1130538D01*
G37*
G36*
G01Y250536D02*
X1129868Y250886D01*
Y251756D01*
X1130538Y252106D01*
X1130713D01*
Y250536D01*
X1130538D01*
G37*
G36*
G01Y246636D02*
X1129868Y246986D01*
Y247856D01*
X1130538Y248206D01*
X1130713D01*
Y246636D01*
X1130538D01*
G37*
G36*
G01Y242736D02*
X1129868Y243086D01*
Y243956D01*
X1130538Y244306D01*
X1130713D01*
Y242736D01*
X1130538D01*
G37*
G36*
G01Y238836D02*
X1129868Y239186D01*
Y240056D01*
X1130538Y240406D01*
X1130713D01*
Y238836D01*
X1130538D01*
G37*
G36*
G01Y234911D02*
X1129868Y235261D01*
Y236131D01*
X1130538Y236481D01*
X1130713D01*
Y234911D01*
X1130538D01*
G37*
G36*
G01X1096103Y398354D02*
X1096773Y398004D01*
Y397134D01*
X1096103Y396784D01*
X1095928D01*
Y398354D01*
X1096103D01*
G37*
G36*
G01Y402205D02*
X1096773Y401855D01*
Y400985D01*
X1096103Y400635D01*
X1095928D01*
Y402205D01*
X1096103D01*
G37*
G36*
G01Y394454D02*
X1096773Y394104D01*
Y393234D01*
X1096103Y392884D01*
X1095928D01*
Y394454D01*
X1096103D01*
G37*
G36*
G01X1095014Y385648D02*
X1094982Y386403D01*
X1095735Y386838D01*
X1096373Y386433D01*
X1096461Y386281D01*
X1095101Y385497D01*
X1095014Y385648D01*
G37*
G36*
G01X1098400Y387602D02*
X1098368Y388357D01*
X1099121Y388792D01*
X1099759Y388387D01*
X1099847Y388235D01*
X1098487Y387451D01*
X1098400Y387602D01*
G37*
G36*
G01X1101774Y389548D02*
X1101742Y390303D01*
X1102495Y390738D01*
X1103133Y390333D01*
X1103221Y390181D01*
X1101861Y389397D01*
X1101774Y389548D01*
G37*
G36*
G01X1107999Y394846D02*
X1107329Y395196D01*
Y396066D01*
X1107999Y396416D01*
X1108174D01*
Y394846D01*
X1107999D01*
G37*
G36*
G01Y398746D02*
X1107329Y399096D01*
Y399966D01*
X1107999Y400316D01*
X1108174D01*
Y398746D01*
X1107999D01*
G37*
G36*
G01Y402646D02*
X1107329Y402996D01*
Y403866D01*
X1107999Y404216D01*
X1108174D01*
Y402646D01*
X1107999D01*
G37*
G36*
G01X1105160Y391502D02*
X1105128Y392257D01*
X1105881Y392692D01*
X1106519Y392287D01*
X1106607Y392135D01*
X1105247Y391351D01*
X1105160Y391502D01*
G37*
G36*
G01X1105702Y389941D02*
X1105734Y389186D01*
X1104981Y388751D01*
X1104343Y389156D01*
X1104255Y389307D01*
X1105615Y390093D01*
X1105702Y389941D01*
G37*
G36*
G01X1102328Y387995D02*
X1102360Y387240D01*
X1101607Y386805D01*
X1100969Y387210D01*
X1100881Y387361D01*
X1102241Y388147D01*
X1102328Y387995D01*
G37*
G36*
G01X1098942Y386041D02*
X1098974Y385286D01*
X1098221Y384851D01*
X1097583Y385256D01*
X1097495Y385407D01*
X1098855Y386193D01*
X1098942Y386041D01*
G37*
G36*
G01X1109623Y402196D02*
X1110293Y401846D01*
Y400976D01*
X1109623Y400626D01*
X1109448D01*
Y402196D01*
X1109623D01*
G37*
G36*
G01Y398296D02*
X1110293Y397946D01*
Y397076D01*
X1109623Y396726D01*
X1109448D01*
Y398296D01*
X1109623D01*
G37*
G36*
G01Y394396D02*
X1110293Y394046D01*
Y393176D01*
X1109623Y392826D01*
X1109448D01*
Y394396D01*
X1109623D01*
G37*
G36*
G01X1109067Y391881D02*
X1109099Y391126D01*
X1108345Y390692D01*
X1107708Y391097D01*
X1107619Y391248D01*
X1108980Y392033D01*
X1109067Y391881D01*
G37*
G36*
G01X1121519Y387036D02*
X1120849Y387386D01*
Y388256D01*
X1121519Y388606D01*
X1121694D01*
Y387036D01*
X1121519D01*
G37*
G36*
G01X1101828Y359543D02*
X1101159Y359894D01*
X1101160Y360763D01*
X1101831Y361113D01*
X1102006Y361112D01*
X1102003Y359543D01*
X1101828D01*
G37*
G36*
G01X1108534Y377848D02*
X1108502Y378603D01*
X1109255Y379038D01*
X1109893Y378633D01*
X1109981Y378481D01*
X1108621Y377697D01*
X1108534Y377848D01*
G37*
G36*
G01X1102377Y361788D02*
X1102155Y362510D01*
X1102774Y363122D01*
X1103494Y362891D01*
X1103617Y362767D01*
X1102500Y361663D01*
X1102377Y361788D01*
G37*
G36*
G01X1104619Y373362D02*
X1103949Y373712D01*
Y374582D01*
X1104619Y374932D01*
X1104794D01*
Y373362D01*
X1104619D01*
G37*
G36*
G01X1105189Y375921D02*
X1105158Y376676D01*
X1105911Y377110D01*
X1106549Y376705D01*
X1106637Y376554D01*
X1105276Y375769D01*
X1105189Y375921D01*
G37*
G36*
G01X1104619Y369462D02*
X1103949Y369812D01*
Y370682D01*
X1104619Y371032D01*
X1104794D01*
Y369462D01*
X1104619D01*
G37*
G36*
G01Y365537D02*
X1103949Y365887D01*
Y366757D01*
X1104619Y367107D01*
X1104794D01*
Y365537D01*
X1104619D01*
G37*
G36*
G01X1118680Y383702D02*
X1118648Y384457D01*
X1119401Y384892D01*
X1120039Y384487D01*
X1120127Y384335D01*
X1118767Y383551D01*
X1118680Y383702D01*
G37*
G36*
G01X1115294Y381748D02*
X1115262Y382503D01*
X1116015Y382938D01*
X1116653Y382533D01*
X1116741Y382381D01*
X1115381Y381597D01*
X1115294Y381748D01*
G37*
G36*
G01X1111920Y379802D02*
X1111888Y380557D01*
X1112641Y380992D01*
X1113279Y380587D01*
X1113367Y380435D01*
X1112007Y379651D01*
X1111920Y379802D01*
G37*
G36*
G01X1121519Y402636D02*
X1120849Y402986D01*
Y403856D01*
X1121519Y404206D01*
X1121694D01*
Y402636D01*
X1121519D01*
G37*
G36*
G01Y398736D02*
X1120849Y399086D01*
Y399956D01*
X1121519Y400306D01*
X1121694D01*
Y398736D01*
X1121519D01*
G37*
G36*
G01Y394836D02*
X1120849Y395186D01*
Y396056D01*
X1121519Y396406D01*
X1121694D01*
Y394836D01*
X1121519D01*
G37*
G36*
G01Y390936D02*
X1120849Y391286D01*
Y392156D01*
X1121519Y392506D01*
X1121694D01*
Y390936D01*
X1121519D01*
G37*
G36*
G01X1112462Y378241D02*
X1112494Y377486D01*
X1111741Y377051D01*
X1111103Y377456D01*
X1111015Y377607D01*
X1112375Y378393D01*
X1112462Y378241D01*
G37*
G36*
G01X1109073Y376286D02*
X1109105Y375531D01*
X1108352Y375096D01*
X1107714Y375501D01*
X1107626Y375653D01*
X1108986Y376437D01*
X1109073Y376286D01*
G37*
G36*
G01X1106243Y372957D02*
X1106913Y372607D01*
Y371737D01*
X1106243Y371387D01*
X1106068D01*
Y372957D01*
X1106243D01*
G37*
G36*
G01Y369106D02*
X1106913Y368756D01*
Y367886D01*
X1106243Y367536D01*
X1106068D01*
Y369106D01*
X1106243D01*
G37*
G36*
G01Y365206D02*
X1106913Y364856D01*
Y363986D01*
X1106243Y363636D01*
X1106068D01*
Y365206D01*
X1106243D01*
G37*
G36*
G01X1122587Y384081D02*
X1122619Y383326D01*
X1121865Y382892D01*
X1121228Y383297D01*
X1121139Y383448D01*
X1122500Y384233D01*
X1122587Y384081D01*
G37*
G36*
G01X1119222Y382141D02*
X1119254Y381386D01*
X1118501Y380951D01*
X1117863Y381356D01*
X1117775Y381507D01*
X1119135Y382293D01*
X1119222Y382141D01*
G37*
G36*
G01X1115848Y380195D02*
X1115880Y379440D01*
X1115127Y379005D01*
X1114489Y379410D01*
X1114401Y379561D01*
X1115761Y380347D01*
X1115848Y380195D01*
G37*
G36*
G01X1123143Y390507D02*
X1123813Y390157D01*
Y389287D01*
X1123143Y388937D01*
X1122968D01*
Y390507D01*
X1123143D01*
G37*
G36*
G01Y386607D02*
X1123813Y386257D01*
Y385387D01*
X1123143Y385037D01*
X1122968D01*
Y386607D01*
X1123143D01*
G37*
G36*
G01Y402207D02*
X1123813Y401857D01*
Y400987D01*
X1123143Y400637D01*
X1122968D01*
Y402207D01*
X1123143D01*
G37*
G36*
G01Y398307D02*
X1123813Y397957D01*
Y397087D01*
X1123143Y396737D01*
X1122968D01*
Y398307D01*
X1123143D01*
G37*
G36*
G01Y394407D02*
X1123813Y394057D01*
Y393187D01*
X1123143Y392837D01*
X1122968D01*
Y394407D01*
X1123143D01*
G37*
G36*
G01X1095014Y389548D02*
X1094982Y390303D01*
X1095735Y390738D01*
X1096373Y390333D01*
X1096461Y390181D01*
X1095101Y389397D01*
X1095014Y389548D01*
G37*
G36*
G01X1104619Y400637D02*
X1103949Y400987D01*
Y401857D01*
X1104619Y402207D01*
X1104794D01*
Y400637D01*
X1104619D01*
G37*
G36*
G01Y396737D02*
X1103949Y397087D01*
Y397957D01*
X1104619Y398307D01*
X1104794D01*
Y396737D01*
X1104619D01*
G37*
G36*
G01X1101774Y393448D02*
X1101742Y394203D01*
X1102495Y394638D01*
X1103133Y394233D01*
X1103221Y394081D01*
X1101861Y393297D01*
X1101774Y393448D01*
G37*
G36*
G01X1098400Y391502D02*
X1098368Y392257D01*
X1099121Y392692D01*
X1099759Y392287D01*
X1099847Y392135D01*
X1098487Y391351D01*
X1098400Y391502D01*
G37*
G36*
G01X1098942Y389941D02*
X1098974Y389186D01*
X1098221Y388751D01*
X1097583Y389156D01*
X1097495Y389307D01*
X1098855Y390093D01*
X1098942Y389941D01*
G37*
G36*
G01X1106243Y396406D02*
X1106913Y396056D01*
Y395186D01*
X1106243Y394836D01*
X1106068D01*
Y396406D01*
X1106243D01*
G37*
G36*
G01Y404206D02*
X1106913Y403856D01*
Y402986D01*
X1106243Y402636D01*
X1106068D01*
Y404206D01*
X1106243D01*
G37*
G36*
G01Y400306D02*
X1106913Y399956D01*
Y399086D01*
X1106243Y398736D01*
X1106068D01*
Y400306D01*
X1106243D01*
G37*
G36*
G01X1102328Y391895D02*
X1102360Y391140D01*
X1101607Y390705D01*
X1100969Y391110D01*
X1100881Y391261D01*
X1102241Y392047D01*
X1102328Y391895D01*
G37*
G36*
G01X1105701Y393839D02*
X1105733Y393084D01*
X1104980Y392650D01*
X1104342Y393055D01*
X1104254Y393206D01*
X1105615Y393991D01*
X1105701Y393839D01*
G37*
G36*
G01X1118139Y388937D02*
X1117469Y389287D01*
Y390157D01*
X1118139Y390507D01*
X1118314D01*
Y388937D01*
X1118139D01*
G37*
G36*
G01X1099483Y361306D02*
X1100153Y360956D01*
Y360086D01*
X1099483Y359736D01*
X1099308D01*
Y361306D01*
X1099483D01*
G37*
G36*
G01X1101239Y375287D02*
X1100569Y375637D01*
Y376507D01*
X1101239Y376857D01*
X1101414D01*
Y375287D01*
X1101239D01*
G37*
G36*
G01Y371387D02*
X1100569Y371737D01*
Y372607D01*
X1101239Y372957D01*
X1101414D01*
Y371387D01*
X1101239D01*
G37*
G36*
G01Y367536D02*
X1100569Y367886D01*
Y368756D01*
X1101239Y369106D01*
X1101414D01*
Y367536D01*
X1101239D01*
G37*
G36*
G01X1101774Y377848D02*
X1101742Y378603D01*
X1102495Y379038D01*
X1103133Y378633D01*
X1103221Y378482D01*
X1101860Y377697D01*
X1101774Y377848D01*
G37*
G36*
G01X1108534Y381748D02*
X1108502Y382503D01*
X1109255Y382938D01*
X1109893Y382533D01*
X1109981Y382381D01*
X1108621Y381597D01*
X1108534Y381748D01*
G37*
G36*
G01X1111920Y383702D02*
X1111888Y384457D01*
X1112641Y384892D01*
X1113279Y384487D01*
X1113367Y384335D01*
X1112007Y383551D01*
X1111920Y383702D01*
G37*
G36*
G01X1115294Y385648D02*
X1115262Y386403D01*
X1116015Y386838D01*
X1116653Y386433D01*
X1116741Y386281D01*
X1115381Y385497D01*
X1115294Y385648D01*
G37*
G36*
G01X1105160Y379802D02*
X1105128Y380557D01*
X1105881Y380992D01*
X1106519Y380587D01*
X1106607Y380435D01*
X1105247Y379651D01*
X1105160Y379802D01*
G37*
G36*
G01X1118139Y396737D02*
X1117469Y397087D01*
Y397957D01*
X1118139Y398307D01*
X1118314D01*
Y396737D01*
X1118139D01*
G37*
G36*
G01Y400637D02*
X1117469Y400987D01*
Y401857D01*
X1118139Y402207D01*
X1118314D01*
Y400637D01*
X1118139D01*
G37*
G36*
G01Y392837D02*
X1117469Y393187D01*
Y394057D01*
X1118139Y394407D01*
X1118314D01*
Y392837D01*
X1118139D01*
G37*
G36*
G01X1098610Y357742D02*
X1097940Y358092D01*
Y358962D01*
X1098610Y359312D01*
X1098785D01*
Y357742D01*
X1098610D01*
G37*
G36*
G01X1119763Y388606D02*
X1120433Y388256D01*
Y387386D01*
X1119763Y387036D01*
X1119588D01*
Y388606D01*
X1119763D01*
G37*
G36*
G01X1102863Y367107D02*
X1103533Y366757D01*
Y365887D01*
X1102863Y365537D01*
X1102688D01*
Y367107D01*
X1102863D01*
G37*
G36*
G01Y371032D02*
X1103533Y370682D01*
Y369812D01*
X1102863Y369462D01*
X1102688D01*
Y371032D01*
X1102863D01*
G37*
G36*
G01Y374956D02*
X1103533Y374606D01*
Y373736D01*
X1102863Y373386D01*
X1102688D01*
Y374956D01*
X1102863D01*
G37*
G36*
G01X1105702Y378241D02*
X1105734Y377486D01*
X1104981Y377051D01*
X1104343Y377456D01*
X1104255Y377607D01*
X1105615Y378393D01*
X1105702Y378241D01*
G37*
G36*
G01X1112462Y382141D02*
X1112494Y381386D01*
X1111741Y380951D01*
X1111103Y381356D01*
X1111015Y381507D01*
X1112375Y382293D01*
X1112462Y382141D01*
G37*
G36*
G01X1115848Y384095D02*
X1115880Y383340D01*
X1115127Y382905D01*
X1114489Y383310D01*
X1114401Y383461D01*
X1115761Y384247D01*
X1115848Y384095D01*
G37*
G36*
G01X1119221Y386039D02*
X1119253Y385284D01*
X1118500Y384850D01*
X1117862Y385255D01*
X1117774Y385406D01*
X1119135Y386191D01*
X1119221Y386039D01*
G37*
G36*
G01X1109088Y380195D02*
X1109120Y379440D01*
X1108367Y379005D01*
X1107729Y379410D01*
X1107641Y379561D01*
X1109001Y380347D01*
X1109088Y380195D01*
G37*
G36*
G01X1119763Y396406D02*
X1120433Y396056D01*
Y395186D01*
X1119763Y394836D01*
X1119588D01*
Y396406D01*
X1119763D01*
G37*
G36*
G01Y400306D02*
X1120433Y399956D01*
Y399086D01*
X1119763Y398736D01*
X1119588D01*
Y400306D01*
X1119763D01*
G37*
G36*
G01Y404206D02*
X1120433Y403856D01*
Y402986D01*
X1119763Y402636D01*
X1119588D01*
Y404206D01*
X1119763D01*
G37*
G36*
G01Y392506D02*
X1120433Y392156D01*
Y391286D01*
X1119763Y390936D01*
X1119588D01*
Y392506D01*
X1119763D01*
G37*
G36*
G01X1111379Y369437D02*
X1110709Y369787D01*
Y370657D01*
X1111379Y371007D01*
X1111554D01*
Y369437D01*
X1111379D01*
G37*
G36*
G01Y361637D02*
X1110709Y361987D01*
Y362857D01*
X1111379Y363207D01*
X1111554D01*
Y361637D01*
X1111379D01*
G37*
G36*
G01Y365537D02*
X1110709Y365887D01*
Y366757D01*
X1111379Y367107D01*
X1111554D01*
Y365537D01*
X1111379D01*
G37*
G36*
G01X1111914Y371999D02*
X1111882Y372754D01*
X1112635Y373189D01*
X1113273Y372784D01*
X1113361Y372633D01*
X1112000Y371848D01*
X1111914Y371999D01*
G37*
G36*
G01X1115300Y373952D02*
X1115268Y374707D01*
X1116021Y375142D01*
X1116659Y374737D01*
X1116747Y374585D01*
X1115387Y373801D01*
X1115300Y373952D01*
G37*
G36*
G01X1118689Y375907D02*
X1118657Y376662D01*
X1119410Y377097D01*
X1120048Y376692D01*
X1120136Y376541D01*
X1118776Y375755D01*
X1118689Y375907D01*
G37*
G36*
G01X1122054Y377848D02*
X1122022Y378603D01*
X1122775Y379038D01*
X1123413Y378633D01*
X1123501Y378481D01*
X1122141Y377697D01*
X1122054Y377848D01*
G37*
G36*
G01X1125439Y379802D02*
X1125407Y380557D01*
X1126160Y380992D01*
X1126798Y380587D01*
X1126886Y380435D01*
X1125526Y379651D01*
X1125439Y379802D01*
G37*
G36*
G01X1131658Y388937D02*
X1130988Y389287D01*
Y390157D01*
X1131658Y390507D01*
X1131833D01*
Y388937D01*
X1131658D01*
G37*
G36*
G01Y385063D02*
X1130988Y385413D01*
Y386283D01*
X1131658Y386633D01*
X1131833D01*
Y385063D01*
X1131658D01*
G37*
G36*
G01X1128813Y381748D02*
X1128781Y382503D01*
X1129534Y382938D01*
X1130172Y382533D01*
X1130260Y382381D01*
X1128900Y381597D01*
X1128813Y381748D01*
G37*
G36*
G01X1131658Y400637D02*
X1130988Y400987D01*
Y401857D01*
X1131658Y402207D01*
X1131833D01*
Y400637D01*
X1131658D01*
G37*
G36*
G01Y396737D02*
X1130988Y397087D01*
Y397957D01*
X1131658Y398307D01*
X1131833D01*
Y396737D01*
X1131658D01*
G37*
G36*
G01Y392837D02*
X1130988Y393187D01*
Y394057D01*
X1131658Y394407D01*
X1131833D01*
Y392837D01*
X1131658D01*
G37*
G36*
G01X1122593Y376286D02*
X1122625Y375531D01*
X1121872Y375096D01*
X1121234Y375501D01*
X1121146Y375653D01*
X1122506Y376437D01*
X1122593Y376286D01*
G37*
G36*
G01X1119228Y374344D02*
X1119260Y373589D01*
X1118507Y373154D01*
X1117869Y373559D01*
X1117781Y373711D01*
X1119141Y374495D01*
X1119228Y374344D01*
G37*
G36*
G01X1115842Y372391D02*
X1115874Y371636D01*
X1115121Y371201D01*
X1114483Y371606D01*
X1114395Y371757D01*
X1115755Y372543D01*
X1115842Y372391D01*
G37*
G36*
G01X1113003Y369106D02*
X1113673Y368756D01*
Y367886D01*
X1113003Y367536D01*
X1112828D01*
Y369106D01*
X1113003D01*
G37*
G36*
G01X1125982Y378241D02*
X1126014Y377486D01*
X1125261Y377051D01*
X1124623Y377456D01*
X1124535Y377607D01*
X1125895Y378393D01*
X1125982Y378241D01*
G37*
G36*
G01X1133281Y388582D02*
X1133951Y388232D01*
Y387362D01*
X1133281Y387012D01*
X1133106D01*
Y388582D01*
X1133281D01*
G37*
G36*
G01X1132740Y382139D02*
X1132772Y381384D01*
X1132019Y380950D01*
X1131381Y381355D01*
X1131294Y381506D01*
X1132654Y382291D01*
X1132740Y382139D01*
G37*
G36*
G01X1129367Y380195D02*
X1129399Y379440D01*
X1128646Y379005D01*
X1128008Y379410D01*
X1127920Y379561D01*
X1129280Y380347D01*
X1129367Y380195D01*
G37*
G36*
G01X1133281Y384682D02*
X1133951Y384332D01*
Y383462D01*
X1133281Y383112D01*
X1133106D01*
Y384682D01*
X1133281D01*
G37*
G36*
G01X1133282Y396406D02*
X1133952Y396056D01*
Y395186D01*
X1133282Y394836D01*
X1133107D01*
Y396406D01*
X1133282D01*
G37*
G36*
G01Y404206D02*
X1133952Y403856D01*
Y402986D01*
X1133282Y402636D01*
X1133107D01*
Y404206D01*
X1133282D01*
G37*
G36*
G01Y400306D02*
X1133952Y399956D01*
Y399086D01*
X1133282Y398736D01*
X1133107D01*
Y400306D01*
X1133282D01*
G37*
G36*
G01Y392506D02*
X1133952Y392156D01*
Y391286D01*
X1133282Y390936D01*
X1133107D01*
Y392506D01*
X1133282D01*
G37*
G36*
G01X1121519Y359675D02*
X1120849Y360025D01*
Y360894D01*
X1121519Y361244D01*
X1121695D01*
X1121694Y359675D01*
X1121519D01*
G37*
G36*
G01X1122059Y362252D02*
X1122027Y363007D01*
X1122780Y363442D01*
X1123418Y363037D01*
X1123506Y362885D01*
X1122146Y362101D01*
X1122059Y362252D01*
G37*
G36*
G01X1125439Y364202D02*
X1125407Y364957D01*
X1126160Y365392D01*
X1126798Y364987D01*
X1126886Y364835D01*
X1125526Y364051D01*
X1125439Y364202D01*
G37*
G36*
G01X1128813Y366148D02*
X1128781Y366903D01*
X1129534Y367338D01*
X1130172Y366933D01*
X1130260Y366781D01*
X1128900Y365997D01*
X1128813Y366148D01*
G37*
G36*
G01X1132199Y368102D02*
X1132167Y368857D01*
X1132920Y369292D01*
X1133558Y368887D01*
X1133646Y368735D01*
X1132286Y367951D01*
X1132199Y368102D01*
G37*
G36*
G01X1145179Y388982D02*
X1144509Y389332D01*
Y390202D01*
X1145179Y390552D01*
X1145354D01*
Y388982D01*
X1145179D01*
G37*
G36*
G01X1142339Y373952D02*
X1142307Y374707D01*
X1143060Y375142D01*
X1143698Y374737D01*
X1143786Y374585D01*
X1142426Y373801D01*
X1142339Y373952D01*
G37*
G36*
G01X1145178Y377237D02*
X1144508Y377587D01*
Y378457D01*
X1145178Y378807D01*
X1145353D01*
Y377237D01*
X1145178D01*
G37*
G36*
G01X1135588Y370057D02*
X1135556Y370812D01*
X1136309Y371247D01*
X1136947Y370842D01*
X1137035Y370691D01*
X1135675Y369905D01*
X1135588Y370057D01*
G37*
G36*
G01X1138953Y371999D02*
X1138921Y372754D01*
X1139674Y373189D01*
X1140312Y372784D01*
X1140400Y372633D01*
X1139040Y371847D01*
X1138953Y371999D01*
G37*
G36*
G01X1145178Y381164D02*
X1144508Y381514D01*
Y382384D01*
X1145178Y382734D01*
X1145353D01*
Y381164D01*
X1145178D01*
G37*
G36*
G01Y385064D02*
X1144508Y385414D01*
Y386284D01*
X1145178Y386634D01*
X1145353D01*
Y385064D01*
X1145178D01*
G37*
G36*
G01X1149114Y401262D02*
X1149082Y402017D01*
X1149836Y402451D01*
X1150473Y402046D01*
X1150561Y401895D01*
X1149202Y401109D01*
X1149114Y401262D01*
G37*
G36*
G01X1145178Y396762D02*
X1144508Y397112D01*
Y397982D01*
X1145178Y398332D01*
X1145353D01*
Y396762D01*
X1145178D01*
G37*
G36*
G01X1145734Y399312D02*
X1145702Y400067D01*
X1146456Y400501D01*
X1147093Y400096D01*
X1147181Y399945D01*
X1145822Y399159D01*
X1145734Y399312D01*
G37*
G36*
G01X1145178Y392862D02*
X1144508Y393212D01*
Y394082D01*
X1145178Y394432D01*
X1145353D01*
Y392862D01*
X1145178D01*
G37*
G36*
G01X1125821Y362491D02*
X1126150Y361810D01*
X1125631Y361112D01*
X1124884Y361231D01*
X1124744Y361335D01*
X1125681Y362596D01*
X1125821Y362491D01*
G37*
G36*
G01X1129367Y364595D02*
X1129399Y363840D01*
X1128646Y363405D01*
X1128008Y363810D01*
X1127920Y363961D01*
X1129280Y364747D01*
X1129367Y364595D01*
G37*
G36*
G01X1132741Y366541D02*
X1132773Y365786D01*
X1132020Y365351D01*
X1131382Y365756D01*
X1131294Y365907D01*
X1132654Y366693D01*
X1132741Y366541D01*
G37*
G36*
G01X1146802Y388584D02*
X1147472Y388234D01*
Y387364D01*
X1146802Y387014D01*
X1146627D01*
Y388584D01*
X1146802D01*
G37*
G36*
G01X1136127Y368495D02*
X1136159Y367740D01*
X1135406Y367305D01*
X1134768Y367710D01*
X1134680Y367861D01*
X1136040Y368647D01*
X1136127Y368495D01*
G37*
G36*
G01X1146802Y376907D02*
X1147472Y376557D01*
Y375687D01*
X1146802Y375337D01*
X1146627D01*
Y376907D01*
X1146802D01*
G37*
G36*
G01X1146267Y374344D02*
X1146299Y373589D01*
X1145546Y373154D01*
X1144908Y373559D01*
X1144821Y373710D01*
X1146181Y374495D01*
X1146267Y374344D01*
G37*
G36*
G01X1142881Y372391D02*
X1142913Y371636D01*
X1142160Y371201D01*
X1141522Y371606D01*
X1141434Y371757D01*
X1142794Y372543D01*
X1142881Y372391D01*
G37*
G36*
G01X1139492Y370436D02*
X1139524Y369681D01*
X1138771Y369246D01*
X1138133Y369651D01*
X1138045Y369803D01*
X1139405Y370587D01*
X1139492Y370436D01*
G37*
G36*
G01X1146802Y384684D02*
X1147472Y384334D01*
Y383464D01*
X1146802Y383114D01*
X1146627D01*
Y384684D01*
X1146802D01*
G37*
G36*
G01Y380807D02*
X1147472Y380457D01*
Y379587D01*
X1146802Y379237D01*
X1146627D01*
Y380807D01*
X1146802D01*
G37*
G36*
G01X1152896Y403898D02*
X1153656Y403549D01*
Y402649D01*
X1152896Y402299D01*
X1152721D01*
Y403898D01*
X1152896D01*
G37*
G36*
G01X1149641Y399691D02*
X1149673Y398936D01*
X1148920Y398501D01*
X1148282Y398906D01*
X1148194Y399057D01*
X1149554Y399843D01*
X1149641Y399691D01*
G37*
G36*
G01X1146802Y396357D02*
X1147472Y396007D01*
Y395137D01*
X1146802Y394787D01*
X1146627D01*
Y396357D01*
X1146802D01*
G37*
G36*
G01Y392506D02*
X1147472Y392156D01*
Y391286D01*
X1146802Y390936D01*
X1146627D01*
Y392506D01*
X1146802D01*
G37*
G36*
G01X1108541Y373954D02*
X1108509Y374709D01*
X1109262Y375143D01*
X1109900Y374738D01*
X1109988Y374587D01*
X1108627Y373802D01*
X1108541Y373954D01*
G37*
G36*
G01X1111929Y375907D02*
X1111897Y376662D01*
X1112650Y377097D01*
X1113288Y376692D01*
X1113376Y376541D01*
X1112016Y375755D01*
X1111929Y375907D01*
G37*
G36*
G01X1115294Y377848D02*
X1115262Y378603D01*
X1116015Y379038D01*
X1116653Y378633D01*
X1116741Y378481D01*
X1115381Y377697D01*
X1115294Y377848D01*
G37*
G36*
G01X1107999Y359736D02*
X1107329Y360086D01*
Y360956D01*
X1107999Y361306D01*
X1108174D01*
Y359736D01*
X1107999D01*
G37*
G36*
G01Y371436D02*
X1107329Y371786D01*
Y372656D01*
X1107999Y373006D01*
X1108174D01*
Y371436D01*
X1107999D01*
G37*
G36*
G01Y363636D02*
X1107329Y363986D01*
Y364856D01*
X1107999Y365206D01*
X1108174D01*
Y363636D01*
X1107999D01*
G37*
G36*
G01Y367536D02*
X1107329Y367886D01*
Y368756D01*
X1107999Y369106D01*
X1108174D01*
Y367536D01*
X1107999D01*
G37*
G36*
G01X1118680Y379802D02*
X1118648Y380557D01*
X1119401Y380992D01*
X1120039Y380587D01*
X1120127Y380435D01*
X1118767Y379651D01*
X1118680Y379802D01*
G37*
G36*
G01X1122054Y381748D02*
X1122022Y382503D01*
X1122775Y382938D01*
X1123413Y382533D01*
X1123501Y382381D01*
X1122141Y381597D01*
X1122054Y381748D01*
G37*
G36*
G01X1125439Y383702D02*
X1125407Y384457D01*
X1126160Y384892D01*
X1126798Y384487D01*
X1126886Y384335D01*
X1125526Y383551D01*
X1125439Y383702D01*
G37*
G36*
G01X1128278Y387014D02*
X1127608Y387364D01*
Y388234D01*
X1128278Y388584D01*
X1128453D01*
Y387014D01*
X1128278D01*
G37*
G36*
G01Y402636D02*
X1127608Y402986D01*
Y403856D01*
X1128278Y404206D01*
X1128453D01*
Y402636D01*
X1128278D01*
G37*
G36*
G01Y394836D02*
X1127608Y395186D01*
Y396056D01*
X1128278Y396406D01*
X1128453D01*
Y394836D01*
X1128278D01*
G37*
G36*
G01Y398736D02*
X1127608Y399086D01*
Y399956D01*
X1128278Y400306D01*
X1128453D01*
Y398736D01*
X1128278D01*
G37*
G36*
G01Y390936D02*
X1127608Y391286D01*
Y392156D01*
X1128278Y392506D01*
X1128453D01*
Y390936D01*
X1128278D01*
G37*
G36*
G01X1119222Y378241D02*
X1119254Y377486D01*
X1118501Y377051D01*
X1117863Y377456D01*
X1117775Y377607D01*
X1119135Y378393D01*
X1119222Y378241D01*
G37*
G36*
G01X1115833Y376286D02*
X1115865Y375531D01*
X1115112Y375096D01*
X1114474Y375501D01*
X1114386Y375653D01*
X1115746Y376437D01*
X1115833Y376286D01*
G37*
G36*
G01X1112468Y374344D02*
X1112500Y373589D01*
X1111747Y373154D01*
X1111109Y373559D01*
X1111021Y373711D01*
X1112381Y374495D01*
X1112468Y374344D01*
G37*
G36*
G01X1109623Y371032D02*
X1110293Y370682D01*
Y369812D01*
X1109623Y369462D01*
X1109448D01*
Y371032D01*
X1109623D01*
G37*
G36*
G01Y367107D02*
X1110293Y366757D01*
Y365887D01*
X1109623Y365537D01*
X1109448D01*
Y367107D01*
X1109623D01*
G37*
G36*
G01X1122608Y380195D02*
X1122640Y379440D01*
X1121887Y379005D01*
X1121249Y379410D01*
X1121161Y379561D01*
X1122521Y380347D01*
X1122608Y380195D01*
G37*
G36*
G01X1125982Y382141D02*
X1126014Y381386D01*
X1125261Y380951D01*
X1124623Y381356D01*
X1124535Y381507D01*
X1125895Y382293D01*
X1125982Y382141D01*
G37*
G36*
G01X1129901Y390536D02*
X1130571Y390186D01*
Y389316D01*
X1129901Y388966D01*
X1129726D01*
Y390536D01*
X1129901D01*
G37*
G36*
G01X1129902Y386634D02*
X1130572Y386284D01*
Y385414D01*
X1129902Y385064D01*
X1129727D01*
Y386634D01*
X1129902D01*
G37*
G36*
G01X1129367Y384096D02*
X1129399Y383341D01*
X1128646Y382906D01*
X1128008Y383311D01*
X1127920Y383462D01*
X1129280Y384247D01*
X1129367Y384096D01*
G37*
G36*
G01X1129902Y402207D02*
X1130572Y401857D01*
Y400987D01*
X1129902Y400637D01*
X1129727D01*
Y402207D01*
X1129902D01*
G37*
G36*
G01Y398307D02*
X1130572Y397957D01*
Y397087D01*
X1129902Y396737D01*
X1129727D01*
Y398307D01*
X1129902D01*
G37*
G36*
G01Y394407D02*
X1130572Y394057D01*
Y393187D01*
X1129902Y392837D01*
X1129727D01*
Y394407D01*
X1129902D01*
G37*
G36*
G01X1119763Y361306D02*
X1120433Y360956D01*
Y360086D01*
X1119763Y359736D01*
X1119588D01*
Y361306D01*
X1119763D01*
G37*
G36*
G01X1122054Y366148D02*
X1122022Y366903D01*
X1122775Y367338D01*
X1123413Y366933D01*
X1123501Y366781D01*
X1122141Y365997D01*
X1122054Y366148D01*
G37*
G36*
G01X1118890Y357742D02*
X1118220Y358092D01*
Y358962D01*
X1118890Y359312D01*
X1119065D01*
Y357742D01*
X1118890D01*
G37*
G36*
G01X1125439Y368102D02*
X1125407Y368857D01*
X1126160Y369292D01*
X1126798Y368887D01*
X1126886Y368735D01*
X1125526Y367951D01*
X1125439Y368102D01*
G37*
G36*
G01X1128828Y370057D02*
X1128796Y370812D01*
X1129549Y371247D01*
X1130187Y370842D01*
X1130275Y370691D01*
X1128915Y369905D01*
X1128828Y370057D01*
G37*
G36*
G01X1132193Y371999D02*
X1132161Y372754D01*
X1132914Y373189D01*
X1133552Y372784D01*
X1133640Y372633D01*
X1132280Y371847D01*
X1132193Y371999D01*
G37*
G36*
G01X1141798Y387036D02*
X1141128Y387386D01*
Y388256D01*
X1141798Y388606D01*
X1141973D01*
Y387036D01*
X1141798D01*
G37*
G36*
G01X1135579Y373952D02*
X1135547Y374707D01*
X1136300Y375142D01*
X1136938Y374737D01*
X1137026Y374585D01*
X1135666Y373801D01*
X1135579Y373952D01*
G37*
G36*
G01X1138959Y375903D02*
X1138927Y376658D01*
X1139680Y377093D01*
X1140318Y376688D01*
X1140406Y376537D01*
X1139046Y375751D01*
X1138959Y375903D01*
G37*
G36*
G01X1141798Y379188D02*
X1141128Y379538D01*
Y380408D01*
X1141798Y380758D01*
X1141973D01*
Y379188D01*
X1141798D01*
G37*
G36*
G01Y383114D02*
X1141128Y383464D01*
Y384334D01*
X1141798Y384684D01*
X1141973D01*
Y383114D01*
X1141798D01*
G37*
G36*
G01X1142333Y401248D02*
X1142301Y402003D01*
X1143054Y402438D01*
X1143692Y402033D01*
X1143779Y401882D01*
X1142420Y401096D01*
X1142333Y401248D01*
G37*
G36*
G01X1141798Y398687D02*
X1141128Y399037D01*
Y399907D01*
X1141798Y400257D01*
X1141973D01*
Y398687D01*
X1141798D01*
G37*
G36*
G01Y394787D02*
X1141128Y395137D01*
Y396007D01*
X1141798Y396357D01*
X1141973D01*
Y394787D01*
X1141798D01*
G37*
G36*
G01Y390936D02*
X1141128Y391286D01*
Y392156D01*
X1141798Y392506D01*
X1141973D01*
Y390936D01*
X1141798D01*
G37*
G36*
G01X1125982Y366541D02*
X1126014Y365786D01*
X1125261Y365351D01*
X1124623Y365756D01*
X1124535Y365907D01*
X1125895Y366693D01*
X1125982Y366541D01*
G37*
G36*
G01X1132732Y370436D02*
X1132764Y369681D01*
X1132011Y369246D01*
X1131373Y369651D01*
X1131285Y369803D01*
X1132645Y370587D01*
X1132732Y370436D01*
G37*
G36*
G01X1129367Y368495D02*
X1129399Y367740D01*
X1128646Y367305D01*
X1128008Y367710D01*
X1127920Y367861D01*
X1129280Y368647D01*
X1129367Y368495D01*
G37*
G36*
G01X1143422Y390507D02*
X1144092Y390157D01*
Y389287D01*
X1143422Y388937D01*
X1143247D01*
Y390507D01*
X1143422D01*
G37*
G36*
G01X1136121Y372391D02*
X1136153Y371636D01*
X1135400Y371201D01*
X1134762Y371606D01*
X1134674Y371757D01*
X1136034Y372543D01*
X1136121Y372391D01*
G37*
G36*
G01X1143422Y378858D02*
X1144092Y378508D01*
Y377638D01*
X1143422Y377288D01*
X1143247D01*
Y378858D01*
X1143422D01*
G37*
G36*
G01X1142887Y376295D02*
X1142919Y375540D01*
X1142166Y375105D01*
X1141528Y375510D01*
X1141441Y375661D01*
X1142800Y376447D01*
X1142887Y376295D01*
G37*
G36*
G01X1139507Y374344D02*
X1139539Y373589D01*
X1138786Y373154D01*
X1138148Y373559D01*
X1138060Y373711D01*
X1139420Y374495D01*
X1139507Y374344D01*
G37*
G36*
G01X1143421Y386632D02*
X1144091Y386282D01*
Y385412D01*
X1143421Y385062D01*
X1143246D01*
Y386632D01*
X1143421D01*
G37*
G36*
G01X1143422Y382758D02*
X1144092Y382408D01*
Y381538D01*
X1143422Y381188D01*
X1143247D01*
Y382758D01*
X1143422D01*
G37*
G36*
G01X1149187Y404011D02*
X1149414Y403291D01*
X1148800Y402675D01*
X1148079Y402900D01*
X1147954Y403024D01*
X1149063Y404135D01*
X1149187Y404011D01*
G37*
G36*
G01X1146267Y401644D02*
X1146299Y400889D01*
X1145546Y400454D01*
X1144908Y400859D01*
X1144820Y401011D01*
X1146180Y401795D01*
X1146267Y401644D01*
G37*
G36*
G01X1143422Y398356D02*
X1144092Y398006D01*
Y397136D01*
X1143422Y396786D01*
X1143247D01*
Y398356D01*
X1143422D01*
G37*
G36*
G01Y394432D02*
X1144092Y394082D01*
Y393212D01*
X1143422Y392862D01*
X1143247D01*
Y394432D01*
X1143422D01*
G37*
G36*
G01X1112461Y389940D02*
X1112492Y389185D01*
X1111739Y388750D01*
X1111101Y389156D01*
X1111014Y389306D01*
X1112374Y390092D01*
X1112461Y389940D01*
G37*
G36*
G01X1096103Y378807D02*
X1096773Y378457D01*
Y377587D01*
X1096103Y377237D01*
X1095928D01*
Y378807D01*
X1096103D01*
G37*
G36*
G01Y374956D02*
X1096773Y374606D01*
Y373736D01*
X1096103Y373386D01*
X1095928D01*
Y374956D01*
X1096103D01*
G37*
G36*
G01Y371032D02*
X1096773Y370682D01*
Y369812D01*
X1096103Y369462D01*
X1095928D01*
Y371032D01*
X1096103D01*
G37*
G36*
G01Y367107D02*
X1096773Y366757D01*
Y365887D01*
X1096103Y365537D01*
X1095928D01*
Y367107D01*
X1096103D01*
G37*
G36*
G01Y363207D02*
X1096773Y362857D01*
Y361987D01*
X1096103Y361637D01*
X1095928D01*
Y363207D01*
X1096103D01*
G37*
G36*
G01X1102328Y384095D02*
X1102360Y383340D01*
X1101607Y382905D01*
X1100969Y383310D01*
X1100881Y383461D01*
X1102241Y384247D01*
X1102328Y384095D01*
G37*
G36*
G01X1098942Y382141D02*
X1098974Y381386D01*
X1098221Y380951D01*
X1097583Y381356D01*
X1097495Y381507D01*
X1098855Y382293D01*
X1098942Y382141D01*
G37*
G36*
G01X1109088Y387995D02*
X1109120Y387240D01*
X1108367Y386805D01*
X1107729Y387210D01*
X1107641Y387361D01*
X1109001Y388147D01*
X1109088Y387995D01*
G37*
G36*
G01X1105702Y386041D02*
X1105734Y385286D01*
X1104981Y384851D01*
X1104343Y385256D01*
X1104255Y385407D01*
X1105615Y386193D01*
X1105702Y386041D01*
G37*
G36*
G01X1113003Y404205D02*
X1113673Y403855D01*
Y402985D01*
X1113003Y402635D01*
X1112828D01*
Y404205D01*
X1113003D01*
G37*
G36*
G01Y400280D02*
X1113673Y399930D01*
Y399060D01*
X1113003Y398710D01*
X1112828D01*
Y400280D01*
X1113003D01*
G37*
G36*
G01Y396355D02*
X1113673Y396005D01*
Y395135D01*
X1113003Y394785D01*
X1112828D01*
Y396355D01*
X1113003D01*
G37*
G36*
G01Y392455D02*
X1113673Y392105D01*
Y391235D01*
X1113003Y390885D01*
X1112828D01*
Y392455D01*
X1113003D01*
G37*
G36*
G01X1096103Y359307D02*
X1096773Y358957D01*
Y358087D01*
X1096103Y357737D01*
X1095928D01*
Y359307D01*
X1096103D01*
G37*
G36*
G01X1122602Y372391D02*
X1122634Y371636D01*
X1121881Y371201D01*
X1121243Y371606D01*
X1121155Y371757D01*
X1122515Y372543D01*
X1122602Y372391D01*
G37*
G36*
G01X1116383Y363207D02*
X1117053Y362857D01*
Y361987D01*
X1116383Y361637D01*
X1116208D01*
Y363207D01*
X1116383D01*
G37*
G36*
G01Y367107D02*
X1117053Y366757D01*
Y365887D01*
X1116383Y365537D01*
X1116208D01*
Y367107D01*
X1116383D01*
G37*
G36*
G01X1119213Y370436D02*
X1119245Y369681D01*
X1118492Y369246D01*
X1117854Y369651D01*
X1117766Y369803D01*
X1119126Y370587D01*
X1119213Y370436D01*
G37*
G36*
G01X1116383Y359307D02*
X1117053Y358957D01*
Y358087D01*
X1116383Y357737D01*
X1116208D01*
Y359307D01*
X1116383D01*
G37*
G36*
G01X1125988Y374344D02*
X1126020Y373589D01*
X1125267Y373154D01*
X1124629Y373559D01*
X1124541Y373711D01*
X1125901Y374495D01*
X1125988Y374344D01*
G37*
G36*
G01X1129352Y376286D02*
X1129384Y375531D01*
X1128631Y375096D01*
X1127993Y375501D01*
X1127905Y375653D01*
X1129265Y376437D01*
X1129352Y376286D01*
G37*
G36*
G01X1136662Y390507D02*
X1137332Y390157D01*
Y389287D01*
X1136662Y388937D01*
X1136487D01*
Y390507D01*
X1136662D01*
G37*
G36*
G01X1132741Y378241D02*
X1132773Y377486D01*
X1132020Y377051D01*
X1131382Y377456D01*
X1131294Y377607D01*
X1132654Y378393D01*
X1132741Y378241D01*
G37*
G36*
G01X1136106Y380181D02*
X1136138Y379426D01*
X1135384Y378992D01*
X1134747Y379397D01*
X1134658Y379548D01*
X1136018Y380334D01*
X1136106Y380181D01*
G37*
G36*
G01X1136662Y386607D02*
X1137332Y386257D01*
Y385387D01*
X1136662Y385037D01*
X1136487D01*
Y386607D01*
X1136662D01*
G37*
G36*
G01Y382749D02*
X1137332Y382399D01*
X1137331Y381530D01*
X1136662Y381180D01*
X1136486Y381179D01*
Y382750D01*
X1136662Y382749D01*
G37*
G36*
G01Y402207D02*
X1137332Y401857D01*
Y400987D01*
X1136662Y400637D01*
X1136487D01*
Y402207D01*
X1136662D01*
G37*
G36*
G01Y398307D02*
X1137332Y397957D01*
Y397087D01*
X1136662Y396737D01*
X1136487D01*
Y398307D01*
X1136662D01*
G37*
G36*
G01Y394432D02*
X1137332Y394082D01*
Y393212D01*
X1136662Y392862D01*
X1136487D01*
Y394432D01*
X1136662D01*
G37*
G36*
G01X1111920Y387602D02*
X1111888Y388357D01*
X1112641Y388792D01*
X1113279Y388387D01*
X1113367Y388235D01*
X1112007Y387451D01*
X1111920Y387602D01*
G37*
G36*
G01X1097859Y377286D02*
X1097189Y377636D01*
Y378506D01*
X1097859Y378856D01*
X1098034D01*
Y377286D01*
X1097859D01*
G37*
G36*
G01X1097860Y369462D02*
X1097190Y369812D01*
Y370682D01*
X1097860Y371032D01*
X1098035D01*
Y369462D01*
X1097860D01*
G37*
G36*
G01X1097859Y373386D02*
X1097189Y373736D01*
Y374606D01*
X1097859Y374956D01*
X1098034D01*
Y373386D01*
X1097859D01*
G37*
G36*
G01X1098401Y379804D02*
X1098369Y380559D01*
X1099122Y380993D01*
X1099760Y380588D01*
X1099848Y380437D01*
X1098487Y379652D01*
X1098401Y379804D01*
G37*
G36*
G01X1108534Y385648D02*
X1108502Y386403D01*
X1109255Y386838D01*
X1109893Y386433D01*
X1109981Y386281D01*
X1108621Y385497D01*
X1108534Y385648D01*
G37*
G36*
G01X1101774Y381748D02*
X1101742Y382503D01*
X1102495Y382938D01*
X1103133Y382533D01*
X1103221Y382381D01*
X1101861Y381597D01*
X1101774Y381748D01*
G37*
G36*
G01X1105160Y383702D02*
X1105128Y384457D01*
X1105881Y384892D01*
X1106519Y384487D01*
X1106607Y384335D01*
X1105247Y383551D01*
X1105160Y383702D01*
G37*
G36*
G01X1114760Y394786D02*
X1114090Y395136D01*
Y396006D01*
X1114760Y396356D01*
X1114935D01*
Y394786D01*
X1114760D01*
G37*
G36*
G01X1114759Y398675D02*
X1114089Y399025D01*
Y399895D01*
X1114759Y400245D01*
X1114934D01*
Y398675D01*
X1114759D01*
G37*
G36*
G01Y402611D02*
X1114089Y402961D01*
Y403831D01*
X1114759Y404181D01*
X1114934D01*
Y402611D01*
X1114759D01*
G37*
G36*
G01X1114760Y390911D02*
X1114090Y391261D01*
Y392131D01*
X1114760Y392481D01*
X1114935D01*
Y390911D01*
X1114760D01*
G37*
G36*
G01X1118689Y368107D02*
X1118657Y368862D01*
X1119410Y369297D01*
X1120048Y368892D01*
X1120136Y368741D01*
X1118776Y367955D01*
X1118689Y368107D01*
G37*
G36*
G01X1122069Y370057D02*
X1122037Y370812D01*
X1122790Y371247D01*
X1123428Y370842D01*
X1123516Y370691D01*
X1122156Y369905D01*
X1122069Y370057D01*
G37*
G36*
G01X1125433Y371999D02*
X1125401Y372754D01*
X1126154Y373189D01*
X1126792Y372784D01*
X1126880Y372633D01*
X1125520Y371847D01*
X1125433Y371999D01*
G37*
G36*
G01X1128819Y373952D02*
X1128787Y374707D01*
X1129540Y375142D01*
X1130178Y374737D01*
X1130266Y374585D01*
X1128906Y373801D01*
X1128819Y373952D01*
G37*
G36*
G01X1132208Y375907D02*
X1132176Y376662D01*
X1132929Y377097D01*
X1133567Y376692D01*
X1133655Y376541D01*
X1132295Y375755D01*
X1132208Y375907D01*
G37*
G36*
G01X1138418Y388937D02*
X1137748Y389287D01*
Y390157D01*
X1138418Y390507D01*
X1138593D01*
Y388937D01*
X1138418D01*
G37*
G36*
G01X1135573Y377848D02*
X1135541Y378603D01*
X1136294Y379038D01*
X1136932Y378633D01*
X1137020Y378481D01*
X1135660Y377697D01*
X1135573Y377848D01*
G37*
G36*
G01X1138418Y385064D02*
X1137748Y385414D01*
Y386284D01*
X1138418Y386634D01*
X1138593D01*
Y385064D01*
X1138418D01*
G37*
G36*
G01Y381137D02*
X1137748Y381487D01*
Y382357D01*
X1138418Y382707D01*
X1138593D01*
Y381137D01*
X1138418D01*
G37*
G36*
G01Y396786D02*
X1137748Y397136D01*
Y398006D01*
X1138418Y398356D01*
X1138593D01*
Y396786D01*
X1138418D01*
G37*
G36*
G01Y400686D02*
X1137748Y401036D01*
Y401906D01*
X1138418Y402256D01*
X1138593D01*
Y400686D01*
X1138418D01*
G37*
G36*
G01Y392862D02*
X1137748Y393212D01*
Y394082D01*
X1138418Y394432D01*
X1138593D01*
Y392862D01*
X1138418D01*
G37*
G36*
G01X1095035Y381762D02*
X1095003Y382517D01*
X1095757Y382951D01*
X1096394Y382546D01*
X1096483Y382395D01*
X1095122Y381610D01*
X1095035Y381762D01*
G37*
G36*
G01X1108534Y389548D02*
X1108502Y390303D01*
X1109255Y390738D01*
X1109893Y390333D01*
X1109981Y390181D01*
X1108621Y389397D01*
X1108534Y389548D01*
G37*
G36*
G01X1105160Y387602D02*
X1105128Y388357D01*
X1105881Y388792D01*
X1106519Y388387D01*
X1106607Y388235D01*
X1105247Y387451D01*
X1105160Y387602D01*
G37*
G36*
G01X1098400Y383702D02*
X1098368Y384457D01*
X1099121Y384892D01*
X1099759Y384487D01*
X1099847Y384335D01*
X1098487Y383551D01*
X1098400Y383702D01*
G37*
G36*
G01X1101774Y385648D02*
X1101742Y386403D01*
X1102495Y386838D01*
X1103133Y386433D01*
X1103221Y386281D01*
X1101861Y385497D01*
X1101774Y385648D01*
G37*
G36*
G01X1111379Y396784D02*
X1110709Y397134D01*
Y398004D01*
X1111379Y398354D01*
X1111554D01*
Y396784D01*
X1111379D01*
G37*
G36*
G01Y400660D02*
X1110709Y401010D01*
Y401880D01*
X1111379Y402230D01*
X1111554D01*
Y400660D01*
X1111379D01*
G37*
G36*
G01Y392885D02*
X1110709Y393235D01*
Y394105D01*
X1111379Y394455D01*
X1111554D01*
Y392885D01*
X1111379D01*
G37*
G36*
G01X1114759Y367536D02*
X1114089Y367886D01*
Y368756D01*
X1114759Y369106D01*
X1114934D01*
Y367536D01*
X1114759D01*
G37*
G36*
G01X1122060Y373952D02*
X1122028Y374707D01*
X1122781Y375142D01*
X1123419Y374737D01*
X1123507Y374585D01*
X1122147Y373801D01*
X1122060Y373952D01*
G37*
G36*
G01X1118674Y371999D02*
X1118642Y372754D01*
X1119395Y373189D01*
X1120033Y372784D01*
X1120121Y372633D01*
X1118761Y371847D01*
X1118674Y371999D01*
G37*
G36*
G01X1115330Y370070D02*
X1115299Y370825D01*
X1116052Y371260D01*
X1116690Y370854D01*
X1116777Y370704D01*
X1115417Y369918D01*
X1115330Y370070D01*
G37*
G36*
G01X1114759Y363636D02*
X1114089Y363986D01*
Y364856D01*
X1114759Y365206D01*
X1114934D01*
Y363636D01*
X1114759D01*
G37*
G36*
G01Y359736D02*
X1114089Y360086D01*
Y360956D01*
X1114759Y361306D01*
X1114934D01*
Y359736D01*
X1114759D01*
G37*
G36*
G01Y355836D02*
X1114089Y356186D01*
Y357056D01*
X1114759Y357406D01*
X1114934D01*
Y355836D01*
X1114759D01*
G37*
G36*
G01X1125448Y375907D02*
X1125416Y376662D01*
X1126169Y377097D01*
X1126807Y376692D01*
X1126895Y376541D01*
X1125535Y375755D01*
X1125448Y375907D01*
G37*
G36*
G01X1135038Y387036D02*
X1134368Y387386D01*
Y388256D01*
X1135038Y388606D01*
X1135213D01*
Y387036D01*
X1135038D01*
G37*
G36*
G01X1128813Y377848D02*
X1128781Y378603D01*
X1129534Y379038D01*
X1130172Y378633D01*
X1130260Y378481D01*
X1128900Y377697D01*
X1128813Y377848D01*
G37*
G36*
G01X1135038Y383136D02*
X1134368Y383486D01*
Y384356D01*
X1135038Y384706D01*
X1135213D01*
Y383136D01*
X1135038D01*
G37*
G36*
G01X1132199Y379802D02*
X1132167Y380557D01*
X1132920Y380992D01*
X1133558Y380587D01*
X1133646Y380435D01*
X1132286Y379651D01*
X1132199Y379802D01*
G37*
G36*
G01X1135038Y394812D02*
X1134368Y395162D01*
Y396032D01*
X1135038Y396382D01*
X1135213D01*
Y394812D01*
X1135038D01*
G37*
G36*
G01Y398736D02*
X1134368Y399086D01*
Y399956D01*
X1135038Y400306D01*
X1135213D01*
Y398736D01*
X1135038D01*
G37*
G36*
G01Y402636D02*
X1134368Y402986D01*
Y403856D01*
X1135038Y404206D01*
X1135213D01*
Y402636D01*
X1135038D01*
G37*
G36*
G01Y390936D02*
X1134368Y391286D01*
Y392156D01*
X1135038Y392506D01*
X1135213D01*
Y390936D01*
X1135038D01*
G37*
G36*
G01X1116383Y390555D02*
X1117053Y390205D01*
Y389335D01*
X1116383Y388985D01*
X1116208D01*
Y390555D01*
X1116383D01*
G37*
G36*
G01X1099483Y376881D02*
X1100153Y376531D01*
Y375661D01*
X1099483Y375311D01*
X1099308D01*
Y376881D01*
X1099483D01*
G37*
G36*
G01Y372957D02*
X1100153Y372607D01*
Y371737D01*
X1099483Y371387D01*
X1099308D01*
Y372957D01*
X1099483D01*
G37*
G36*
G01Y369057D02*
X1100153Y368707D01*
Y367837D01*
X1099483Y367487D01*
X1099308D01*
Y369057D01*
X1099483D01*
G37*
G36*
G01X1102328Y380195D02*
X1102360Y379440D01*
X1101607Y379005D01*
X1100969Y379410D01*
X1100881Y379561D01*
X1102241Y380347D01*
X1102328Y380195D01*
G37*
G36*
G01X1115827Y387981D02*
X1115859Y387226D01*
X1115105Y386792D01*
X1114468Y387197D01*
X1114379Y387348D01*
X1115740Y388133D01*
X1115827Y387981D01*
G37*
G36*
G01X1112462Y386041D02*
X1112494Y385286D01*
X1111741Y384851D01*
X1111103Y385256D01*
X1111015Y385407D01*
X1112375Y386193D01*
X1112462Y386041D01*
G37*
G36*
G01X1109088Y384095D02*
X1109120Y383340D01*
X1108367Y382905D01*
X1107729Y383310D01*
X1107641Y383461D01*
X1109001Y384247D01*
X1109088Y384095D01*
G37*
G36*
G01X1105702Y382141D02*
X1105734Y381386D01*
X1104981Y380951D01*
X1104343Y381356D01*
X1104255Y381507D01*
X1105615Y382293D01*
X1105702Y382141D01*
G37*
G36*
G01X1116383Y402255D02*
X1117053Y401905D01*
Y401035D01*
X1116383Y400685D01*
X1116208D01*
Y402255D01*
X1116383D01*
G37*
G36*
G01Y398354D02*
X1117053Y398004D01*
Y397134D01*
X1116383Y396784D01*
X1116208D01*
Y398354D01*
X1116383D01*
G37*
G36*
G01Y394455D02*
X1117053Y394105D01*
Y393235D01*
X1116383Y392885D01*
X1116208D01*
Y394455D01*
X1116383D01*
G37*
G36*
G01X1122608Y368495D02*
X1122640Y367740D01*
X1121887Y367305D01*
X1121249Y367710D01*
X1121161Y367861D01*
X1122521Y368647D01*
X1122608Y368495D01*
G37*
G36*
G01X1125973Y370436D02*
X1126005Y369681D01*
X1125252Y369246D01*
X1124614Y369651D01*
X1124526Y369803D01*
X1125886Y370587D01*
X1125973Y370436D01*
G37*
G36*
G01X1132747Y374344D02*
X1132779Y373589D01*
X1132026Y373154D01*
X1131388Y373559D01*
X1131300Y373711D01*
X1132660Y374495D01*
X1132747Y374344D01*
G37*
G36*
G01X1129361Y372391D02*
X1129393Y371636D01*
X1128640Y371201D01*
X1128002Y371606D01*
X1127914Y371757D01*
X1129274Y372543D01*
X1129361Y372391D01*
G37*
G36*
G01X1140041Y388582D02*
X1140711Y388232D01*
Y387362D01*
X1140041Y387012D01*
X1139866D01*
Y388582D01*
X1140041D01*
G37*
G36*
G01X1136112Y376286D02*
X1136144Y375531D01*
X1135391Y375096D01*
X1134753Y375501D01*
X1134665Y375653D01*
X1136025Y376437D01*
X1136112Y376286D01*
G37*
G36*
G01X1139500Y378239D02*
X1139532Y377484D01*
X1138779Y377050D01*
X1138141Y377455D01*
X1138053Y377606D01*
X1139413Y378392D01*
X1139500Y378239D01*
G37*
G36*
G01X1140041Y380783D02*
X1140711Y380433D01*
Y379563D01*
X1140041Y379213D01*
X1139866D01*
Y380783D01*
X1140041D01*
G37*
G36*
G01Y384683D02*
X1140711Y384333D01*
Y383463D01*
X1140041Y383113D01*
X1139866D01*
Y384683D01*
X1140041D01*
G37*
G36*
G01X1142887Y403595D02*
X1142919Y402840D01*
X1142166Y402405D01*
X1141528Y402810D01*
X1141440Y402961D01*
X1142800Y403747D01*
X1142887Y403595D01*
G37*
G36*
G01X1140042Y400281D02*
X1140712Y399931D01*
Y399061D01*
X1140042Y398711D01*
X1139867D01*
Y400281D01*
X1140042D01*
G37*
G36*
G01Y396357D02*
X1140712Y396007D01*
Y395137D01*
X1140042Y394787D01*
X1139867D01*
Y396357D01*
X1140042D01*
G37*
G36*
G01Y392506D02*
X1140712Y392156D01*
Y391286D01*
X1140042Y390936D01*
X1139867D01*
Y392506D01*
X1140042D01*
G37*
G36*
G01X1107999Y406546D02*
X1107329Y406896D01*
Y407766D01*
X1107999Y408116D01*
X1108174D01*
Y406546D01*
X1107999D01*
G37*
G36*
G01Y410446D02*
X1107329Y410796D01*
Y411666D01*
X1107999Y412016D01*
X1108174D01*
Y410446D01*
X1107999D01*
G37*
G36*
G01Y414346D02*
X1107329Y414696D01*
Y415566D01*
X1107999Y415916D01*
X1108174D01*
Y414346D01*
X1107999D01*
G37*
G36*
G01X1109623Y409996D02*
X1110293Y409646D01*
Y408776D01*
X1109623Y408426D01*
X1109448D01*
Y409996D01*
X1109623D01*
G37*
G36*
G01Y406096D02*
X1110293Y405746D01*
Y404876D01*
X1109623Y404526D01*
X1109448D01*
Y406096D01*
X1109623D01*
G37*
G36*
G01Y413896D02*
X1110293Y413546D01*
Y412676D01*
X1109623Y412326D01*
X1109448D01*
Y413896D01*
X1109623D01*
G37*
G36*
G01Y417796D02*
X1110293Y417446D01*
Y416576D01*
X1109623Y416226D01*
X1109448D01*
Y417796D01*
X1109623D01*
G37*
G36*
G01X1121519Y410436D02*
X1120849Y410786D01*
Y411656D01*
X1121519Y412006D01*
X1121694D01*
Y410436D01*
X1121519D01*
G37*
G36*
G01Y406536D02*
X1120849Y406886D01*
Y407756D01*
X1121519Y408106D01*
X1121694D01*
Y406536D01*
X1121519D01*
G37*
G36*
G01Y414336D02*
X1120849Y414686D01*
Y415556D01*
X1121519Y415906D01*
X1121694D01*
Y414336D01*
X1121519D01*
G37*
G36*
G01X1123143Y410007D02*
X1123813Y409657D01*
Y408787D01*
X1123143Y408437D01*
X1122968D01*
Y410007D01*
X1123143D01*
G37*
G36*
G01Y406107D02*
X1123813Y405757D01*
Y404887D01*
X1123143Y404537D01*
X1122968D01*
Y406107D01*
X1123143D01*
G37*
G36*
G01Y413907D02*
X1123813Y413557D01*
Y412687D01*
X1123143Y412337D01*
X1122968D01*
Y413907D01*
X1123143D01*
G37*
G36*
G01X1104619Y408437D02*
X1103949Y408787D01*
Y409657D01*
X1104619Y410007D01*
X1104794D01*
Y408437D01*
X1104619D01*
G37*
G36*
G01Y404537D02*
X1103949Y404887D01*
Y405757D01*
X1104619Y406107D01*
X1104794D01*
Y404537D01*
X1104619D01*
G37*
G36*
G01X1104126Y414523D02*
X1103342Y414233D01*
X1102705Y414870D01*
X1102995Y415654D01*
X1103119Y415778D01*
X1104250Y414647D01*
X1104126Y414523D01*
G37*
G36*
G01X1106243Y412006D02*
X1106913Y411656D01*
Y410786D01*
X1106243Y410436D01*
X1106068D01*
Y412006D01*
X1106243D01*
G37*
G36*
G01Y408106D02*
X1106913Y407756D01*
Y406886D01*
X1106243Y406536D01*
X1106068D01*
Y408106D01*
X1106243D01*
G37*
G36*
G01X1103774Y416433D02*
X1104559Y416723D01*
X1105195Y416087D01*
X1104905Y415302D01*
X1104782Y415178D01*
X1103650Y416310D01*
X1103774Y416433D01*
G37*
G36*
G01X1118139Y404537D02*
X1117469Y404887D01*
Y405757D01*
X1118139Y406107D01*
X1118314D01*
Y404537D01*
X1118139D01*
G37*
G36*
G01Y408437D02*
X1117469Y408787D01*
Y409657D01*
X1118139Y410007D01*
X1118314D01*
Y408437D01*
X1118139D01*
G37*
G36*
G01Y412337D02*
X1117469Y412687D01*
Y413557D01*
X1118139Y413907D01*
X1118314D01*
Y412337D01*
X1118139D01*
G37*
G36*
G01Y416237D02*
X1117469Y416587D01*
Y417457D01*
X1118139Y417807D01*
X1118314D01*
Y416237D01*
X1118139D01*
G37*
G36*
G01X1119763Y408106D02*
X1120433Y407756D01*
Y406886D01*
X1119763Y406536D01*
X1119588D01*
Y408106D01*
X1119763D01*
G37*
G36*
G01Y412006D02*
X1120433Y411656D01*
Y410786D01*
X1119763Y410436D01*
X1119588D01*
Y412006D01*
X1119763D01*
G37*
G36*
G01Y415906D02*
X1120433Y415556D01*
Y414686D01*
X1119763Y414336D01*
X1119588D01*
Y415906D01*
X1119763D01*
G37*
G36*
G01X1135139Y408376D02*
X1134915Y409098D01*
X1135532Y409710D01*
X1136252Y409482D01*
X1136376Y409358D01*
X1135262Y408251D01*
X1135139Y408376D01*
G37*
G36*
G01X1131658Y404537D02*
X1130988Y404887D01*
Y405757D01*
X1131658Y406107D01*
X1131833D01*
Y404537D01*
X1131658D01*
G37*
G36*
G01X1132200Y407104D02*
X1132168Y407859D01*
X1132921Y408293D01*
X1133559Y407888D01*
X1133647Y407737D01*
X1132287Y406951D01*
X1132200Y407104D01*
G37*
G36*
G01X1136106Y407481D02*
X1136138Y406726D01*
X1135384Y406292D01*
X1134747Y406697D01*
X1134658Y406848D01*
X1136018Y407634D01*
X1136106Y407481D01*
G37*
G36*
G01X1137597Y412683D02*
X1138357Y412333D01*
Y411433D01*
X1137597Y411083D01*
X1137422D01*
Y412683D01*
X1137597D01*
G37*
G36*
G01X1151796Y402799D02*
X1151036Y403149D01*
Y404048D01*
X1151796Y404398D01*
X1151971D01*
Y402799D01*
X1151796D01*
G37*
G36*
G01X1128278Y406536D02*
X1127608Y406886D01*
Y407756D01*
X1128278Y408106D01*
X1128453D01*
Y406536D01*
X1128278D01*
G37*
G36*
G01X1128834Y409062D02*
X1128802Y409817D01*
X1129556Y410251D01*
X1130193Y409846D01*
X1130281Y409695D01*
X1128922Y408909D01*
X1128834Y409062D01*
G37*
G36*
G01X1133282Y412006D02*
X1133952Y411656D01*
Y410786D01*
X1133282Y410436D01*
X1133107D01*
Y412006D01*
X1133282D01*
G37*
G36*
G01X1132740Y409439D02*
X1132772Y408684D01*
X1132019Y408250D01*
X1131381Y408655D01*
X1131294Y408806D01*
X1132654Y409591D01*
X1132740Y409439D01*
G37*
G36*
G01X1129902Y406107D02*
X1130572Y405757D01*
Y404887D01*
X1129902Y404537D01*
X1129727D01*
Y406107D01*
X1129902D01*
G37*
G36*
G01X1148164Y405715D02*
X1147404Y406065D01*
Y406965D01*
X1148164Y407315D01*
X1148339D01*
Y405715D01*
X1148164D01*
G37*
G36*
G01X1145713Y403198D02*
X1145681Y403953D01*
X1146434Y404388D01*
X1147072Y403983D01*
X1147159Y403832D01*
X1145800Y403046D01*
X1145713Y403198D01*
G37*
G36*
G01X1149264Y407315D02*
X1150024Y406965D01*
Y406065D01*
X1149264Y405715D01*
X1149089D01*
Y407315D01*
X1149264D01*
G37*
G36*
G01X1113003Y412016D02*
X1113673Y411666D01*
Y410796D01*
X1113003Y410446D01*
X1112828D01*
Y412016D01*
X1113003D01*
G37*
G36*
G01Y408116D02*
X1113673Y407766D01*
Y406896D01*
X1113003Y406546D01*
X1112828D01*
Y408116D01*
X1113003D01*
G37*
G36*
G01Y415916D02*
X1113673Y415566D01*
Y414696D01*
X1113003Y414346D01*
X1112828D01*
Y415916D01*
X1113003D01*
G37*
G36*
G01X1139501Y405541D02*
X1139533Y404786D01*
X1138780Y404351D01*
X1138142Y404756D01*
X1138054Y404907D01*
X1139414Y405693D01*
X1139501Y405541D01*
G37*
G36*
G01X1114759Y406536D02*
X1114089Y406886D01*
Y407756D01*
X1114759Y408106D01*
X1114934D01*
Y406536D01*
X1114759D01*
G37*
G36*
G01Y410436D02*
X1114089Y410786D01*
Y411656D01*
X1114759Y412006D01*
X1114934D01*
Y410436D01*
X1114759D01*
G37*
G36*
G01X1114981Y418729D02*
X1114221Y419079D01*
Y419979D01*
X1114981Y420329D01*
X1115156D01*
Y418729D01*
X1114981D01*
G37*
G36*
G01X1114759Y414336D02*
X1114089Y414686D01*
Y415556D01*
X1114759Y415906D01*
X1114934D01*
Y414336D01*
X1114759D01*
G37*
G36*
G01X1142333Y405148D02*
X1142301Y405903D01*
X1143054Y406338D01*
X1143692Y405933D01*
X1143780Y405782D01*
X1142420Y404996D01*
X1142333Y405148D01*
G37*
G36*
G01X1138960Y403204D02*
X1138928Y403959D01*
X1139681Y404393D01*
X1140319Y403988D01*
X1140406Y403837D01*
X1139046Y403052D01*
X1138960Y403204D01*
G37*
G36*
G01X1144584Y406654D02*
X1143824Y407004D01*
Y407904D01*
X1144584Y408254D01*
X1144759D01*
Y406654D01*
X1144584D01*
G37*
G36*
G01X1111379Y404526D02*
X1110709Y404876D01*
Y405746D01*
X1111379Y406096D01*
X1111554D01*
Y404526D01*
X1111379D01*
G37*
G36*
G01Y408426D02*
X1110709Y408776D01*
Y409646D01*
X1111379Y409996D01*
X1111554D01*
Y408426D01*
X1111379D01*
G37*
G36*
G01Y412326D02*
X1110709Y412676D01*
Y413546D01*
X1111379Y413896D01*
X1111554D01*
Y412326D01*
X1111379D01*
G37*
G36*
G01X1135573Y405148D02*
X1135541Y405903D01*
X1136294Y406338D01*
X1136932Y405933D01*
X1137020Y405782D01*
X1135660Y404996D01*
X1135573Y405148D01*
G37*
G36*
G01X1116383Y410007D02*
X1117053Y409657D01*
Y408787D01*
X1116383Y408437D01*
X1116208D01*
Y410007D01*
X1116383D01*
G37*
G36*
G01Y406107D02*
X1117053Y405757D01*
Y404887D01*
X1116383Y404537D01*
X1116208D01*
Y406107D01*
X1116383D01*
G37*
G36*
G01X1116081Y420329D02*
X1116841Y419979D01*
Y419079D01*
X1116081Y418729D01*
X1115906D01*
Y420329D01*
X1116081D01*
G37*
G36*
G01X1116383Y413907D02*
X1117053Y413557D01*
Y412687D01*
X1116383Y412337D01*
X1116208D01*
Y413907D01*
X1116383D01*
G37*
G36*
G01Y417807D02*
X1117053Y417457D01*
Y416587D01*
X1116383Y416237D01*
X1116208D01*
Y417807D01*
X1116383D01*
G37*
G36*
G01X1145703Y407847D02*
X1146372Y407496D01*
X1146369Y406626D01*
X1145699Y406278D01*
X1145524D01*
X1145527Y407849D01*
X1145703Y407847D01*
G37*
G36*
G01X1145682Y405729D02*
X1145860Y404995D01*
X1145205Y404422D01*
X1144501Y404696D01*
X1144385Y404827D01*
X1145567Y405862D01*
X1145682Y405729D01*
G37*
G36*
G01X1252385Y90725D02*
X1252022Y91088D01*
X1252195Y91262D01*
X1252238Y91277D01*
G03X1250809Y93618I-466J1322D01*
G02X1250134Y93909I-275J291D01*
G01Y118493D01*
X1249682Y118946D01*
Y119131D01*
X1247886Y120926D01*
G02X1247982Y121563I283J283D01*
G03X1248473Y121996I-656J1239D01*
G02X1249111Y122017I327J-230D01*
G03X1249053Y123706I1089J883D01*
G02X1248415Y123685I-327J230D01*
G03X1246087Y123458I-1089J-883D01*
G02X1245450Y123362I-354J187D01*
G01X1240929Y127883D01*
G02X1240943Y128462I283J283D01*
G03X1238962Y130443I-943J1038D01*
G02X1238383Y130429I-296J269D01*
G01X1189031Y179782D01*
X1188846D01*
X1174118Y194509D01*
Y194827D01*
X1168259Y200686D01*
Y204041D01*
X1170071Y205853D01*
X1173449D01*
G03X1175989I1270J594D01*
G01X1180209D01*
G03X1182749I1270J594D01*
G01X1183332D01*
G02X1183671Y205241I0J-400D01*
G03X1186047I1188J-745D01*
G02X1186386Y205853I339J212D01*
G01X1186969D01*
G03X1188841Y205181I1270J594D01*
G01X1188969Y205241D01*
X1191846Y202364D01*
Y187412D01*
X1199922Y179336D01*
Y179164D01*
X1232003Y147083D01*
G03X1232034Y147054I751J772D01*
G01X1232037Y147051D01*
X1236951Y142136D01*
X1236952D01*
X1237309Y141780D01*
X1237478D01*
X1246131Y133127D01*
X1247396D01*
G03X1249836I1220J690D01*
G01X1251729D01*
X1259890Y124966D01*
Y120369D01*
X1260677Y119582D01*
G02X1260418Y118900I-283J-283D01*
G03X1259281Y118193I82J-1400D01*
G02X1258693Y118070I-348J197D01*
G03X1257135Y115744I-844J-1120D01*
G02Y115056I-204J-344D01*
G03X1257026Y112716I715J-1206D01*
G02X1257014Y112061I-236J-323D01*
G03X1258624Y112034I786J-1161D01*
G02X1258636Y112689I236J323D01*
G03X1258565Y115056I-786J1161D01*
G02Y115744I204J344D01*
G03X1259069Y116257I-715J1206D01*
G02X1259657Y116380I348J-197D01*
G03X1261900Y117418I843J1120D01*
G02X1262582Y117677I399J-24D01*
G01X1265143Y115116D01*
Y112739D01*
X1262892Y110488D01*
Y107522D01*
X1262838Y107469D01*
Y91423D01*
X1262141Y90725D01*
X1252385D01*
G37*
G36*
G01X1248356Y517338D02*
X1248300Y517393D01*
Y527299D01*
G02X1248491Y527499I200J0D01*
G03X1248627Y530286I-67J1400D01*
G01X1248456Y530311D01*
Y535637D01*
X1248627Y535662D01*
G03X1248491Y538449I-203J1387D01*
G02X1248300Y538649I9J200D01*
G01Y546357D01*
G02X1248491Y546557I200J0D01*
G03X1248539Y549354I-66J1400D01*
G02X1248356Y549554I17J199D01*
G01Y555138D01*
X1248300Y555193D01*
Y565099D01*
G02X1248491Y565299I200J0D01*
G03X1248802Y568049I-67J1400D01*
G01X1248655Y568090D01*
Y573458D01*
X1248802Y573499D01*
G03X1248491Y576249I-378J1350D01*
G02X1248300Y576449I9J200D01*
G01Y584157D01*
G02X1248491Y584357I200J0D01*
G03Y587157I-66J1400D01*
G02X1248300Y587357I9J200D01*
G01Y602899D01*
G02X1248491Y603099I200J0D01*
G03Y605899I-66J1400D01*
G02X1248300Y606099I9J200D01*
G01Y611049D01*
G02X1248491Y611249I200J0D01*
G03X1249760Y613078I-66J1400D01*
G02X1250141Y613600I381J122D01*
G01X1253409D01*
G02X1253789Y613074I0J-400D01*
G03X1253731Y612826I1331J-442D01*
G01X1253722Y612760D01*
X1252466Y611504D01*
Y606277D01*
G02X1252001Y605882I-400J-1D01*
G03Y603116I-230J-1383D01*
G02X1252466Y602721I65J-394D01*
G01Y595377D01*
G02X1252001Y594982I-400J-1D01*
G03Y592216I-230J-1383D01*
G02X1252466Y591821I65J-394D01*
G01Y575964D01*
X1253722Y574708D01*
X1253731Y574642D01*
G03X1255312Y576223I1389J192D01*
G01X1255246Y576232D01*
X1254622Y576856D01*
Y591801D01*
G02X1255043Y592200I400J0D01*
G03Y595000I77J1400D01*
G02X1254622Y595399I-21J399D01*
G01Y610612D01*
X1255246Y611236D01*
X1255312Y611245D01*
G03X1256451Y613074I-192J1389D01*
G02X1256831Y613600I380J126D01*
G01X1266000D01*
X1271150Y608450D01*
Y595368D01*
G02X1270672Y594975I-400J-1D01*
G03X1269389Y594571I-272J-1375D01*
G02X1268811I-289J277D01*
G03X1266771Y594553I-1012J-971D01*
G02X1266185I-293J272D01*
G03X1266186Y592646I-1028J-954D01*
G02X1266772I293J-272D01*
G03X1268811Y592629I1028J954D01*
G02X1269389I289J-277D01*
G03X1270672Y592225I1011J971D01*
G02X1271150Y591832I78J-392D01*
G01Y559750D01*
X1274050Y556850D01*
Y550250D01*
X1274700Y549600D01*
Y546300D01*
X1271700Y543300D01*
Y541600D01*
X1272400Y540900D01*
X1275700D01*
X1276300Y541500D01*
X1295800D01*
X1297700Y539600D01*
X1300600D01*
X1302900Y537300D01*
Y510774D01*
X1298186Y506060D01*
X1285836D01*
X1284826Y505050D01*
X1278950D01*
X1275300Y501400D01*
X1271011D01*
G02X1270611Y501795I0J400D01*
G03X1267807I-1402J-18D01*
G02X1267407Y501400I-400J5D01*
G01X1254300D01*
X1248900Y506800D01*
Y508832D01*
X1249016Y508886D01*
G03Y511428I-591J1271D01*
G01X1248900Y511482D01*
Y516300D01*
X1248356Y516844D01*
Y517338D01*
G37*
G36*
G01X1331600Y546600D02*
X1329900Y548300D01*
Y615100D01*
X1335622Y620822D01*
X1362078D01*
X1366900Y616000D01*
Y598900D01*
X1363700Y595700D01*
Y590700D01*
X1366700Y587700D01*
Y568200D01*
X1362150Y563650D01*
Y553050D01*
X1355700Y546600D01*
X1331600D01*
G37*
G36*
G01X1398218Y15699D02*
G03X1397128Y4786I1882J-5699D01*
G02X1397212Y4155I-198J-347D01*
G01X1392500Y-557D01*
Y-16790D01*
X1388790Y-20500D01*
X1369900D01*
X1361500Y-12100D01*
Y9697D01*
X1367200Y15397D01*
Y34800D01*
G03X1368400Y35094I-99J3000D01*
G03X1372347Y36384I1300J2706D01*
G03X1373133Y36590I53J1401D01*
G01X1376730D01*
X1376892Y36752D01*
X1376976Y36751D01*
G03X1379470Y41472I33J3002D01*
G02X1379717Y42093I328J229D01*
G03X1382111Y45113I-607J2940D01*
G03X1382699Y47574I-294J1371D01*
G02X1382668Y48168I252J311D01*
G01X1385500Y51000D01*
Y55655D01*
G03Y59443I-2329J1894D01*
G01Y75000D01*
X1385482Y75018D01*
Y79771D01*
X1386086Y80375D01*
X1398637D01*
X1400500Y78512D01*
Y75000D01*
X1404000Y71500D01*
Y52661D01*
G02X1403400Y52315I-400J0D01*
G03Y49885I-700J-1215D01*
G02X1404000Y49539I200J-346D01*
G01Y49118D01*
X1400541Y45659D01*
Y40548D01*
X1403983Y37106D01*
X1406394D01*
X1412602Y30898D01*
Y23082D01*
X1406134D01*
X1405790D01*
G02X1405392Y23528I0J400D01*
G03X1399765Y20489I-3876J448D01*
G02X1399868Y19849I-180J-357D01*
G01X1398218Y18200D01*
Y15699D01*
G37*
G36*
G01X1354800Y369200D02*
X1351500Y372500D01*
Y390000D01*
X1358905Y397405D01*
X1362500D01*
X1364726Y399631D01*
Y403226D01*
X1366700Y405200D01*
X1385400D01*
X1388300Y402300D01*
Y397600D01*
X1385800Y395100D01*
X1384783D01*
X1384749Y395113D01*
G03X1383278Y395272I-1048J-2813D01*
G02X1382840Y395786I-56J396D01*
G03X1380190Y395700I-1340J414D01*
G02X1379932Y395174I-373J-143D01*
G03X1379712Y395098I870J-2873D01*
G02X1379461Y395195I-72J186D01*
G03X1377753Y393242I-1254J-627D01*
G02X1377882Y393006I-65J-189D01*
G03X1378700Y390155I2918J-706D01*
G01Y383328D01*
X1381200Y380828D01*
Y379899D01*
G02X1380816Y379499I-400J0D01*
G03Y376697I56J-1401D01*
G02X1381200Y376297I-16J-400D01*
G01Y369942D01*
X1380458Y369200D01*
X1373292D01*
X1372378Y370114D01*
X1371013D01*
X1370099Y369200D01*
X1354800D01*
G37*
G36*
G01X1468138Y615977D02*
G03X1472710Y616137I2218J2023D01*
G03X1474484Y616561I222J2994D01*
G03X1477277Y616558I1399J2656D01*
G03X1480570Y617125I1223J2742D01*
G03X1482852Y617758I404J2975D01*
G01X1482877D01*
G03X1483658Y617750I404J1342D01*
G01X1483682Y617758D01*
X1535293D01*
X1535525Y617525D01*
Y615095D01*
G02X1535086Y614697I-400J0D01*
G03X1534043Y612231I-138J-1395D01*
G02X1534039Y611616I-258J-306D01*
G03X1535081Y609138I889J-1084D01*
G02X1535525Y608741I44J-397D01*
G01Y600666D01*
G02X1535107Y600267I-400J0D01*
G03X1532887Y599432I-139J-2999D01*
G01X1531979D01*
X1526393Y593846D01*
X1520199D01*
X1519811Y593457D01*
X1508175D01*
X1502586Y587868D01*
X1463342D01*
X1463329Y588054D01*
G03X1463017Y588841I-1399J-99D01*
G02X1463041Y589374I310J253D01*
G03X1463125Y591240I-1002J980D01*
G02X1463151Y591774I310J253D01*
G03X1461069Y591875I-996J987D01*
G02X1461043Y591341I-310J-253D01*
G03X1460952Y589469I996J-987D01*
G02X1460928Y588936I-310J-253D01*
G03X1460531Y588054I1001J-981D01*
G01X1460518Y587868D01*
X1457644D01*
X1455396Y585620D01*
X1450268D01*
X1450240Y585592D01*
X1442292D01*
X1436701Y580000D01*
X1425500D01*
X1423177Y582323D01*
X1398355D01*
X1397552Y583126D01*
Y585748D01*
X1396474Y586825D01*
Y591584D01*
X1396792Y591902D01*
X1405769D01*
X1409813Y587858D01*
X1428603D01*
X1441944Y601199D01*
Y607724D01*
X1448283Y614064D01*
X1463688D01*
X1466121Y616497D01*
X1466256Y616413D01*
G03X1468138Y615977I1583J2551D01*
G37*
G36*
G01X1370800Y568600D02*
X1372800Y570600D01*
X1377000D01*
X1383400Y564200D01*
Y557600D01*
X1382000Y556200D01*
X1373600D01*
X1370800Y559000D01*
Y568600D01*
G37*
G36*
G01X1443300Y378900D02*
X1449700D01*
Y397300D01*
X1443300D01*
Y378900D01*
G37*
G36*
G01X1436900Y417400D02*
X1447400D01*
Y430000D01*
X1436900D01*
Y417400D01*
G37*
G36*
G01X1512720Y404309D02*
G02X1512322Y404675I0J400D01*
G03X1509691Y405219I-1397J-121D01*
G02X1509056Y405125I-352J189D01*
G01X1507820Y406361D01*
Y412088D01*
G02X1508437Y412423I400J-1D01*
G03X1509881Y414825I762J1177D01*
G02Y415525I194J350D01*
G03X1510425Y416069I-681J1225D01*
G02X1511125I350J-194D01*
G03X1513575I1225J681D01*
G02X1514275I350J-194D01*
G03X1516725I1225J681D01*
G02X1517425I350J-194D01*
G03X1517969Y415525I1225J681D01*
G02Y414825I-194J-350D01*
G03X1519331I681J-1225D01*
G02Y415525I194J350D01*
G03Y417975I-681J1225D01*
G02Y418675I194J350D01*
G03Y421125I-681J1225D01*
G02Y421825I194J350D01*
G03Y424275I-681J1225D01*
G02Y424975I194J350D01*
G03Y427425I-681J1225D01*
G02Y428125I194J350D01*
G03X1517425Y430031I-681J1225D01*
G02X1516725I-350J194D01*
G03X1514275I-1225J-681D01*
G02X1513575I-350J194D01*
G03X1511125I-1225J-681D01*
G02X1510425I-350J194D01*
G03X1507956Y429997I-1225J-681D01*
G02X1507259Y429974I-355J184D01*
G03X1507303Y428602I-1200J-725D01*
G02X1508000Y428625I355J-184D01*
G03X1508519Y428125I1199J726D01*
G02Y427425I-194J-350D01*
G03Y424975I681J-1225D01*
G02Y424275I-194J-350D01*
G03X1508172Y424004I679J-1227D01*
G02X1507596Y423993I-293J272D01*
G01X1504664Y426925D01*
X1502742D01*
G02X1502394Y427522I0J400D01*
G03X1499954Y428903I-1219J692D01*
G02X1499323Y428816I-349J196D01*
G01X1496303Y431836D01*
G02X1496306Y432404I283J283D01*
G03X1494323Y434387I-981J1002D01*
G02X1493755Y434384I-285J280D01*
G01X1493410Y434729D01*
G02X1493622Y435406I282J283D01*
G03X1491979Y436660I-247J1380D01*
G01X1491987Y436567D01*
X1491779Y436360D01*
X1491500Y436639D01*
Y438756D01*
X1491666Y438785D01*
G03X1491937Y441471I-241J1381D01*
G02X1491800Y442126I146J372D01*
G01X1492300Y442626D01*
X1492441Y442500D01*
G03Y444592I934J1046D01*
G01X1492300Y444466D01*
X1491800Y444966D01*
G02X1491937Y445621I283J283D01*
G03X1490641Y448088I-511J1305D01*
G01X1490504Y447996D01*
X1490057Y448443D01*
G02X1490148Y449076I283J282D01*
G03X1490282Y451453I-673J1230D01*
G02X1490172Y451991I230J327D01*
G01Y452098D01*
G02X1490762Y452451I400J1D01*
G03X1490504Y454743I663J1235D01*
G02X1490172Y454894I-132J151D01*
G01Y455042D01*
X1490028Y455187D01*
G02X1490125Y455824I283J283D01*
G03X1490753Y457643I-650J1242D01*
G02X1491117Y458207I365J164D01*
G01X1491733D01*
G02X1492097Y457643I-1J-400D01*
G03X1494653I1278J-577D01*
G02X1495017Y458207I365J164D01*
G01X1495633D01*
G02X1495997Y457643I-1J-400D01*
G03X1498553I1278J-577D01*
G02X1498917Y458207I365J164D01*
G01X1499533D01*
G02X1499897Y457643I-1J-400D01*
G03X1502453I1278J-577D01*
G02X1502817Y458207I365J164D01*
G01X1507333D01*
G02X1507697Y457643I-1J-400D01*
G03X1507626Y456685I1278J-576D01*
G03X1508074Y455991I1350J380D01*
G02X1508116Y455440I-267J-297D01*
G03X1507843Y454903I1084J-889D01*
G03X1510327Y453715I1357J-354D01*
G03X1510435Y453886I-1129J833D01*
G02X1511145Y453875I352J-190D01*
G03X1511208Y453762I1255J626D01*
G03X1513780Y454250I1192J738D01*
G03X1511165Y455164I-1380J251D01*
G02X1510455Y455175I-352J190D01*
G03X1510434Y455216I-1258J-619D01*
G03X1510101Y455625I-1235J-665D01*
G02X1510059Y456176I267J297D01*
G03X1510253Y457643I-1084J890D01*
G02X1510617Y458207I365J164D01*
G01X1515133D01*
G02X1515497Y457643I-1J-400D01*
G03X1518053I1278J-577D01*
G02X1518417Y458207I365J164D01*
G01X1519033D01*
G02X1519397Y457643I-1J-400D01*
G03X1521953I1278J-577D01*
G02X1522317Y458207I365J164D01*
G01X1526833D01*
G02X1527197Y457643I-1J-400D01*
G03X1529753I1278J-577D01*
G02X1530117Y458207I365J164D01*
G01X1538533D01*
G02X1538897Y457643I-1J-400D01*
G03X1539378Y455912I1278J-577D01*
G02X1539484Y455362I-227J-329D01*
G03X1540018Y453338I1169J-774D01*
G02X1540028Y452631I-182J-356D01*
G03X1539699Y452382I672J-1230D01*
G03X1539467Y452067I1002J-981D01*
G02X1538783I-342J208D01*
G03X1536317I-1233J-667D01*
G02X1535633I-342J208D01*
G03X1533167I-1233J-667D01*
G02X1532483I-342J208D01*
G03Y450733I-1233J-667D01*
G02X1533167I342J-208D01*
G03X1535633I1233J667D01*
G02X1536317I342J-208D01*
G03X1538783I1233J667D01*
G02X1539467I342J-208D01*
G03X1541933I1233J667D01*
G02X1542617I342J-208D01*
G03Y452067I1233J667D01*
G02X1541933I-342J208D01*
G03X1541401Y452614I-1233J-667D01*
G03X1541335Y452650I-704J-1212D01*
G02X1541325Y453357I182J356D01*
G03X1541450Y455742I-672J1231D01*
G02X1541344Y456292I227J329D01*
G03X1541453Y457643I-1169J774D01*
G02X1541817Y458207I365J164D01*
G01X1542433D01*
G02X1542797Y457643I-1J-400D01*
G03X1545353I1278J-577D01*
G02X1545717Y458207I365J164D01*
G01X1546333D01*
G02X1546697Y457643I-1J-400D01*
G03X1549253I1278J-577D01*
G02X1549617Y458207I365J164D01*
G01X1550233D01*
G02X1550597Y457643I-1J-400D01*
G03X1553153I1278J-577D01*
G02X1553517Y458207I365J164D01*
G01X1554133D01*
G02X1554497Y457643I-1J-400D01*
G03X1556313Y455771I1278J-577D01*
G02X1556572Y455668I76J-185D01*
G03X1556915Y455076I3101J1401D01*
G02X1556874Y454800I-162J-117D01*
G03X1557162Y452402I851J-1114D01*
G03X1558602Y452592I563J1284D01*
G02X1559252Y452281I250J-312D01*
G01Y451998D01*
X1559120Y451950D01*
G03X1558214Y450387I475J-1319D01*
G01X1558218Y450369D01*
Y448726D01*
G02X1557797Y448326I-400J0D01*
G03X1557085Y445679I-72J-1400D01*
G01X1557113Y445664D01*
X1557277Y445501D01*
X1557028Y445251D01*
Y445134D01*
G02X1556438Y444781I-400J-1D01*
G03X1556696Y442489I-663J-1235D01*
G02X1557028Y442338I132J-151D01*
G01Y442149D01*
X1557145Y442031D01*
G02X1557054Y441397I-283J-283D01*
G03X1556372Y440534I671J-1231D01*
G03X1556925Y439015I1353J-368D01*
G02X1557022Y438454I-228J-328D01*
G01Y437852D01*
X1556822D01*
G02X1556590Y437927I1J400D01*
G03X1554613Y436001I-815J-1141D01*
G02X1554282Y435378I-332J-223D01*
G01X1553649D01*
X1550952Y432681D01*
Y431224D01*
X1549433Y429705D01*
Y429274D01*
X1548961Y428802D01*
X1548819Y428943D01*
G03X1546618Y428867I-1065J-1059D01*
G03X1547003Y426583I972J-1011D01*
G03X1548571Y426623I751J1301D01*
G02X1548816Y426255I-155J-369D01*
G01Y425558D01*
G03Y423948I1148J-805D01*
G01Y419416D01*
X1547600Y418200D01*
X1542400D01*
X1542100Y418500D01*
Y419830D01*
G03X1541367Y421133I-1400J70D01*
G02Y421817I208J342D01*
G03Y424283I-667J1233D01*
G02Y424967I208J342D01*
G03X1541933Y425533I-667J1233D01*
G02X1542617I342J-208D01*
G03X1544517Y427433I1233J667D01*
G02Y428117I208J342D01*
G03X1542617Y430017I-667J1233D01*
G02X1541933I-342J208D01*
G03X1539467I-1233J-667D01*
G02X1538783I-342J208D01*
G03X1536317I-1233J-667D01*
G02X1535633I-342J208D01*
G03X1533167I-1233J-667D01*
G02X1532483I-342J208D01*
G03X1530583Y428117I-1233J-667D01*
G02Y427433I-208J-342D01*
G03Y424967I667J-1233D01*
G02Y424283I-208J-342D01*
G03Y421817I667J-1233D01*
G02Y421133I-208J-342D01*
G03X1532483Y419233I667J-1233D01*
G02X1533167I342J-208D01*
G03X1533733Y418667I1233J667D01*
G02Y417983I-208J-342D01*
G03X1535633Y416083I667J-1233D01*
G02X1536317I342J-208D01*
G03X1536883Y415517I1233J667D01*
G02Y414833I-208J-342D01*
G03X1536382Y414376I666J-1234D01*
G03X1536303Y414241I1169J-774D01*
G02X1535604Y414219I-356J183D01*
G03X1533061Y413084I-1204J-719D01*
G03X1535281Y412410I1339J416D01*
G03X1535647Y412859I-880J1091D01*
G02X1536346Y412881I356J-183D01*
G03X1537391Y412207I1204J719D01*
G03X1538783Y412933I159J1393D01*
G02X1539467I342J-208D01*
G03X1540033Y412367I1233J667D01*
G02Y411683I-208J-342D01*
G03X1539298Y410477I667J-1233D01*
G01X1539297Y410397D01*
X1537829Y408929D01*
G02X1537264Y408928I-283J283D01*
G03X1535005Y407340I-989J-994D01*
G02X1534588Y406791I-370J-152D01*
G01X1533431Y405634D01*
X1533424Y405628D01*
G03X1533251Y405455I901J-1074D01*
G01X1533245Y405448D01*
X1532106Y404309D01*
X1528320D01*
G02X1527922Y404675I0J400D01*
G03X1525128I-1397J-121D01*
G02X1524730Y404309I-398J34D01*
G01X1524420D01*
G02X1524022Y404675I0J400D01*
G03X1521228I-1397J-121D01*
G02X1520830Y404309I-398J34D01*
G01X1512720D01*
G37*
G36*
G01X1608262Y386799D02*
X1597960D01*
Y396541D01*
X1608262D01*
Y386799D01*
G37*
G36*
G01X1764266Y160704D02*
X1761991Y162978D01*
X1752285D01*
X1750749Y164514D01*
X1712639D01*
X1712526Y164402D01*
X1712475D01*
X1709532Y161458D01*
X1705201D01*
X1705163Y161609D01*
G03X1702523Y162390I-1552J-395D01*
G02X1701968Y162401I-272J294D01*
G03X1699272Y161615I-1132J-1133D01*
G01X1699237Y161458D01*
X1691269D01*
X1691227Y161602D01*
G03X1688343I-1442J-422D01*
G01X1688301Y161458D01*
X1685899D01*
X1679250Y168107D01*
Y177413D01*
X1679418Y177581D01*
Y182658D01*
Y186524D01*
Y187221D01*
X1680397Y188200D01*
X1689864D01*
Y187459D01*
G02X1689162Y187198I-400J1D01*
G03Y185102I-1212J-1048D01*
G02X1689864Y184841I302J-262D01*
G01Y180742D01*
X1700984D01*
Y185338D01*
G02X1701607Y185670I400J0D01*
G03X1703031Y185489I893J1330D01*
G01X1703064Y185500D01*
X1711000D01*
X1711263Y185763D01*
X1711487Y185539D01*
X1711456Y185427D01*
G03X1713053Y186601I1544J-427D01*
G02X1712784Y187284I13J400D01*
G01X1714133Y188633D01*
X1714236Y188614D01*
G03X1716059Y190661I292J1575D01*
G01X1716050Y190690D01*
Y191150D01*
X1717200Y192300D01*
X1717569D01*
G02X1717855Y191620I0J-400D01*
G03X1720145I1145J-1120D01*
G02X1720431Y192300I286J280D01*
G01X1808000D01*
X1810950Y189350D01*
Y166961D01*
X1810300Y166312D01*
Y162032D01*
X1808972Y160704D01*
X1794544D01*
G02X1794301Y161421I0J400D01*
G03X1794527Y163920I-1033J1353D01*
G02X1794515Y164444I296J269D01*
G03X1791946Y164385I-1310J1087D01*
G02X1791958Y163861I-296J-269D01*
G03X1792235Y161421I1310J-1087D01*
G02X1791992Y160704I-243J-317D01*
G01X1764266D01*
G37*
G36*
G01X1715905Y94230D02*
X1712597Y97538D01*
Y147536D01*
G02X1713245Y147850I400J0D01*
G03X1715427Y149441I869J1100D01*
G02X1715802Y149980I375J139D01*
G01X1734267D01*
G02X1734649Y149463I0J-400D01*
G03X1737329I1340J-413D01*
G02X1737711Y149980I382J117D01*
G01X1740446D01*
X1741761Y148666D01*
X1748734D01*
X1750500Y146900D01*
Y142226D01*
X1750487Y142192D01*
G03Y141208I1313J-492D01*
G01X1750500Y141174D01*
Y96131D01*
X1748599Y94230D01*
X1747976D01*
G02X1747647Y94856I1J400D01*
G03X1745335I-1156J794D01*
G02X1745006Y94230I-330J-226D01*
G01X1715905D01*
G37*
G36*
G01X1812304Y554341D02*
G03I-600J0D01*
G37*
G36*
G01X1788100Y597791D02*
G03I-600J0D01*
G37*
G36*
G01X1861700Y170500D02*
Y157700D01*
X1872100D01*
Y170500D01*
X1861700D01*
G37*
G36*
G01X1906562Y151376D02*
G03X1906503Y151444I-1465J-1212D01*
G02X1906521Y151998I297J268D01*
G03X1904200Y152589I-981J1002D01*
G02X1903817Y152072I-382J-117D01*
G01X1903018D01*
X1892188Y162902D01*
X1887884D01*
X1886241Y164544D01*
G02X1886289Y165151I283J283D01*
G03X1885057Y167626I-824J1134D01*
G02X1884540Y168009I-117J383D01*
G01Y171215D01*
X1884889Y171564D01*
G02X1885445Y171574I283J-283D01*
G03X1887415Y173567I955J1026D01*
G02X1887422Y174126I290J276D01*
G01X1888249Y174953D01*
Y182030D01*
X1888302Y182083D01*
Y191734D01*
X1888845Y192277D01*
X1890437D01*
X1892882Y189832D01*
X1911968D01*
X1913760Y188040D01*
X1922884D01*
X1928319Y182605D01*
Y177042D01*
G02X1928131Y176842I-200J0D01*
G03Y174044I87J-1399D01*
G02X1928319Y173844I-12J-200D01*
G01Y172153D01*
G02X1927826Y171764I-400J0D01*
G03Y169036I-326J-1364D01*
G02X1928319Y168647I93J-389D01*
G01Y163642D01*
X1928316Y163626D01*
G03Y163174I1384J-226D01*
G01X1928319Y163158D01*
Y159825D01*
G03Y157375I681J-1225D01*
G01Y156946D01*
X1928033D01*
X1927973Y157009D01*
G03X1927704Y154866I-1021J-960D01*
G02X1928319Y154528I215J-337D01*
G01Y154110D01*
X1927655Y153446D01*
X1927532Y153497D01*
G03X1925703Y151668I-532J-1297D01*
G01X1925754Y151545D01*
X1925585Y151376D01*
X1925158D01*
X1925108Y151504D01*
G03X1922492I-1308J-504D01*
G01X1922442Y151376D01*
X1921798D01*
Y151698D01*
X1921906Y151754D01*
G03X1920235Y152048I-642J1246D01*
G02X1919942Y151376I-293J-272D01*
G01X1916303D01*
G02X1915945Y151954I0J400D01*
G03X1913435I-1255J626D01*
G02X1913077Y151376I-358J-178D01*
G01X1906562D01*
G37*
G36*
G01X1889700Y444600D02*
X1889200Y445100D01*
Y446460D01*
X1889353Y446497D01*
G03X1890236Y447065I-377J1557D01*
G02X1890866I315J-247D01*
G03X1893386I1260J989D01*
G02X1894015I315J-247D01*
G03X1896598Y447151I1260J989D01*
G02X1897261Y447149I331J-225D01*
G03X1899650Y447248I1164J781D01*
G02X1900349I349J-194D01*
G03Y448612I1225J682D01*
G02X1899650I-350J194D01*
G03X1897326Y448800I-1225J-682D01*
G02X1896665Y448850I-314J249D01*
G03X1894015Y449043I-1390J-796D01*
G02X1893386I-314J247D01*
G03X1890866I-1260J-989D01*
G02X1890236I-315J247D01*
G03X1889353Y449611I-1260J-989D01*
G01X1889200Y449648D01*
Y452790D01*
X1889352Y452828D01*
G03X1890228Y453394I-384J1555D01*
G02X1890858I315J-247D01*
G03X1893488Y453553I1260J989D01*
G02X1894151Y453584I342J-208D01*
G03X1896500Y453741I1124J838D01*
G02X1897200I350J-194D01*
G03Y455103I1225J681D01*
G02X1896500I-350J194D01*
G03X1894130Y455232I-1226J-681D01*
G02X1893467Y455247I-326J231D01*
G03X1890858Y455372I-1349J-864D01*
G02X1890228I-315J247D01*
G03X1889352Y455938I-1260J-989D01*
G01X1889200Y455976D01*
Y473000D01*
X1891500Y475300D01*
X1907790D01*
X1909280Y473810D01*
Y472693D01*
X1909257Y472649D01*
G03Y471351I1243J-649D01*
G01X1909280Y471307D01*
Y455917D01*
G02X1908657Y455585I-400J0D01*
G03X1906649Y455103I-783J-1163D01*
G02X1905949I-350J194D01*
G03Y453741I-1225J-681D01*
G02X1906649I350J-194D01*
G03X1908657Y453259I1225J681D01*
G02X1909280Y452927I223J-332D01*
G01Y449895D01*
G02X1908657Y449563I-400J0D01*
G03X1907670Y447013I-783J-1163D01*
G02X1907894Y446334I-58J-396D01*
G01X1906160Y444600D01*
X1889700D01*
G37*
G36*
G01X1929587Y69229D02*
X1928490Y70326D01*
Y73880D01*
X1930145Y75535D01*
X1933905D01*
X1940514Y82144D01*
X1947316D01*
G02X1947572Y81437I0J-400D01*
G03X1949372I900J-1075D01*
G02X1949628Y82144I256J307D01*
G01X1954344D01*
X1955565Y80923D01*
Y70845D01*
X1953949Y69229D01*
X1929587D01*
G37*
G36*
G01X1924226Y480947D02*
X1922932Y482241D01*
Y492630D01*
G02X1923497Y492994I400J0D01*
G03X1927263Y497513I1257J2781D01*
G02X1927591Y498141I328J228D01*
G01X1931760D01*
G02X1932088Y497513I0J-400D01*
G03X1937106I2509J-1738D01*
G02X1937434Y498141I328J228D01*
G01X1939510D01*
X1940305Y497346D01*
Y491046D01*
X1939974Y490715D01*
X1939791Y490897D01*
X1939779Y490954D01*
G03X1937851Y489364I-1369J-304D01*
G02X1937974Y488715I-160J-366D01*
G01X1930206Y480947D01*
X1930086D01*
G02X1929793Y481619I0J400D01*
G03X1927447I-1173J1091D01*
G02X1927154Y480947I-293J-272D01*
G01X1924226D01*
G37*
%LPC*%
G75*
G36*
G01X746700Y-37400D02*
X783207D01*
Y-57100D01*
X746700D01*
Y-57200D01*
X541400D01*
Y-37300D01*
X746700D01*
Y-37400D01*
G37*
G36*
G01X397000Y-39100D02*
X450380D01*
Y-57500D01*
X394400D01*
Y-57530D01*
X115400D01*
Y-37300D01*
X145500D01*
Y-39050D01*
X397000D01*
Y-39100D01*
G37*
G36*
G01X874068Y-37100D02*
X1115285D01*
Y-57100D01*
X874068D01*
Y-37100D01*
G37*
G36*
G01X1427866Y-37300D02*
X1670408D01*
Y-57200D01*
X1427866D01*
Y-37300D01*
G37*
G36*
G01X1370957Y-57200D02*
X1151443D01*
Y-37400D01*
X1370957D01*
Y-57200D01*
G37*
G36*
G01X4973Y301570D02*
G02Y303124I-1167J777D01*
G03X5639I333J222D01*
G02Y301570I1167J-777D01*
G03X4973I-333J-222D01*
G37*
G36*
G01X239800Y659600D02*
X400100D01*
Y639900D01*
X239800D01*
Y659600D01*
G37*
G36*
G01X930900D02*
X1216600D01*
Y639900D01*
X930900D01*
Y659600D01*
G37*
G36*
G01X1733Y66210D02*
G03X1351Y66698I-390J88D01*
G02X2749Y67790I31J1402D01*
G03X3131Y67302I390J-88D01*
G02X1733Y66210I-31J-1402D01*
G37*
G36*
G01X15325Y53505D02*
G02X11358Y54833I-1300J2706D01*
G02X9772Y55369I-433J1334D01*
G02X11892Y59029I-784J2898D01*
G03X12484Y58787I387J101D01*
G02X15325Y58917I1541J-2576D01*
G02Y53505I1300J-2706D01*
G37*
G36*
G01X2743Y39077D02*
G02X758Y37166I857J-2877D01*
G02X2743Y39077I813J1142D01*
G37*
G36*
G01X12702Y32923D02*
G03X12689Y32394I293J-272D01*
G02X10437Y32448I-1150J-967D01*
G03X10450Y32977I-293J272D01*
G02X10468Y34931I1150J966D01*
G03Y35457I-302J263D01*
G02X12732I1132J987D01*
G03Y34931I302J-263D01*
G02X12702Y32923I-1132J-987D01*
G37*
G36*
G01X13886Y63423D02*
G02X13771Y61874I1225J-870D01*
G03X13089Y61924I-356J-182D01*
G02X10762Y63815I-1225J870D01*
G03X10775Y64344I-293J272D01*
G02X10793Y66298I1150J966D01*
G03Y66824I-302J263D01*
G02X13057I1132J987D01*
G03Y66298I302J-263D01*
G02X13027Y64290I-1132J-987D01*
G03X13014Y63761I293J-272D01*
G02X13204Y63473I-1151J-966D01*
G03X13886Y63423I356J182D01*
G37*
G36*
G01X2629Y57596D02*
G02X1052Y57616I-803J-1149D01*
G03X1060Y58277I-221J333D01*
G02X2637Y58257I803J1149D01*
G03X2629Y57596I221J-333D01*
G37*
G36*
G01X28987Y589962D02*
G03X28729Y589961I-128J-153D01*
G02X28720Y592864I-1234J1448D01*
G03X28978Y592865I128J153D01*
G02X31336Y592951I1233J-1448D01*
G02X33799Y593022I1273J-1413D01*
G02X33895Y590137I1286J-1401D01*
G02X31485Y590004I-1286J1401D01*
G02X28987Y589962I-1273J1413D01*
G37*
G36*
G01X47796Y579554D02*
G03Y578946I260J-304D01*
G02X45324I-1236J-1446D01*
G03Y579554I-260J304D01*
G02X47796I1236J1446D01*
G37*
G36*
G01X15150Y573407D02*
G02X15110Y577179I650J1893D01*
G02Y577621I1990J221D01*
G02X14691Y581167I690J1879D01*
G03Y581833I-221J333D01*
G02X14987Y585330I1109J1667D01*
G01X15106Y585382D01*
Y585514D01*
G02X15127Y585804I2002J1D01*
G02X15139Y589600I643J1896D01*
G02X17770Y587783I2000J83D01*
G02X17751Y587409I-2000J-86D01*
G02X18216Y583846I-643J-1896D01*
G03X18224Y583174I221J-333D01*
G02X17800Y579585I-1068J-1693D01*
G02X17790Y579279I-2000J-88D01*
G02Y575521I-690J-1879D01*
G02X17789Y575076I-1990J-218D01*
G02X18703Y571933I-650J-1893D01*
G02X15575I-1564J-1250D01*
G02X15150Y573407I1564J1249D01*
G37*
G36*
G01X20698Y565266D02*
G02Y568134I-1250J1434D01*
G02X23215Y568119I1250J-1434D01*
G03X23481I133J149D01*
G02Y565281I1267J-1419D01*
G03X23215I-133J-149D01*
G02X20698Y565266I-1267J1419D01*
G37*
G36*
G01X28381Y558982D02*
G03X28647I133J149D01*
G02X31315Y558849I1267J-1419D01*
G03X31920Y558868I294J271D01*
G02X34646Y559102I1476J-1200D01*
G02X37163Y559087I1250J-1434D01*
G03X37429I133J149D01*
G02Y556249I1267J-1419D01*
G03X37163I-133J-149D01*
G02X34646Y556234I-1267J1419D01*
G02X31995Y556382I-1250J1434D01*
G03X31390Y556363I-294J-271D01*
G02X28647Y556144I-1476J1200D01*
G03X28381I-133J-149D01*
G02Y558982I-1267J1419D01*
G37*
G36*
G01X47282Y556535D02*
G03Y555995I295J-270D01*
G02X44478I-1402J-1285D01*
G03Y556535I-295J270D01*
G02X47282I1402J1285D01*
G37*
G36*
G01X3064Y541850D02*
G02X3026Y539304I-1564J-1250D01*
G02X-87Y539379I-1587J-1221D01*
G02X-64Y541850I1587J1221D01*
G02X3064I1564J1250D01*
G37*
G36*
G01X43566Y534091D02*
G03X43400Y533885I34J-197D01*
G02X41175Y535674I-1900J-85D01*
G03X41341Y535880I-34J197D01*
G02X41933Y537346I1900J85D01*
G03X41958Y537607I-138J145D01*
G02X44210Y540481I1547J1107D01*
G03X44713Y540668I148J371D01*
G02X47636Y538344I1687J-878D01*
G03Y537736I260J-304D01*
G02X45236Y534786I-1235J-1446D01*
G03X44687Y534729I-245J-316D01*
G02X43566Y534091I-1446J1236D01*
G37*
G36*
G01X28200Y530824D02*
G02Y533776I-1200J1476D01*
G02Y530824I1200J-1476D01*
G37*
G36*
G01X12075Y535933D02*
G02X13600Y539185I1564J1250D01*
G02X15104Y541040I2000J-85D01*
G02X15110Y541421I1996J159D01*
G02Y545179I690J1879D01*
G02Y545621I1990J221D01*
G02X15043Y549354I690J1879D01*
G02X15053Y549838I1992J201D01*
G02X15139Y553594I734J1862D01*
G02X17787Y551789I2000J89D01*
G02X17769Y551420I-2000J-87D01*
G02X17792Y547704I-734J-1863D01*
G02X17790Y547279I-1992J-203D01*
G02Y543521I-690J-1879D01*
G02Y543079I-1990J-221D01*
G02X18214Y539537I-690J-1879D01*
G03X18221Y538868I223J-332D01*
G02X18703Y535933I-1082J-1685D01*
G02X19138Y534580I-1564J-1249D01*
G03X19462Y534167I400J-20D01*
G02X20400Y533688I-362J-1867D01*
G02Y530912I1300J-1388D01*
G02X17198Y532304I-1300J1388D01*
G03X16855Y532701I-400J1D01*
G02X15680Y533312I284J1982D01*
G03X15098I-291J-274D01*
G02X12075Y535933I-1460J1370D01*
G37*
G36*
G01X45419Y525634D02*
G03X45563Y526142I-217J336D01*
G02X49355Y526752I1806J863D01*
G03X49760Y526302I397J-50D01*
G02X48580Y522713I40J-2002D01*
G03X48031Y522655I-244J-317D01*
G02X45419Y525634I-1524J1298D01*
G37*
G36*
G01X38219Y521278D02*
G03X37933Y521799I-378J132D01*
G02X40008Y524925I456J1949D01*
G03X40609Y524871I324J235D01*
G02X42391Y521463I1384J-1446D01*
G03X42078Y520996I80J-392D01*
G02X38219Y521278I-1967J-373D01*
G37*
G36*
G01X39597Y507538D02*
G02X35628Y507055I-1997J-137D01*
G02X33705Y509088I79J2000D01*
G02X33295Y509269I598J1910D01*
G02X32805Y512331I-1495J1331D01*
G02X35541Y512571I1495J-1331D01*
G02X38981Y511490I1459J-1371D01*
G02X39597Y507538I218J-1990D01*
G37*
G36*
G01X45515Y505748D02*
G03X46098Y505745I293J272D01*
G02X46085Y503002I1452J-1378D01*
G03X45502Y503005I-293J-272D01*
G02X45515Y505748I-1452J1378D01*
G37*
G36*
G01X58175Y255329D02*
G02X56785Y255306I-675J-1229D01*
G03X56753Y256011I-204J344D01*
G02X58183Y256034I692J1445D01*
G03X58175Y255329I184J-355D01*
G37*
G36*
G01X108874Y392919D02*
G03X108274I-300J-265D01*
G02Y394777I-1050J929D01*
G03X108874I300J265D01*
G02Y392919I1050J-929D01*
G37*
G36*
G01X118570Y384194D02*
G02X116059Y379642I59J-3001D01*
G02X115807Y385639I-59J3001D01*
G02X118364Y384493I1256J-622D01*
G02X118570Y384194I-2364J-1849D01*
G37*
G36*
G01X124461Y379637D02*
G03X124474Y380166I-293J272D01*
G02X124492Y382120I1150J966D01*
G03Y382646I-302J263D01*
G02X126756I1132J987D01*
G03Y382120I302J-263D01*
G02X126726Y380112I-1132J-987D01*
G03X126713Y379583I293J-272D01*
G02X126837Y379411I-1153J-962D01*
G03X127182Y379421I170J106D01*
G02X127368Y377713I1318J-721D01*
G03X126750Y377696I-302J-262D01*
G02X124461Y379637I-1187J920D01*
G37*
G36*
G01X121407Y373181D02*
G03X121446Y373762I-254J309D01*
G02X123366Y373635I1027J954D01*
G03X123327Y373054I254J-309D01*
G02X121407Y373181I-1027J-954D01*
G37*
G36*
G01X127135Y345549D02*
G03X126602Y345531I-256J-307D01*
G02X124461Y347637I-1039J1085D01*
G03X124474Y348166I-293J272D01*
G02X124492Y350120I1150J966D01*
G03Y350646I-302J263D01*
G02X126756I1132J987D01*
G03Y350120I302J-263D01*
G02X126608Y347998I-1132J-987D01*
G03X126600Y347702I131J-152D01*
G02X126649Y347653I-1037J-1086D01*
G03X126947Y347663I145J138D01*
G02X127135Y345549I1153J-963D01*
G37*
G36*
G01X114446Y347320D02*
G03X114504Y348041I-142J374D01*
G02X115807Y353639I1496J2602D01*
G02X118364Y352493I1256J-622D01*
G02X118723Y351907I-2363J-1851D01*
G02X118627Y346054I-715J-2916D01*
G03X118333Y345527I83J-392D01*
G02X118344Y343528I-2825J-1015D01*
G03X118795Y343004I378J-131D01*
G02X118511Y340331I255J-1379D01*
G03X118253Y340231I-77J-185D01*
G02X112923Y342986I-2717J1278D01*
G02X114446Y347320I2585J1526D01*
G37*
G36*
G01X127234Y313650D02*
G03X126679Y313611I-257J-306D01*
G02X124461Y315637I-1116J1005D01*
G03X124474Y316166I-293J272D01*
G02X124492Y318120I1150J966D01*
G03Y318646I-302J263D01*
G02X126756I1132J987D01*
G03Y318120I302J-263D01*
G02X126608Y315998I-1132J-987D01*
G03X126600Y315702I131J-152D01*
G02X126661Y315641I-1031J-1092D01*
G03X126971Y315663I146J137D01*
G02X127234Y313650I1229J-863D01*
G37*
G36*
G01X122105Y308776D02*
G03X121926Y309351I-341J209D01*
G02X123689Y309901I567J1282D01*
G03X123868Y309326I341J-209D01*
G02X122105Y308776I-567J-1282D01*
G37*
G36*
G01X114446Y315320D02*
G03X114504Y316041I-142J374D01*
G02X115807Y321639I1496J2602D01*
G02X118364Y320493I1256J-622D01*
G02X118723Y319907I-2363J-1851D01*
G02X118627Y314054I-715J-2916D01*
G03X118333Y313527I83J-392D01*
G02X118121Y311034I-2825J-1015D01*
G02X112923Y310986I-2585J-1526D01*
G02X114446Y315320I2585J1526D01*
G37*
G36*
G01X127152Y281524D02*
G03X126598Y281527I-279J-287D01*
G02X124461Y283637I-1035J1089D01*
G03X124474Y284166I-293J272D01*
G02X124492Y286120I1150J966D01*
G03Y286646I-302J263D01*
G02X126756I1132J987D01*
G03Y286120I302J-263D01*
G02X126726Y284112I-1132J-987D01*
G03X126713Y283583I293J-272D01*
G02X126732Y283559I-1168J-944D01*
G03X127042Y283557I156J125D01*
G02X127152Y281524I1158J-957D01*
G37*
G36*
G01X114446Y283320D02*
G03X114504Y284041I-142J374D01*
G02X115807Y289639I1496J2602D01*
G02X118364Y288493I1256J-622D01*
G02X118723Y287907I-2363J-1851D01*
G02X118627Y282054I-715J-2916D01*
G03X118333Y281527I83J-392D01*
G02X118121Y279034I-2825J-1015D01*
G02X112923Y278986I-2585J-1526D01*
G02X114446Y283320I2585J1526D01*
G37*
G36*
G01X127193Y249585D02*
G03X126639Y249568I-268J-297D01*
G02X124461Y251637I-1076J1048D01*
G03X124474Y252166I-293J272D01*
G02X124492Y254120I1150J966D01*
G03Y254646I-302J263D01*
G02X126756I1132J987D01*
G03Y254120I302J-263D01*
G02X126608Y251998I-1132J-987D01*
G03X126600Y251702I131J-152D01*
G02X126696Y251602I-1034J-1089D01*
G03X127006Y251612I151J131D01*
G02X127193Y249585I1194J-912D01*
G37*
G36*
G01X123380Y245914D02*
G03X123517Y245349I336J-218D01*
G02X121643Y244894I-697J-1216D01*
G03X121506Y245459I-336J218D01*
G02X123380Y245914I697J1216D01*
G37*
G36*
G01X118576Y250043D02*
G03X118280Y249501I75J-393D01*
G02X118110Y246898I-2783J-1125D01*
G02X112912Y246850I-2585J-1526D01*
G02X114575Y251233I2585J1526D01*
G03X114634Y251970I-123J381D01*
G02X115807Y257639I1366J2673D01*
G02X118364Y256493I1256J-622D01*
G02X118723Y255907I-2363J-1851D01*
G02X118576Y250043I-715J-2916D01*
G37*
G36*
G01X127368Y217713D02*
G03X126750Y217696I-302J-262D01*
G02X124461Y219637I-1187J920D01*
G03X124474Y220166I-293J272D01*
G02X124492Y222120I1150J966D01*
G03Y222646I-302J263D01*
G02X126756I1132J987D01*
G03Y222120I302J-263D01*
G02X126726Y220112I-1132J-987D01*
G03X126713Y219583I293J-272D01*
G02X126837Y219411I-1153J-962D01*
G03X127182Y219421I170J106D01*
G02X127368Y217713I1318J-721D01*
G37*
G36*
G01X114889Y219449D02*
G03X115183Y219976I-83J392D01*
G02X115116Y220186I2824J1017D01*
G02X115798Y225898I1194J2754D01*
G02X118452Y225043I1282J-568D01*
G02X119202Y223745I-2142J-2103D01*
G02X118627Y218054I-1194J-2754D01*
G03X118333Y217527I83J-392D01*
G02X118121Y215034I-2825J-1015D01*
G02X112923Y214986I-2585J-1526D01*
G02X114889Y219449I2585J1526D01*
G37*
G36*
G01X128750Y371148D02*
G02X128552Y372417I-1330J442D01*
G03X129255Y372527I323J236D01*
G02X129453Y371258I1330J-442D01*
G03X128750Y371148I-323J-236D01*
G37*
G36*
G01X113766Y367078D02*
G02X112134Y367622I-1166J-778D01*
G03X112334Y368222I-133J378D01*
G02X113966Y367678I1166J778D01*
G03X113766Y367078I133J-378D01*
G37*
G36*
G01X128370Y338700D02*
G02X127731Y340196I-1370J299D01*
G03X128330Y340452I208J341D01*
G02X128969Y338956I1370J-299D01*
G03X128370Y338700I-208J-341D01*
G37*
G36*
G01X128755Y306876D02*
G02X128442Y308539I-1255J625D01*
G03X129069Y308657I269J296D01*
G02X129382Y306994I1255J-625D01*
G03X128755Y306876I-269J-296D01*
G37*
G36*
G01X123666Y277219D02*
G02X121957Y276796I-592J-1271D01*
G03X121808Y277400I-318J242D01*
G02X123517Y277823I592J1271D01*
G03X123666Y277219I318J-242D01*
G37*
G36*
G01X128755Y274876D02*
G02X128442Y276539I-1255J625D01*
G03X129069Y276657I269J296D01*
G02X129382Y274994I1255J-625D01*
G03X128755Y274876I-269J-296D01*
G37*
G36*
G01Y242876D02*
G02X128442Y244539I-1255J625D01*
G03X129069Y244657I269J296D01*
G02X129382Y242994I1255J-625D01*
G03X128755Y242876I-269J-296D01*
G37*
G36*
G01X128822Y210945D02*
G02X126588Y211074I-1068J908D01*
G03X125954Y211114I-332J-222D01*
G02X123725Y211260I-1059J919D01*
G02X125461Y213316I-1183J2759D01*
G02X126061Y212812I-566J-1283D01*
G03X126695Y212772I332J222D01*
G02X128685Y212901I1059J-919D01*
G03X129256Y212941I266J299D01*
G02X129393Y210985I1068J-908D01*
G03X128822Y210945I-266J-299D01*
G37*
G36*
G01X193564Y331470D02*
G03X193010I-277J-288D01*
G02Y333490I-973J1010D01*
G03X193564I277J288D01*
G02X195510I973J-1010D01*
G03X196064I277J288D01*
G02Y331470I973J-1010D01*
G03X195510I-277J-288D01*
G02X193564I-973J1010D01*
G37*
G36*
G01X376998Y330627D02*
G03X377585Y330641I287J279D01*
G02X379464Y328129I1200J-1061D01*
G03X379286Y327569I170J-362D01*
G02X376816Y325592I-1392J-792D01*
G03X376282Y325596I-269J-296D01*
G02X374111Y325645I-1059J1202D01*
G03X373545Y325635I-278J-288D01*
G02X371263Y325609I-1154J1111D01*
G03X370735Y325640I-282J-284D01*
G02X368626Y325759I-987J1262D01*
G03X368101Y325790I-280J-286D01*
G02X368083Y325776I-992J1257D01*
G03X368050Y325488I120J-160D01*
G02X365736Y325637I-1228J-1029D01*
G03X365796Y326156I-271J294D01*
G02X368243Y328200I1325J901D01*
G03X368768Y328169I280J286D01*
G02X370876Y328039I980J-1267D01*
G03X371404Y328008I282J284D01*
G02X373503Y327899I987J-1262D01*
G03X374069Y327909I278J288D01*
G02X374351Y328142I1155J-1110D01*
G03X374476Y328684I-217J336D01*
G02X376998Y330627I1371J828D01*
G37*
G36*
G01X434694Y323112D02*
G03X434094I-300J-265D01*
G02Y325234I-1200J1061D01*
G03X434694I300J265D01*
G02Y323112I1200J-1061D01*
G37*
G36*
G01X427494D02*
G03X426894I-300J-265D01*
G02Y325234I-1200J1061D01*
G03X427494I300J265D01*
G02Y323112I1200J-1061D01*
G37*
G36*
G01X447675Y322713D02*
G03X447155Y322704I-255J-308D01*
G02X447113Y325140I-1061J1200D01*
G03X447633Y325149I255J308D01*
G02X449481Y325344I1061J-1200D01*
G03X449995Y325450I196J349D01*
G02X450480Y323081I1272J-974D01*
G03X449966Y322975I-196J-349D01*
G02X447675Y322713I-1272J974D01*
G37*
G36*
G01X367579Y311230D02*
G03X367069Y311072I-167J-363D01*
G02X366528Y313260I-1376J821D01*
G03X367053Y313358I208J342D01*
G02X369157Y313494I1112J-854D01*
G03X369709Y313480I283J283D01*
G02X371644Y313430I941J-1039D01*
G03X372201Y313421I283J282D01*
G02X374123I961J-1021D01*
G03X374680Y313430I274J291D01*
G02X376640Y313458I994J-989D01*
G03X377190I275J290D01*
G02Y311424I966J-1017D01*
G03X376640I-275J-290D01*
G02X374713Y311420I-966J1017D01*
G03X374156Y311411I-274J-291D01*
G02X372168I-994J989D01*
G03X371611Y311420I-283J-282D01*
G02X369658Y311451I-961J1021D01*
G03X369106Y311465I-283J-283D01*
G02X367579Y311230I-941J1039D01*
G37*
G36*
G01X455158Y309368D02*
G03Y308814I288J-277D01*
G02X452981Y307064I-1010J-972D01*
G03X452426Y307175I-333J-222D01*
G02X450266Y308104I-778J1166D01*
G03X449789Y308428I-394J-67D01*
G02X448527Y308790I-289J1372D01*
G03X447973I-277J-288D01*
G02Y310810I-973J1010D01*
G03X448527I277J288D01*
G02X450882Y310037I973J-1010D01*
G03X451359Y309713I394J67D01*
G02X452218Y309622I289J-1372D01*
G03X452773Y310066I163J365D01*
G02X455158Y309368I1375J275D01*
G37*
G36*
G01X193564Y298740D02*
G03X193010I-277J-288D01*
G02Y300760I-973J1010D01*
G03X193564I277J288D01*
G02X195510I973J-1010D01*
G03X196064I277J288D01*
G02Y298740I973J-1010D01*
G03X195510I-277J-288D01*
G02X193564I-973J1010D01*
G37*
G36*
G01X405894Y294843D02*
G03X405294I-300J-265D01*
G02Y296965I-1200J1061D01*
G03X405894I300J265D01*
G02Y294843I1200J-1061D01*
G37*
G36*
G01X398694D02*
G03X398094I-300J-265D01*
G02Y296965I-1200J1061D01*
G03X398694I300J265D01*
G02Y294843I1200J-1061D01*
G37*
G36*
G01X391494D02*
G03X390894I-300J-265D01*
G02Y296965I-1200J1061D01*
G03X391494I300J265D01*
G02Y294843I1200J-1061D01*
G37*
G36*
G01X384294D02*
G03X383694I-300J-265D01*
G02Y296965I-1200J1061D01*
G03X384294I300J265D01*
G02Y294843I1200J-1061D01*
G37*
G36*
G01X377094D02*
G03X376494I-300J-265D01*
G02Y296965I-1200J1061D01*
G03X377094I300J265D01*
G02Y294843I1200J-1061D01*
G37*
G36*
G01X369894D02*
G03X369294I-300J-265D01*
G02Y296965I-1200J1061D01*
G03X369894I300J265D01*
G02Y294843I1200J-1061D01*
G37*
G36*
G01X434727Y292127D02*
G03X434061I-333J-222D01*
G02X431986Y293972I-1167J777D01*
G03X431960Y294602I-259J305D01*
G02X434094Y296965I934J1302D01*
G03X434694I300J265D01*
G02X436828Y294602I1200J-1061D01*
G03X436802Y293972I233J-325D01*
G02X434727Y292127I-908J-1068D01*
G37*
G36*
G01X427527D02*
G03X426861I-333J-222D01*
G02X424786Y293972I-1167J777D01*
G03X424760Y294602I-259J305D01*
G02X426894Y296965I934J1302D01*
G03X427494I300J265D01*
G02X429628Y294602I1200J-1061D01*
G03X429602Y293972I233J-325D01*
G02X427527Y292127I-908J-1068D01*
G37*
G36*
G01X420327D02*
G03X419661I-333J-222D01*
G02X417586Y293972I-1167J777D01*
G03X417560Y294602I-259J305D01*
G02X419694Y296965I934J1302D01*
G03X420294I300J265D01*
G02X422428Y294602I1200J-1061D01*
G03X422402Y293972I233J-325D01*
G02X420327Y292127I-908J-1068D01*
G37*
G36*
G01X413127D02*
G03X412461I-333J-222D01*
G02X410386Y293972I-1167J777D01*
G03X410360Y294602I-259J305D01*
G02X412494Y296965I934J1302D01*
G03X413094I300J265D01*
G02X415228Y294602I1200J-1061D01*
G03X415202Y293972I233J-325D01*
G02X413127Y292127I-908J-1068D01*
G37*
G36*
G01X448798Y277912D02*
G03X448198I-300J-265D01*
G02Y279770I-1050J929D01*
G03X448798I300J265D01*
G02Y277912I1050J-929D01*
G37*
G36*
G01X434704Y277866D02*
G03X434104Y277860I-297J-268D01*
G02X434084Y279982I-1210J1050D01*
G03X434684Y279988I297J268D01*
G02X434704Y277866I1210J-1050D01*
G37*
G36*
G01X427494Y277849D02*
G03X426894I-300J-265D01*
G02Y279971I-1200J1061D01*
G03X427494I300J265D01*
G02Y277849I1200J-1061D01*
G37*
G36*
G01X420335Y277870D02*
G03X419735Y277863I-297J-268D01*
G02X419711Y279984I-1212J1047D01*
G03X420311Y279991I297J268D01*
G02X420335Y277870I1212J-1047D01*
G37*
G36*
G01X413039Y277813D02*
G03X412456I-291J-273D01*
G02Y280007I-1168J1097D01*
G03X413039I291J273D01*
G02Y277813I1168J-1097D01*
G37*
G36*
G01X441894Y277843D02*
G03X441294I-300J-265D01*
G02Y279965I-1200J1061D01*
G03X441894I300J265D01*
G02Y277843I1200J-1061D01*
G37*
G36*
G01X391494D02*
G03X390894I-300J-265D01*
G02Y279965I-1200J1061D01*
G03X391494I300J265D01*
G02Y277843I1200J-1061D01*
G37*
G36*
G01X377094D02*
G03X376494I-300J-265D01*
G02Y279965I-1200J1061D01*
G03X377094I300J265D01*
G02Y277843I1200J-1061D01*
G37*
G36*
G01X369894D02*
G03X369294I-300J-265D01*
G02Y279965I-1200J1061D01*
G03X369894I300J265D01*
G02Y277843I1200J-1061D01*
G37*
G36*
G01X452389Y274629D02*
G03X451811I-289J-277D01*
G02Y276571I-1011J971D01*
G03X452389I289J277D01*
G02Y274629I1011J-971D01*
G37*
G36*
G01X193564Y269740D02*
G03X193010I-277J-288D01*
G02Y271760I-973J1010D01*
G03X193564I277J288D01*
G02X195510I973J-1010D01*
G03X196064I277J288D01*
G02Y269740I973J-1010D01*
G03X195510I-277J-288D01*
G02X193564I-973J1010D01*
G37*
G36*
G01X381946Y272676D02*
G03Y272076I265J-300D01*
G02X379824I-1061J-1200D01*
G03Y272676I-265J300D01*
G02X381946I1061J1200D01*
G37*
G36*
G01X198627Y239616D02*
G03Y239062I288J-277D01*
G02X196607I-1010J-973D01*
G03Y239616I-288J277D01*
G02Y241562I1010J973D01*
G03Y242116I-288J277D01*
G02X198627I1010J973D01*
G03Y241562I288J-277D01*
G02Y239616I-1010J-973D01*
G37*
G36*
G01X192547Y239516D02*
G03Y238962I288J-277D01*
G02X190527I-1010J-973D01*
G03Y239516I-288J277D01*
G02Y241462I1010J973D01*
G03Y242016I-288J277D01*
G02X192547I1010J973D01*
G03Y241462I288J-277D01*
G02Y239516I-1010J-973D01*
G37*
G36*
G01X386654Y323068D02*
G02Y325278I-1160J1105D01*
G03X387234I290J275D01*
G02X389494Y325337I1160J-1105D01*
G03X390044I275J291D01*
G02X392244I1100J-1164D01*
G03X392794I275J291D01*
G02X395094Y325234I1100J-1164D01*
G03X395694I300J265D01*
G02X398094I1200J-1061D01*
G03X398694I300J265D01*
G02X401094I1200J-1061D01*
G03X401694I300J265D01*
G02X404094I1200J-1061D01*
G03X404694I300J265D01*
G02X407094I1200J-1061D01*
G03X407694I300J265D01*
G02X410094I1200J-1061D01*
G03X410694I300J265D01*
G02X413094I1200J-1061D01*
G03X413694I300J265D01*
G02X416334Y324874I1200J-1061D01*
G03X417054I360J175D01*
G02X419694Y325234I1440J-701D01*
G03X420294I300J265D01*
G02Y323112I1200J-1061D01*
G03X419694I-300J-265D01*
G02X417054Y323472I-1200J1061D01*
G03X416334I-360J-175D01*
G02X413694Y323112I-1440J701D01*
G03X413094I-300J-265D01*
G02X410694I-1200J1061D01*
G03X410094I-300J-265D01*
G02X407694I-1200J1061D01*
G03X407094I-300J-265D01*
G02X404694I-1200J1061D01*
G03X404094I-300J-265D01*
G02X401694I-1200J1061D01*
G03X401094I-300J-265D01*
G02X398694I-1200J1061D01*
G03X398094I-300J-265D01*
G02X395694I-1200J1061D01*
G03X395094I-300J-265D01*
G02X392794Y323009I-1200J1061D01*
G03X392244I-275J-291D01*
G02X390044I-1100J1164D01*
G03X389494I-275J-291D01*
G02X387234Y323068I-1100J1164D01*
G03X386654I-290J-275D01*
G37*
G36*
G01X434061Y309127D02*
G02Y310681I-1167J777D01*
G03X434727I333J222D01*
G02Y309127I1167J-777D01*
G03X434061I-333J-222D01*
G37*
G36*
G01X426861D02*
G02Y310681I-1167J777D01*
G03X427527I333J222D01*
G02Y309127I1167J-777D01*
G03X426861I-333J-222D01*
G37*
G36*
G01X419661D02*
G02Y310681I-1167J777D01*
G03X420327I333J222D01*
G02Y309127I1167J-777D01*
G03X419661I-333J-222D01*
G37*
G36*
G01X412461D02*
G02Y310681I-1167J777D01*
G03X413127I333J222D01*
G02Y309127I1167J-777D01*
G03X412461I-333J-222D01*
G37*
G36*
G01X441282Y309097D02*
G02Y310585I-1188J744D01*
G03X441960I339J213D01*
G02Y309097I1188J-744D01*
G03X441282I-339J-213D01*
G37*
G36*
G01X455207Y293288D02*
G02X453794Y290967I19J-1602D01*
G03X453085Y290978I-357J-179D01*
G02X450200Y291115I-1410J761D01*
G03X449695Y291335I-368J-156D01*
G02X447972Y291753I-547J1506D01*
G03X447385Y291754I-294J-271D01*
G02X444848Y291998I-1176J1088D01*
G03X444194Y292035I-340J-211D01*
G02X441927Y292127I-1100J869D01*
G03X441261I-333J-222D01*
G02X439186Y293972I-1167J777D01*
G03X439160Y294602I-259J305D01*
G02X441294Y296965I934J1302D01*
G03X441894I300J265D01*
G02X444427Y296792I1200J-1061D01*
G03X445085Y296779I334J221D01*
G02X447371Y294580I1299J-938D01*
G03X447336Y293981I246J-315D01*
G02X447385Y293930I-1131J-1135D01*
G03X447972Y293929I294J271D01*
G02X450623Y293465I1176J-1088D01*
G03X451128Y293245I368J156D01*
G02X451614Y293340I547J-1506D01*
G03X451999Y293728I-15J400D01*
G02X452009Y293862I1401J-37D01*
G03X451653Y294310I-397J50D01*
G02X453079Y296889I163J1594D01*
G03X453700Y296877I315J246D01*
G02X455139Y294254I1222J-1036D01*
G03X454796Y293819I55J-396D01*
G02X454802Y293687I-1396J-130D01*
G03X455207Y293288I400J1D01*
G37*
G36*
G01X405294Y277849D02*
G02X402792Y277977I-1200J1061D01*
G03X402142Y277978I-325J-233D01*
G02X402144Y279847I-1300J936D01*
G03X402794Y279846I325J233D01*
G02X405294Y279971I1300J-936D01*
G03X405894I300J265D01*
G02Y277849I1200J-1061D01*
G03X405294I-300J-265D01*
G37*
G36*
G01X384661Y279438D02*
G02X384467Y277861I1284J-958D01*
G03X383778Y277946I-369J-154D01*
G02X383972Y279523I-1284J958D01*
G03X384661Y279438I369J154D01*
G37*
G36*
G01X449786Y267746D02*
G02X448489Y267587I-498J-1311D01*
G03X448402Y268289I-229J328D01*
G02X449699Y268448I498J1311D01*
G03X449786Y267746I229J-328D01*
G37*
G36*
G01X445305Y265476D02*
G02X443931Y265325I-554J-1288D01*
G03X443855Y266017I-234J325D01*
G02X445229Y266168I554J1288D01*
G03X445305Y265476I234J-325D01*
G37*
G36*
G01X440857Y264577D02*
G02X439243Y265001I-1093J-878D01*
G03X439407Y265622I-148J371D01*
G02X441021Y265198I1093J878D01*
G03X440857Y264577I148J-371D01*
G37*
G36*
G01X364291Y16081D02*
G03X363703Y16074I-291J-275D01*
G02X363682Y17975I-1041J939D01*
G03X364270Y17982I291J275D01*
G02X366322Y18013I1040J-940D01*
G03X366900I289J277D01*
G02Y16071I1011J-971D01*
G03X366322I-289J-277D01*
G02X364291Y16081I-1011J971D01*
G37*
G36*
G01X376959Y5723D02*
G02Y7277I-1167J777D01*
G03X377625I333J222D01*
G02Y5723I1167J-777D01*
G03X376959I-333J-222D01*
G37*
G36*
G01X375160Y594586D02*
G02X375066Y592831I1044J-936D01*
G03X374444Y592864I-324J-234D01*
G02X374538Y594619I-1044J936D01*
G03X375160Y594586I324J234D01*
G37*
G36*
G01X422547Y248802D02*
X424698Y253996D01*
Y254476D01*
X425712Y257129D01*
X428832Y260250D01*
Y263761D01*
G02X430836Y263869I949J1032D01*
G01Y259420D01*
X427430Y256015D01*
X426702Y254106D01*
Y253598D01*
X424219Y247605D01*
X423998Y247384D01*
X423993Y247308D01*
G02X422430Y248788I-1399J88D01*
G01X422547Y248802D01*
G37*
G36*
G01X844127Y330490D02*
G03X843573I-277J-288D01*
G02Y332510I-973J1010D01*
G03X844127I277J288D01*
G02X846073I973J-1010D01*
G03X846627I277J288D01*
G02Y330490I973J-1010D01*
G03X846073I-277J-288D01*
G02X844127I-973J1010D01*
G37*
G36*
G01X1017937Y325288D02*
G03X1017717Y324783I156J-368D01*
G02X1015855Y325596I-1318J-479D01*
G03X1016075Y326101I-156J368D01*
G02X1018366Y327590I1318J480D01*
G03X1018920I277J288D01*
G02X1020866I973J-1010D01*
G03X1021420I277J288D01*
G02X1023366I973J-1010D01*
G03X1023920I277J288D01*
G02X1024287Y327844I971J-1011D01*
G03X1024479Y328371I-172J361D01*
G02X1026567Y330094I1276J580D01*
G03X1027153Y330233I232J326D01*
G02X1028642Y328200I1240J-653D01*
G03X1028420Y327534I71J-394D01*
G02X1026420Y325570I-1027J-955D01*
G03X1025866I-277J-288D01*
G02X1023920I-973J1010D01*
G03X1023366I-277J-288D01*
G02X1021420I-973J1010D01*
G03X1020866I-277J-288D01*
G02X1018920I-973J1010D01*
G03X1018366I-277J-288D01*
G02X1017937Y325288I-972J1011D01*
G37*
G36*
G01X1077820Y323113D02*
G03X1077220I-300J-265D01*
G02Y325235I-1200J1061D01*
G03X1077820I300J265D01*
G02Y323113I1200J-1061D01*
G37*
G36*
G01X1017207Y311236D02*
G03X1016654Y311109I-213J-338D01*
G02X1016286Y313212I-1361J846D01*
G03X1016850Y313281I248J314D01*
G02X1018914Y313445I1107J-860D01*
G03X1019458Y313442I274J292D01*
G02X1021395Y313399I946J-1034D01*
G03X1021953Y313391I283J283D01*
G02X1023893Y313377I963J-1019D01*
G03X1024453Y313379I279J286D01*
G02X1026438Y313364I985J-998D01*
G03X1027015Y313371I285J281D01*
G02X1027039Y311431I1024J-957D01*
G03X1026462Y311424I-285J-281D01*
G02X1024460Y311376I-1025J957D01*
G03X1023900Y311374I-279J-286D01*
G02X1021924Y311381I-984J998D01*
G03X1021366Y311389I-283J-283D01*
G02X1019447Y311384I-962J1019D01*
G03X1018903Y311387I-274J-292D01*
G02X1017207Y311236I-947J1034D01*
G37*
G36*
G01X844127Y298890D02*
G03X843573I-277J-288D01*
G02Y300910I-973J1010D01*
G03X844127I277J288D01*
G02X846073I973J-1010D01*
G03X846627I277J288D01*
G02Y298890I973J-1010D01*
G03X846073I-277J-288D01*
G02X844127I-973J1010D01*
G37*
G36*
G01X1055367Y294798D02*
G03X1054767I-300J-265D01*
G02Y296920I-1200J1061D01*
G03X1055367I300J265D01*
G02Y294798I1200J-1061D01*
G37*
G36*
G01X1048167D02*
G03X1047567I-300J-265D01*
G02Y296920I-1200J1061D01*
G03X1048167I300J265D01*
G02Y294798I1200J-1061D01*
G37*
G36*
G01X1040967D02*
G03X1040367I-300J-265D01*
G02Y296920I-1200J1061D01*
G03X1040967I300J265D01*
G02Y294798I1200J-1061D01*
G37*
G36*
G01X1033767D02*
G03X1033167I-300J-265D01*
G02Y296920I-1200J1061D01*
G03X1033767I300J265D01*
G02Y294798I1200J-1061D01*
G37*
G36*
G01X1026567D02*
G03X1025967I-300J-265D01*
G02Y296920I-1200J1061D01*
G03X1026567I300J265D01*
G02Y294798I1200J-1061D01*
G37*
G36*
G01X1019367D02*
G03X1018767I-300J-265D01*
G02Y296920I-1200J1061D01*
G03X1019367I300J265D01*
G02Y294798I1200J-1061D01*
G37*
G36*
G01X1084335Y292127D02*
G03X1083669I-333J-222D01*
G02X1081527Y293911I-1167J777D01*
G03X1081472Y294530I-278J287D01*
G02X1083567Y296920I895J1329D01*
G03X1084167I300J265D01*
G02X1086379Y294617I1200J-1061D01*
G03X1086381Y293996I253J-310D01*
G02X1084335Y292127I-879J-1092D01*
G37*
G36*
G01X1077135D02*
G03X1076469I-333J-222D01*
G02X1074327Y293911I-1167J777D01*
G03X1074272Y294530I-278J287D01*
G02X1076367Y296920I895J1329D01*
G03X1076967I300J265D01*
G02X1079179Y294617I1200J-1061D01*
G03X1079181Y293996I253J-310D01*
G02X1077135Y292127I-879J-1092D01*
G37*
G36*
G01X1069935D02*
G03X1069269I-333J-222D01*
G02X1067127Y293911I-1167J777D01*
G03X1067072Y294530I-278J287D01*
G02X1069167Y296920I895J1329D01*
G03X1069767I300J265D01*
G02X1071979Y294617I1200J-1061D01*
G03X1071981Y293996I253J-310D01*
G02X1069935Y292127I-879J-1092D01*
G37*
G36*
G01X1062735D02*
G03X1062069I-333J-222D01*
G02X1059927Y293911I-1167J777D01*
G03X1059872Y294530I-278J287D01*
G02X1061967Y296920I895J1329D01*
G03X1062567I300J265D01*
G02X1064779Y294617I1200J-1061D01*
G03X1064781Y293996I253J-310D01*
G02X1062735Y292127I-879J-1092D01*
G37*
G36*
G01X1097703Y279975D02*
G03X1098242I269J295D01*
G02X1098239Y277904I944J-1037D01*
G03X1097700I-269J-295D01*
G02X1097703Y279975I-944J1037D01*
G37*
G36*
G01X1084242Y277941D02*
G03X1083606I-318J-242D01*
G02Y279879I-1276J969D01*
G03X1084242I318J242D01*
G02Y277941I1276J-969D01*
G37*
G36*
G01X1077102Y277849D02*
G03X1076502I-300J-265D01*
G02Y279971I-1200J1061D01*
G03X1077102I300J265D01*
G02Y277849I1200J-1061D01*
G37*
G36*
G01X1069668Y277918D02*
G03X1069041I-314J-248D01*
G02Y279902I-1258J992D01*
G03X1069668I314J248D01*
G02Y277918I1258J-992D01*
G37*
G36*
G01X1062574Y277725D02*
G03X1062036I-269J-296D01*
G02Y280095I-1078J1185D01*
G03X1062574I269J296D01*
G02Y277725I1078J-1185D01*
G37*
G36*
G01X1026702Y277843D02*
G03X1026102I-300J-265D01*
G02Y279965I-1200J1061D01*
G03X1026702I300J265D01*
G02Y277843I1200J-1061D01*
G37*
G36*
G01X1019502D02*
G03X1018902I-300J-265D01*
G02Y279965I-1200J1061D01*
G03X1019502I300J265D01*
G02Y277843I1200J-1061D01*
G37*
G36*
G01X1102063Y273444D02*
G03X1101589Y273107I-78J-392D01*
G02X1100473Y274675I-1389J193D01*
G03X1100947Y275012I78J392D01*
G02X1102063Y273444I1389J-193D01*
G37*
G36*
G01X1031550Y272689D02*
G03Y272089I265J-300D01*
G02X1029428I-1061J-1200D01*
G03Y272689I-265J300D01*
G02X1031550I1061J1200D01*
G37*
G36*
G01X844127Y267190D02*
G03X843573I-277J-288D01*
G02Y269210I-973J1010D01*
G03X844127I277J288D01*
G02X846073I973J-1010D01*
G03X846627I277J288D01*
G02Y267190I973J-1010D01*
G03X846073I-277J-288D01*
G02X844127I-973J1010D01*
G37*
G36*
G01X848610Y239927D02*
G03Y239373I288J-277D01*
G02X846590I-1010J-973D01*
G03Y239927I-288J277D01*
G02Y241873I1010J973D01*
G03Y242427I-288J277D01*
G02X848610I1010J973D01*
G03Y241873I288J-277D01*
G02Y239927I-1010J-973D01*
G37*
G36*
G01X842410Y239827D02*
G03Y239273I288J-277D01*
G02X840390I-1010J-973D01*
G03Y239827I-288J277D01*
G02Y241773I1010J973D01*
G03Y242327I-288J277D01*
G02X842410I1010J973D01*
G03Y241773I288J-277D01*
G02Y239827I-1010J-973D01*
G37*
G36*
G01X1036980Y323069D02*
G02Y325279I-1160J1105D01*
G03X1037560I290J275D01*
G02X1039820Y325338I1160J-1105D01*
G03X1040370I275J291D01*
G02X1042570I1100J-1164D01*
G03X1043120I275J291D01*
G02X1045420Y325235I1100J-1164D01*
G03X1046020I300J265D01*
G02X1048420I1200J-1061D01*
G03X1049020I300J265D01*
G02X1051420I1200J-1061D01*
G03X1052020I300J265D01*
G02X1054420I1200J-1061D01*
G03X1055020I300J265D01*
G02X1057420I1200J-1061D01*
G03X1058020I300J265D01*
G02X1060420I1200J-1061D01*
G03X1061020I300J265D01*
G02X1063420I1200J-1061D01*
G03X1064020I300J265D01*
G02X1066660Y324875I1200J-1061D01*
G03X1067380I360J175D01*
G02X1070020Y325235I1440J-701D01*
G03X1070620I300J265D01*
G02Y323113I1200J-1061D01*
G03X1070020I-300J-265D01*
G02X1067380Y323473I-1200J1061D01*
G03X1066660I-360J-175D01*
G02X1064020Y323113I-1440J701D01*
G03X1063420I-300J-265D01*
G02X1061020I-1200J1061D01*
G03X1060420I-300J-265D01*
G02X1058020I-1200J1061D01*
G03X1057420I-300J-265D01*
G02X1055020I-1200J1061D01*
G03X1054420I-300J-265D01*
G02X1052020I-1200J1061D01*
G03X1051420I-300J-265D01*
G02X1049020I-1200J1061D01*
G03X1048420I-300J-265D01*
G02X1046020I-1200J1061D01*
G03X1045420I-300J-265D01*
G02X1043120Y323010I-1200J1061D01*
G03X1042570I-275J-291D01*
G02X1040370I-1100J1164D01*
G03X1039820I-275J-291D01*
G02X1037560Y323069I-1100J1164D01*
G03X1036980I-290J-275D01*
G37*
G36*
G01X1083669Y309127D02*
G02Y310681I-1167J777D01*
G03X1084335I333J222D01*
G02Y309127I1167J-777D01*
G03X1083669I-333J-222D01*
G37*
G36*
G01X1076469D02*
G02Y310681I-1167J777D01*
G03X1077135I333J222D01*
G02Y309127I1167J-777D01*
G03X1076469I-333J-222D01*
G37*
G36*
G01X1069269D02*
G02Y310681I-1167J777D01*
G03X1069935I333J222D01*
G02Y309127I1167J-777D01*
G03X1069269I-333J-222D01*
G37*
G36*
G01X1062069D02*
G02Y310681I-1167J777D01*
G03X1062735I333J222D01*
G02Y309127I1167J-777D01*
G03X1062069I-333J-222D01*
G37*
G36*
G01X1054717Y277918D02*
G02X1052004Y278239I-1258J992D01*
G03X1051287Y278257I-363J-168D01*
G02X1051322Y279670I-1420J742D01*
G03X1052039Y279652I363J168D01*
G02X1054717Y279902I1420J-742D01*
G03X1055344I314J248D01*
G02Y277918I1258J-992D01*
G03X1054717I-314J-248D01*
G37*
G36*
G01X1037239Y278042D02*
G02X1037181Y279611I-1425J733D01*
G03X1037877Y279637I341J209D01*
G02X1040502Y279965I1425J-733D01*
G03X1041102I300J265D01*
G02Y277843I1200J-1061D01*
G03X1040502I-300J-265D01*
G02X1037935Y278068I-1200J1061D01*
G03X1037239Y278042I-341J-209D01*
G37*
G36*
G01X1096538Y267024D02*
G02X1094862I-838J-1124D01*
G03Y267666I-239J321D01*
G02X1096538I838J1124D01*
G03Y267024I239J-321D01*
G37*
G36*
G01X1090267Y263723D02*
G02X1088053Y265432I-1167J776D01*
G03X1088031Y265987I-299J266D01*
G02X1090047Y266068I969J1013D01*
G03X1090069Y265513I299J-266D01*
G02X1090267Y265277I-969J-1014D01*
G03X1090933I333J222D01*
G02X1091255Y265619I1167J-777D01*
G03X1091299Y266218I-241J319D01*
G02X1093145Y266081I1001J982D01*
G03X1093101Y265482I241J-319D01*
G02X1090933Y263723I-1001J-982D01*
G03X1090267I-333J-222D01*
G37*
G36*
G01X1031207Y24330D02*
G02X1029654Y24304I-757J-1180D01*
G03X1029643Y24970I-227J329D01*
G02X1031196Y24996I757J1180D01*
G03X1031207Y24330I227J-329D01*
G37*
G36*
G01X1015360Y612989D02*
G03X1015938Y612881I339J213D01*
G02X1015591Y611012I840J-1123D01*
G03X1015013Y611120I-339J-213D01*
G02X1015360Y612989I-840J1123D01*
G37*
G36*
G01X1024477Y592640D02*
G03X1023923I-277J-288D01*
G02Y594660I-973J1010D01*
G03X1024477I277J288D01*
G02Y592640I973J-1010D01*
G37*
G36*
G01X1016508Y592671D02*
G03X1015930I-289J-277D01*
G02Y594613I-1011J971D01*
G03X1016508I289J277D01*
G02Y592671I1011J-971D01*
G37*
G36*
G01X1071806Y248743D02*
X1073183Y251212D01*
X1076016Y259306D01*
X1078723Y264026D01*
X1078740Y264152D01*
X1078697Y264215D01*
G02X1080783Y263946I1162J785D01*
G01X1080726Y263896D01*
X1080659Y263374D01*
X1077846Y258470D01*
X1075017Y250388D01*
X1073556Y247768D01*
X1073572Y247694D01*
G02X1071735Y248718I-1370J-298D01*
G01X1071806Y248743D01*
G37*
G36*
G01X1248070Y129434D02*
G03X1247454Y129346I-272J-293D01*
G02X1247206Y131092I-1203J720D01*
G03X1247822Y131180I272J293D01*
G02X1248070Y129434I1203J-720D01*
G37*
G36*
G01X1253012Y127043D02*
G03X1252417Y127023I-289J-277D01*
G02X1252356Y128895I-1073J902D01*
G03X1252951Y128915I289J277D01*
G02X1253012Y127043I1073J-902D01*
G37*
G36*
G01X1255446Y106007D02*
G02X1252898Y105227I-1146J-807D01*
G03X1252383Y105617I-400J7D01*
G02X1253382Y106933I-403J1343D01*
G03X1253897Y106543I400J-7D01*
G02X1254009Y106572I407J-1342D01*
G03X1254254Y107193I-82J391D01*
G02X1255691Y106628I1147J807D01*
G03X1255446Y106007I82J-391D01*
G37*
G36*
G01X1265133Y606366D02*
G03X1265434Y605850I380J-124D01*
G02X1263824Y604910I-277J-1374D01*
G03X1263523Y605426I-380J124D01*
G02X1265133Y606366I277J1374D01*
G37*
G36*
G01X1373032Y27613D02*
G03Y27087I302J-263D01*
G02X1370768I-1132J-987D01*
G03Y27613I-302J263D01*
G02Y29587I1132J987D01*
G03Y30113I-302J263D01*
G02X1373032I1132J987D01*
G03Y29587I302J-263D01*
G02Y27613I-1132J-987D01*
G37*
G36*
G01X1382196Y27186D02*
G02X1381043Y24630I-554J-1288D01*
G02X1377988Y29746I-1843J2370D01*
G02X1382162Y27486I2962J486D01*
G02X1382196Y27186I-2962J-488D01*
G37*
G36*
G01X1368378Y4805D02*
G03X1367800I-289J-277D01*
G02Y6747I-1011J971D01*
G03X1368378I289J277D01*
G02Y4805I1011J-971D01*
G37*
G36*
G01X1382754Y-2591D02*
G02X1382952Y-4394I-2746J-1214D01*
G02X1381189Y-6565I-802J-1150D01*
G02X1377932Y-1636I-1181J2760D01*
G02X1378026Y984I2746J1213D01*
G02X1377620Y1591I2274J1960D01*
G03X1377357Y1683I-179J-90D01*
G02X1374463Y6926I-1262J2724D01*
G02X1377028Y7259I1213J704D01*
G02X1377417Y7101I-932J-2854D01*
G03X1377675Y7174I89J179D01*
G02X1382955Y4345I2544J-1594D01*
G02X1382952Y1538I-2655J-1401D01*
G02X1382754Y-2591I-2274J-1960D01*
G37*
G36*
G01X1372721Y-4411D02*
G03Y-4937I302J-263D01*
G02X1370457I-1132J-987D01*
G03Y-4411I-302J263D01*
G02X1370487Y-2403I1132J987D01*
G03X1370500Y-1874I-293J272D01*
G02X1372752Y-1928I1150J967D01*
G03X1372739Y-2457I293J-272D01*
G02X1372721Y-4411I-1150J-966D01*
G37*
G36*
G01X1370996Y395697D02*
G03X1370418I-289J-277D01*
G02Y397639I-1011J971D01*
G03X1370996I289J277D01*
G02Y395697I1011J-971D01*
G37*
G36*
G01X1375339Y386481D02*
G03Y385955I302J-263D01*
G02X1373075I-1132J-987D01*
G03Y386481I-302J263D01*
G02X1373105Y388489I1132J987D01*
G03X1373118Y389018I-293J272D01*
G02X1375370Y388964I1150J967D01*
G03X1375357Y388435I293J-272D01*
G02X1375339Y386481I-1150J-966D01*
G37*
G36*
G01X1359490Y372797D02*
G02X1357525Y372788I-978J-1005D01*
G03X1357508Y373372I-281J284D01*
G02X1358565Y376001I992J1128D01*
G03X1358922Y376610I17J399D01*
G02X1358699Y377466I1278J790D01*
G03X1358375Y377876I-399J17D01*
G02X1358605Y380853I280J1476D01*
G03X1358799Y381059I-6J200D01*
G02X1358798Y381098I1501J58D01*
G03X1358598Y381298I-200J0D01*
G02X1358362Y384283I2J1502D01*
G03X1358698Y384683I-64J395D01*
G02X1358702Y384810I1502J16D01*
G03X1358387Y385231I-399J30D01*
G02X1358422Y388176I313J1469D01*
G03X1358737Y388660I-74J393D01*
G02X1358698Y389002I1463J340D01*
G03X1358355Y389398I-400J0D01*
G02X1357436Y391872I213J1487D01*
G03Y392398I-302J263D01*
G02X1359700I1132J987D01*
G03Y391872I302J-263D01*
G02X1360061Y390723I-1132J-987D01*
G03X1360253Y390501I199J-22D01*
G02X1360356Y390494I-50J-1501D01*
G03X1360576Y390715I21J199D01*
G02X1360936Y391872I1492J170D01*
G03Y392398I-302J263D01*
G02X1363200I1132J987D01*
G03Y391872I302J-263D01*
G02X1362095Y389383I-1132J-987D01*
G03X1361702Y388987I7J-400D01*
G02X1360478Y387524I-1502J13D01*
G03X1360163Y387040I74J-393D01*
G02X1360198Y386590I-1463J-340D01*
G03X1360513Y386169I399J-30D01*
G02X1360438Y383217I-313J-1469D01*
G03X1360102Y382817I64J-395D01*
G01Y382802D01*
G03X1360302Y382602I200J0D01*
G02X1360350Y379599I-2J-1502D01*
G03X1360156Y379393I6J-200D01*
G02Y379286I-1501J-54D01*
G03X1360480Y378876I399J-17D01*
G02X1360135Y375899I-280J-1476D01*
G03X1359778Y375290I-17J-399D01*
G02X1359502Y373381I-1278J-790D01*
G03X1359490Y372797I267J-298D01*
G37*
G36*
G01X1515380Y611807D02*
G03X1514854I-263J-302D01*
G02X1512846Y611837I-987J1132D01*
G03X1512317Y611850I-272J-293D01*
G02X1512371Y614102I-967J1150D01*
G03X1512900Y614089I272J293D01*
G02X1514854Y614071I966J-1150D01*
G03X1515380I263J302D01*
G02Y611807I987J-1132D01*
G37*
G36*
G01X1479322Y612798D02*
G03X1479833Y612784I264J300D01*
G02X1479767Y610475I927J-1182D01*
G03X1479256Y610489I-264J-300D01*
G02X1477308Y610569I-927J1182D01*
G03X1476779Y610582I-272J-293D01*
G02X1476833Y612834I-967J1150D01*
G03X1477362Y612821I272J293D01*
G02X1479322Y612798I967J-1150D01*
G37*
G36*
G01X1501994Y609800D02*
G02X1507406I2706J1300D01*
G02X1501994I-2706J-1300D01*
G37*
G36*
G01X1466638Y609175D02*
G02X1471863Y609354I2562J1564D01*
G02X1466638Y609175I-2562J-1564D01*
G37*
G36*
G01X1520505Y597038D02*
G03X1520268Y596884I-41J-196D01*
G02X1517342Y596839I-1468J316D01*
G03X1516921Y597142I-388J-96D01*
G02X1516432Y597183I-121J1497D01*
G03X1515948Y596901I-98J-388D01*
G02X1513027Y597008I-1448J399D01*
G03X1512792Y597166I-196J-38D01*
G02X1512319Y597148I-293J1473D01*
G03X1511888Y596866I-48J-397D01*
G02X1509463Y596168I-1438J434D01*
G03X1508937I-263J-302D01*
G02X1506895Y598369I-986J1133D01*
G03X1506912Y598920I-281J284D01*
G02X1508609Y601308I1119J1002D01*
G03X1509117Y601493I153J369D01*
G02X1511937Y600590I1333J-693D01*
G03X1512368Y600135I396J-56D01*
G02X1513973Y598931I132J-1496D01*
G03X1514208Y598773I196J38D01*
G02X1514868Y598756I292J-1473D01*
G03X1515352Y599038I98J388D01*
G02X1518258Y599000I1448J-399D01*
G03X1518679Y598697I388J96D01*
G02X1519108Y598670I121J-1497D01*
G03X1519345Y598824I41J196D01*
G02X1522265Y598892I1468J-316D01*
G03X1522510Y598751I193J52D01*
G02X1523086Y598790I388J-1451D01*
G03X1523310Y598964I25J199D01*
G02X1526268Y599095I1490J-187D01*
G03X1526720Y598784I391J84D01*
G02X1525482Y596983I230J-1484D01*
G03X1525030Y597294I-391J-84D01*
G02X1524614Y597288I-229J1484D01*
G03X1524390Y597114I-25J-199D01*
G02X1521448Y596916I-1490J186D01*
G03X1521203Y597057I-193J-52D01*
G02X1520505Y597038I-389J1451D01*
G37*
G36*
G01X1473925Y594900D02*
G03X1473399I-263J-302D01*
G02X1471191Y595158I-987J1132D01*
G03X1470622Y595242I-325J-233D01*
G02X1469098Y597585I-855J1111D01*
G03X1469083Y598295I-191J351D01*
G02X1470710Y600527I618J1259D01*
G03X1471296Y600537I288J277D01*
G02X1473399Y600664I1116J-1005D01*
G03X1473925I263J302D01*
G02X1476414Y599532I987J-1132D01*
G01Y599531D01*
G03X1476880Y599137I400J1D01*
G02X1478601Y597954I249J-1481D01*
G03X1479001Y597634I392J80D01*
G02X1479303Y597609I28J-1502D01*
G03X1479766Y597911I74J393D01*
G02X1482721Y597741I1463J-340D01*
G03X1482942Y597565I199J23D01*
G02X1483463Y597530I161J-1493D01*
G03X1483952Y597846I96J388D01*
G02X1486903Y597857I1477J-275D01*
G03X1487303Y597534I393J77D01*
G02X1487355I26J-1502D01*
G03X1487755Y597857I7J400D01*
G02X1490707Y597837I1474J-287D01*
G03X1491166Y597514I394J72D01*
G02X1489934Y595766I246J-1482D01*
G03X1489475Y596089I-394J-72D01*
G02X1489203Y596069I-246J1482D01*
G03X1488803Y595746I-7J-400D01*
G02X1485855I-1474J286D01*
G03X1485455Y596069I-393J-77D01*
G02X1485070Y596113I-23J1502D01*
G03X1484581Y595797I-96J-388D01*
G02X1481612Y595902I-1477J275D01*
G03X1481391Y596078I-199J-23D01*
G02X1480955Y596094I-164J1493D01*
G03X1480492Y595792I-74J-393D01*
G02X1477557Y595834I-1463J340D01*
G03X1477157Y596154I-392J-80D01*
G02X1476867Y596177I-27J1502D01*
G03X1476401Y595835I-69J-394D01*
G02X1473925Y594900I-1489J197D01*
G37*
G36*
G01X1504996Y433308D02*
G03X1504477Y433036I-133J-377D01*
G02X1503591Y434728I-1352J370D01*
G03X1504110Y435000I133J377D01*
G02X1504427Y435576I1353J-369D01*
G03X1504411Y436131I-296J269D01*
G02X1506427Y436187I981J1002D01*
G03X1506443Y435632I296J-269D01*
G02X1504996Y433308I-981J-1002D01*
G37*
G36*
G01X1529189Y409668D02*
G03X1529273Y409087I311J-252D01*
G02X1527386Y408816I-797J-1153D01*
G03X1527302Y409397I-311J252D01*
G02X1529189Y409668I797J1153D01*
G37*
G36*
G01X1504493Y439858D02*
G02X1503772Y441410I-1368J308D01*
G03X1504347Y441676I185J354D01*
G02X1504622Y442247I1368J-307D01*
G03X1504562Y442809I-311J251D01*
G02X1506535Y443021I881J1091D01*
G03X1506595Y442459I311J-251D01*
G02X1505068Y440124I-880J-1091D01*
G03X1504493Y439858I-185J-354D01*
G37*
G36*
G01X1532475Y434969D02*
G02X1530569Y436875I-1225J681D01*
G03Y437575I-194J350D01*
G02Y440025I681J1225D01*
G03Y440725I-194J350D01*
G02X1532475Y442631I681J1225D01*
G03X1533175I350J194D01*
G02X1535625I1225J-681D01*
G03X1536325I350J194D01*
G02X1538775I1225J-681D01*
G03X1539475I350J194D01*
G02X1541925I1225J-681D01*
G03X1542625I350J194D01*
G02X1543169Y443175I1225J-681D01*
G03Y443875I-194J350D01*
G02X1544531I681J1225D01*
G03Y443175I194J-350D01*
G02X1544569Y440746I-681J-1225D01*
G03X1544591Y440047I205J-343D01*
G02Y437553I-641J-1247D01*
G03X1544569Y436854I183J-356D01*
G02X1543209Y436897I-719J-1204D01*
G03X1543231Y437596I-183J356D01*
G02Y440004I719J1204D01*
G03X1543209Y440703I-205J343D01*
G02X1542625Y441269I642J1246D01*
G03X1541925I-350J-194D01*
G02X1539475I-1225J681D01*
G03X1538775I-350J-194D01*
G02X1536325I-1225J681D01*
G03X1535625I-350J-194D01*
G02X1535081Y440725I-1225J681D01*
G03Y440025I194J-350D01*
G02Y437575I-681J-1225D01*
G03Y436875I194J-350D01*
G02X1535625Y436331I-681J-1225D01*
G03X1536325I350J194D01*
G02Y434969I1225J-681D01*
G03X1535625I-350J-194D01*
G02X1533175I-1225J681D01*
G03X1532475I-350J-194D01*
G37*
G36*
G01X1525631Y436875D02*
G02X1524269I-681J-1225D01*
G03Y437575I-194J350D01*
G02Y440025I681J1225D01*
G03Y440725I-194J350D01*
G02X1523725Y441269I681J1225D01*
G03X1523025I-350J-194D01*
G02Y442631I-1225J681D01*
G03X1523725I350J194D01*
G02X1525631Y440725I1225J-681D01*
G03Y440025I194J-350D01*
G02Y437575I-681J-1225D01*
G03Y436875I194J-350D01*
G37*
G36*
G01X1510425Y434969D02*
G02X1508519Y436875I-1225J681D01*
G03Y437575I-194J350D01*
G02Y440025I681J1225D01*
G03Y440725I-194J350D01*
G02Y443175I681J1225D01*
G03Y443875I-194J350D01*
G02X1510425Y445781I681J1225D01*
G03X1511125I350J194D01*
G02X1513575I1225J-681D01*
G03X1514275I350J194D01*
G02X1514819Y446325I1225J-681D01*
G03Y447025I-194J350D01*
G02X1514777Y449451I681J1225D01*
G03X1514753Y450151I-205J343D01*
G02X1516112Y450199I636J1249D01*
G03X1516136Y449499I205J-343D01*
G02X1516725Y448931I-636J-1249D01*
G03X1517425I350J194D01*
G02X1517996Y449490I1225J-681D01*
G03X1518002Y450195I-186J354D01*
G02X1519896Y452114I673J1230D01*
G03X1520590Y452108I349J196D01*
G02X1522481Y450175I1210J-708D01*
G03Y449475I194J-350D01*
G02X1520575Y447569I-681J-1225D01*
G03X1519875I-350J-194D01*
G02X1517425I-1225J681D01*
G03X1516725I-350J-194D01*
G02X1516181Y447025I-1225J681D01*
G03Y446325I194J-350D01*
G02Y443875I-681J-1225D01*
G03Y443175I194J-350D01*
G02Y440725I-681J-1225D01*
G03Y440025I194J-350D01*
G02X1516725Y439481I-681J-1225D01*
G03X1517425I350J194D01*
G02X1519331Y437575I1225J-681D01*
G03Y436875I194J-350D01*
G02X1517425Y434969I-681J-1225D01*
G03X1516725I-350J-194D01*
G02X1514275I-1225J681D01*
G03X1513575I-350J-194D01*
G02X1511125I-1225J681D01*
G03X1510425I-350J-194D01*
G37*
G36*
G01X1525650Y414815D02*
G02X1524289Y414836I-699J-1215D01*
G03X1524300Y415535I-189J353D01*
G02Y417965I700J1215D01*
G03X1524289Y418664I-200J346D01*
G02X1524269Y421125I661J1236D01*
G03Y421825I-194J350D01*
G02Y424275I681J1225D01*
G03Y424975I-194J350D01*
G02Y427425I681J1225D01*
G03Y428125I-194J350D01*
G02X1525631I681J1225D01*
G03Y427425I194J-350D01*
G02Y424975I-681J-1225D01*
G03Y424275I194J-350D01*
G02Y421825I-681J-1225D01*
G03Y421125I194J-350D01*
G02X1525650Y418685I-681J-1225D01*
G03X1525661Y417986I200J-346D01*
G02Y415514I-661J-1236D01*
G03X1525650Y414815I189J-353D01*
G37*
G36*
G01X1720176Y177843D02*
G03X1720146Y177213I231J-327D01*
G02X1718174Y177307I-1046J-1213D01*
G03X1718204Y177937I-231J327D01*
G02X1720176Y177843I1046J1213D01*
G37*
G36*
G01X1794355Y170780D02*
G03X1793835Y170760I-248J-314D01*
G02X1793741Y173194I-1087J1177D01*
G03X1794261Y173214I248J314D01*
G02X1796459Y173191I1087J-1177D01*
G03X1796737I139J144D01*
G02Y170883I1111J-1154D01*
G03X1796459I-139J-144D01*
G02X1794355Y170780I-1111J1154D01*
G37*
G36*
G01X1803316Y175014D02*
X1803285Y175003D01*
G02X1801516Y177504I-501J1522D01*
G03X1801433Y178074I-316J245D01*
G02X1803784Y178624I936J1300D01*
G03X1804138Y178036I354J-188D01*
G01X1807252D01*
X1807283Y178047D01*
G02X1807524Y178106I500J-1522D01*
G03X1807633Y178444I-33J197D01*
G02X1809289Y178059I1135J1130D01*
G03X1809092Y177450I130J-378D01*
G02X1807283Y175003I-1308J-925D01*
G01X1807252Y175014D01*
X1803316D01*
G37*
G36*
G01X1778119D02*
X1778088Y175003D01*
G02X1776319Y177504I-501J1522D01*
G03X1776236Y178074I-316J245D01*
G02X1778587Y178624I936J1300D01*
G03X1778941Y178036I354J-188D01*
G01X1782055D01*
X1782086Y178047D01*
G02X1782327Y178106I500J-1522D01*
G03X1782436Y178444I-33J197D01*
G02X1784092Y178059I1135J1130D01*
G03X1783895Y177450I130J-378D01*
G02X1782086Y175003I-1308J-925D01*
G01X1782055Y175014D01*
X1778119D01*
G37*
G36*
G01X1765520D02*
X1765489Y175003D01*
G02X1763750Y177542I-501J1522D01*
G03X1763687Y178111I-309J254D01*
G02X1766088Y178624I985J1263D01*
G03X1766442Y178036I354J-188D01*
G01X1769456D01*
X1769487Y178047D01*
G02X1769728Y178106I500J-1522D01*
G03X1769837Y178444I-33J197D01*
G02X1771493Y178059I1135J1130D01*
G03X1771296Y177450I130J-378D01*
G02X1769487Y175003I-1308J-925D01*
G01X1769456Y175014D01*
X1765520D01*
G37*
G36*
G01X1740324D02*
X1740293Y175003D01*
G02X1738524Y177504I-501J1522D01*
G03X1738441Y178074I-316J245D01*
G02X1740792Y178624I936J1300D01*
G03X1741146Y178036I354J-188D01*
G01X1744260D01*
X1744291Y178047D01*
G02X1744532Y178106I500J-1522D01*
G03X1744641Y178444I-33J197D01*
G02X1746297Y178059I1135J1130D01*
G03X1746100Y177450I130J-378D01*
G02X1744291Y175003I-1308J-925D01*
G01X1744260Y175014D01*
X1740324D01*
G37*
G36*
G01X1727725D02*
X1727694Y175003D01*
G02X1725914Y177490I-501J1522D01*
G03X1725816Y178064I-319J241D01*
G02X1728104Y178629I884J1336D01*
G03X1728455Y178036I351J-193D01*
G01X1731661D01*
X1731692Y178047D01*
G02X1731933Y178106I500J-1522D01*
G03X1732042Y178444I-33J197D01*
G02X1733698Y178059I1135J1130D01*
G03X1733501Y177450I130J-378D01*
G02X1731692Y175003I-1308J-925D01*
G01X1731661Y175014D01*
X1727725D01*
G37*
G36*
G01X1750668Y175279D02*
G02X1750398Y177266I-1373J825D01*
G03X1751017Y177350I276J290D01*
G02X1751122Y177504I1374J-824D01*
G03X1751039Y178074I-316J245D01*
G02X1753390Y178624I936J1300D01*
G03X1753744Y178036I354J-188D01*
G01X1756858D01*
X1756889Y178047D01*
G02X1757130Y178106I500J-1522D01*
G03X1757239Y178444I-33J197D01*
G02X1758895Y178059I1135J1130D01*
G03X1758698Y177450I130J-378D01*
G02X1756889Y175003I-1308J-925D01*
G01X1756858Y175014D01*
X1752922D01*
X1752891Y175003D01*
G02X1751287Y175363I-501J1522D01*
G03X1750668Y175279I-276J-290D01*
G37*
G36*
G01X1788544Y175072D02*
G02X1788005Y176748I-1544J428D01*
G03X1788641Y176953I251J311D01*
G02X1788947Y177542I1544J-428D01*
G03X1788884Y178111I-309J254D01*
G02X1791285Y178624I985J1263D01*
G03X1791639Y178036I354J-188D01*
G01X1794653D01*
X1794684Y178047D01*
G02X1794925Y178106I500J-1522D01*
G03X1795034Y178444I-33J197D01*
G02X1796690Y178059I1135J1130D01*
G03X1796493Y177450I130J-378D01*
G02X1794684Y175003I-1308J-925D01*
G01X1794653Y175014D01*
X1790717D01*
X1790686Y175003D01*
G02X1789180Y175277I-501J1522D01*
G03X1788544Y175072I-251J-311D01*
G37*
G36*
G01X1690105Y175241D02*
G02X1690058Y173542I1334J-887D01*
G03X1689380Y173560I-345J-203D01*
G02X1689427Y175259I-1334J887D01*
G03X1690105Y175241I345J203D01*
G37*
G36*
G01X1718239Y138819D02*
G02X1716333Y140725I-1225J681D01*
G03Y141425I-194J350D01*
G02X1717695I681J1225D01*
G03Y140725I194J-350D01*
G02X1718239Y140181I-681J-1225D01*
G03X1718939I350J194D01*
G02X1721389I1225J-681D01*
G03X1722089I350J194D01*
G02X1722633Y140725I1225J-681D01*
G03Y141425I-194J350D01*
G02X1722650Y143885I681J1225D01*
G03X1722639Y144595I-190J352D01*
G02X1722070Y145116I626J1255D01*
G03X1721381Y145105I-341J-209D01*
G02X1721358Y146534I-1217J695D01*
G03X1722047Y146545I341J209D01*
G02X1724519Y146475I1217J-695D01*
G03X1725229Y146464I358J179D01*
G02X1725209Y145175I1235J-664D01*
G03X1724499Y145186I-358J-179D01*
G02X1723928Y144615I-1235J664D01*
G03X1723939Y143905I190J-352D01*
G02X1723995Y141425I-625J-1255D01*
G03Y140725I194J-350D01*
G02X1722089Y138819I-681J-1225D01*
G03X1721389I-350J-194D01*
G02X1718939I-1225J681D01*
G03X1718239I-350J-194D01*
G37*
G36*
G01X1739745Y137575D02*
G02X1738383I-681J-1225D01*
G03Y138275I-194J350D01*
G02X1737839Y138819I681J1225D01*
G03X1737139I-350J-194D01*
G02Y140181I-1225J681D01*
G03X1737839I350J194D01*
G02X1738383Y140725I1225J-681D01*
G03Y141425I-194J350D01*
G02Y143875I681J1225D01*
G03Y144575I-194J350D01*
G02X1740289Y146481I681J1225D01*
G03X1740989I350J194D01*
G02X1743439I1225J-681D01*
G03X1744139I350J194D01*
G02Y145119I1225J-681D01*
G03X1743439I-350J-194D01*
G02X1742895Y144575I-1225J681D01*
G03Y143875I194J-350D01*
G02X1740989Y141969I-681J-1225D01*
G03X1740289I-350J-194D01*
G02X1739745Y141425I-1225J681D01*
G03Y140725I194J-350D01*
G02Y138275I-681J-1225D01*
G03Y137575I194J-350D01*
G37*
G36*
G01X1721411Y126159D02*
G02X1721368Y127519I-1247J641D01*
G03X1722067Y127541I343J205D01*
G02X1722633Y128125I1246J-642D01*
G03Y128825I-194J350D01*
G02Y131275I681J1225D01*
G03Y131975I-194J350D01*
G02X1722089Y132519I681J1225D01*
G03X1721389I-350J-194D01*
G02Y133881I-1225J681D01*
G03X1722089I350J194D01*
G02X1724539I1225J-681D01*
G03X1725239I350J194D01*
G02Y132519I1225J-681D01*
G03X1724539I-350J-194D01*
G02X1723995Y131975I-1225J681D01*
G03Y131275I194J-350D01*
G02Y128825I-681J-1225D01*
G03Y128125I194J-350D01*
G02X1722110Y126181I-681J-1225D01*
G03X1721411Y126159I-343J-205D01*
G37*
G36*
G01X1723994Y118676D02*
G02X1722634I-680J-1226D01*
G03Y119375I-195J350D01*
G02X1722089Y119919I680J1226D01*
G03X1721390I-350J-194D01*
G02X1721389Y121282I-1226J681D01*
G03X1722088I350J194D01*
G02X1724540I1226J-681D01*
G03X1725239I350J194D01*
G02X1725783Y121825I1224J-683D01*
G03Y122525I-194J350D01*
G02X1727615Y124551I681J1225D01*
G03X1728276Y124558I328J228D01*
G02X1728293Y122981I1168J-776D01*
G03X1727632Y122974I-328J-228D01*
G02X1727145Y122525I-1167J777D01*
G03Y121825I194J-350D01*
G02X1725238Y119919I-681J-1225D01*
G03X1724539I-350J-194D01*
G02X1723994Y119375I-1225J682D01*
G03Y118676I195J-350D01*
G37*
G36*
G01X1739745Y115525D02*
G02X1738383I-681J-1225D01*
G03Y116225I-194J350D01*
G02X1737839Y116769I681J1225D01*
G03X1737139I-350J-194D01*
G02Y118131I-1225J681D01*
G03X1737839I350J194D01*
G02X1738383Y118675I1225J-681D01*
G03Y119375I-194J350D01*
G02Y121825I681J1225D01*
G03Y122525I-194J350D01*
G02X1737838Y123070I681J1226D01*
G03X1737138I-350J-194D01*
G02Y124430I-1226J680D01*
G03X1737838I350J194D01*
G02X1738383Y124975I1226J-681D01*
G03Y125675I-194J350D01*
G02Y128125I681J1225D01*
G03Y128825I-194J350D01*
G02X1740289Y130731I681J1225D01*
G03X1740989I350J194D01*
G02X1742895Y128825I1225J-681D01*
G03Y128125I194J-350D01*
G02X1740989Y126219I-681J-1225D01*
G03X1740289I-350J-194D01*
G02X1739745Y125675I-1225J681D01*
G03Y124975I194J-350D01*
G02Y122525I-681J-1225D01*
G03Y121825I194J-350D01*
G02X1740289Y121281I-681J-1225D01*
G03X1740989I350J194D01*
G02X1743439I1225J-681D01*
G03X1744139I350J194D01*
G02Y119919I1225J-681D01*
G03X1743439I-350J-194D01*
G02X1742895Y119375I-1225J681D01*
G03Y118676I194J-350D01*
G02X1740988Y116768I-683J-1225D01*
G03X1740289I-350J-195D01*
G02X1739745Y116225I-1224J683D01*
G03Y115525I194J-350D01*
G37*
G36*
G01X1736595Y106075D02*
G02X1735233I-681J-1225D01*
G03Y106775I-194J350D01*
G02X1737139Y108681I681J1225D01*
G03X1737839I350J194D01*
G02Y107319I1225J-681D01*
G03X1737139I-350J-194D01*
G02X1736595Y106775I-1225J681D01*
G03Y106075I194J-350D01*
G37*
G36*
G01X1742895Y99775D02*
G02X1741533I-681J-1225D01*
G03Y100475I-194J350D01*
G02X1742895I681J1225D01*
G03Y99775I194J-350D01*
G37*
G36*
G01X1723995D02*
G02X1722633I-681J-1225D01*
G03Y100475I-194J350D01*
G02Y102925I681J1225D01*
G03Y103625I-194J350D01*
G02X1722089Y104169I681J1225D01*
G03X1721389I-350J-194D01*
G02X1719483Y106075I-1225J681D01*
G03Y106775I-194J350D01*
G02X1718939Y107319I681J1225D01*
G03X1718239I-350J-194D01*
G02Y108681I-1225J681D01*
G03X1718939I350J194D01*
G02X1719483Y109225I1225J-681D01*
G03Y109925I-194J350D01*
G02X1721389Y111831I681J1225D01*
G03X1722089I350J194D01*
G02X1724539I1225J-681D01*
G03X1725239I350J194D01*
G02Y110469I1225J-681D01*
G03X1724539I-350J-194D01*
G02X1723995Y109925I-1225J681D01*
G03Y109225I194J-350D01*
G02Y106775I-681J-1225D01*
G03Y106075I194J-350D01*
G02Y103625I-681J-1225D01*
G03Y102925I194J-350D01*
G02X1724451Y102521I-680J-1226D01*
G03X1725112Y102539I324J234D01*
G02X1725157Y100964I1182J-754D01*
G03X1724496Y100946I-324J-234D01*
G02X1723995Y100475I-1181J755D01*
G03Y99775I194J-350D01*
G37*
G54D51*
X1688207Y168972D03*
X1900740Y178720D03*
X1900700Y172990D03*
Y167290D03*
X1906440Y178720D03*
X1906500Y173100D03*
X1906400Y167290D03*
X1912190Y178870D03*
X1912230Y167330D03*
Y173030D03*
G54D46*
X40132Y499800D03*
X27280Y510420D03*
X60300Y508650D03*
X51607Y511747D03*
X57936Y516012D03*
G54D44*
X448593Y652514D03*
Y646514D03*
X438681D03*
Y652514D03*
X567029Y652238D03*
Y646238D03*
X576941D03*
Y652238D03*
X1265293Y652264D03*
Y646264D03*
X1255381D03*
Y652264D03*
X1509696Y652236D03*
Y646236D03*
X1519608D03*
Y652236D03*
X19800Y257900D03*
X102456Y393756D03*
X114084Y399937D03*
X1032102Y278904D03*
X1089702D03*
X1083220Y324174D03*
X1708250Y164950D03*
X1708350Y175050D03*
X1695734Y164676D03*
X1713596Y175795D03*
X1723189Y176012D03*
X1785500Y164000D03*
X1778900Y165800D03*
X1785500Y168000D03*
G54D47*
X104600Y316602D03*
G54D50*
X1392264Y23976D03*
G54D43*
X5120Y276058D03*
X2269Y273532D03*
X1500Y295000D03*
X-1190Y53240D03*
X-1470Y63910D03*
X19904Y254162D03*
X110670Y344500D03*
X109960Y313190D03*
X110397Y402603D03*
X109640Y376070D03*
X109500Y370000D03*
X103100Y411800D03*
X112904Y237218D03*
X113100Y269163D03*
X118800Y298400D03*
X113100Y333106D03*
X113000Y304000D03*
X122361Y342649D03*
X118220Y360500D03*
X271239Y273460D03*
X291519Y277360D03*
X281379Y275409D03*
Y271509D03*
X284759Y277360D03*
X288139Y275409D03*
X277999Y277360D03*
X274619Y275409D03*
X294899D03*
X267859Y271509D03*
X264179Y273460D03*
X274619Y271509D03*
X277999Y273460D03*
X291519Y285160D03*
Y292959D03*
X284759Y285160D03*
X277999Y308560D03*
Y300760D03*
Y292959D03*
Y285160D03*
X284759Y300760D03*
X291519D03*
X284759Y292959D03*
X308418Y275409D03*
X301659D03*
X321938Y283209D03*
Y275409D03*
X315178Y279310D03*
X318558Y277360D03*
X315178Y283209D03*
X318558Y281260D03*
X325318Y269560D03*
X318558D03*
X328698Y283209D03*
X332078Y269560D03*
Y281260D03*
X325318D03*
Y273460D03*
X305039D03*
Y277360D03*
X311798D03*
Y269560D03*
X298279Y277360D03*
X338838Y281260D03*
X335458Y283209D03*
X345598Y273460D03*
Y269560D03*
X342218Y271509D03*
Y283209D03*
Y279310D03*
Y275409D03*
X315178D03*
Y271509D03*
X311798Y273460D03*
X321938Y271509D03*
X308418D03*
X318558Y273460D03*
X338838D03*
Y269560D03*
X332078Y273460D03*
X335458Y275409D03*
X328698D03*
X338838Y277360D03*
X332078D03*
X325318D03*
X335458Y279310D03*
X328698D03*
X321938D03*
X335458Y271509D03*
X328698D03*
X311798Y292959D03*
X305039D03*
X318558D03*
X311798Y285160D03*
X328698Y310509D03*
X332078Y300760D03*
Y292959D03*
X321938Y310509D03*
X315178D03*
X311798Y308560D03*
X305039Y300760D03*
X325318D03*
X311798D03*
X298279D03*
X318558D03*
X325318Y292959D03*
X305039Y285160D03*
X298279D03*
Y292959D03*
X318558Y312460D03*
X325318D03*
X332078D03*
X335458Y310509D03*
X338838Y300760D03*
Y292959D03*
X342218Y310509D03*
Y314409D03*
X338838Y312460D03*
Y316360D03*
X345598Y328060D03*
X342218Y322209D03*
Y318309D03*
Y326110D03*
X345598Y320260D03*
Y324160D03*
X328698Y314409D03*
X321938D03*
X328698Y318309D03*
X332078Y320260D03*
Y316360D03*
X325318D03*
X335458Y314409D03*
Y318309D03*
Y322209D03*
X338838Y320260D03*
Y324160D03*
X452865Y270081D03*
X380200Y-1200D03*
X364565Y28014D03*
Y35942D03*
Y-1858D03*
Y9114D03*
X361218Y-1858D03*
Y9114D03*
X367911Y-1858D03*
Y9114D03*
Y35942D03*
Y28014D03*
X374039Y611186D03*
X367911Y604614D03*
X481172Y278596D03*
X469913Y305896D03*
X477792Y307851D03*
X481172Y309797D03*
Y301996D03*
X477792Y303947D03*
Y315647D03*
Y319547D03*
Y327347D03*
X481172Y313696D03*
X469913Y321496D03*
X481172D03*
Y317596D03*
X466100Y300021D03*
X477792Y311747D03*
X469913Y309797D03*
Y313696D03*
Y317596D03*
X487932Y282496D03*
Y278596D03*
X484552Y276646D03*
X494692Y294196D03*
X491312Y292245D03*
Y300047D03*
X494692Y309797D03*
X487932D03*
X498072Y303947D03*
X484552Y300047D03*
Y292245D03*
X494692Y286396D03*
X487932Y317596D03*
Y313696D03*
X491312Y315647D03*
X484552Y319546D03*
X491312Y288347D03*
Y284447D03*
X498072Y288347D03*
X494692Y290296D03*
X498072Y292247D03*
X487932Y305896D03*
X491312Y303947D03*
X494692Y298096D03*
X498072Y307847D03*
X484552Y303947D03*
X487932Y294196D03*
X491312Y296147D03*
X494692Y301996D03*
X487932D03*
Y298096D03*
X484552Y311747D03*
Y315647D03*
X498072Y300047D03*
Y296147D03*
X484552Y307847D03*
X491312D03*
Y311747D03*
X494692Y305896D03*
X605300Y124600D03*
X609482Y124568D03*
X504832Y307847D03*
X538631Y311747D03*
X514972Y301996D03*
X521731D03*
X531871Y303947D03*
X535251Y301996D03*
X531871Y311747D03*
Y307847D03*
X535251Y309797D03*
X518352Y315647D03*
X521731Y317596D03*
X542011Y321496D03*
X525111Y315647D03*
X528491Y317596D03*
X531871Y319547D03*
X538631D03*
X531871Y315647D03*
X511592Y303947D03*
X542011Y313696D03*
Y309797D03*
X538631Y307847D03*
Y303947D03*
X535251Y317596D03*
X542011D03*
Y305896D03*
X535251D03*
X542011Y301996D03*
X538631Y323446D03*
X535251Y313696D03*
X538631Y315647D03*
X545391Y307847D03*
X555831Y309797D03*
Y305896D03*
X548771Y309797D03*
X545391Y303947D03*
X548771Y313696D03*
X561971Y317320D03*
X558911Y335147D03*
X562591Y333196D03*
Y344896D03*
X561966Y325502D03*
X559211Y319547D03*
X552151Y323446D03*
X545391Y319547D03*
Y315647D03*
X548771Y321496D03*
X545391Y323446D03*
Y311747D03*
X552151Y319547D03*
Y315647D03*
Y311747D03*
X548771Y305896D03*
Y301996D03*
X562591Y340996D03*
X559211Y331103D03*
X555531Y329296D03*
X559211Y323446D03*
X555531Y321496D03*
X548771Y317596D03*
X555831Y313696D03*
X552151Y307847D03*
Y303947D03*
X555831Y301996D03*
X562591Y337096D03*
X559211Y327347D03*
X555531Y325396D03*
X555831Y317446D03*
X924227Y275409D03*
X927607Y277360D03*
X964786Y283209D03*
X971546D03*
X964786Y279310D03*
X974926Y281260D03*
X968166D03*
X971546Y279310D03*
X934367Y285160D03*
Y300760D03*
X927607D03*
Y308560D03*
X934367D03*
X927607Y285160D03*
Y292959D03*
X934367D03*
X961406D03*
Y285160D03*
X954647Y292959D03*
Y285160D03*
X968166Y292959D03*
Y300760D03*
X971546Y310509D03*
X964786D03*
X954647Y308560D03*
X961406D03*
X954647Y300760D03*
X961406D03*
X974926D03*
X947887Y308560D03*
X941127D03*
Y300760D03*
X947887D03*
X941127Y285160D03*
Y292959D03*
X947887D03*
Y285160D03*
X974926Y292959D03*
Y312460D03*
X968166D03*
X964786Y314409D03*
X971546D03*
X981686Y281260D03*
X995206Y273460D03*
X991826Y283209D03*
Y279310D03*
Y275409D03*
X988446Y281260D03*
X985066Y283209D03*
X978306D03*
X988446Y277360D03*
X985066Y279310D03*
X978306D03*
X981686Y292959D03*
Y300760D03*
X988446D03*
X978306Y310509D03*
X991826D03*
X985066D03*
X988446Y292959D03*
X995206Y328060D03*
X991826Y326110D03*
X981686Y312460D03*
X988446D03*
X991826Y314409D03*
X995206Y324160D03*
X988446Y316360D03*
X991826Y318309D03*
X995206Y320260D03*
X991826Y322209D03*
X1008725Y339760D03*
X1005345Y337809D03*
X1001965Y335860D03*
X1012105Y341709D03*
X988446Y320260D03*
X985066Y318309D03*
X978306Y314409D03*
X985066D03*
X1028400Y6500D03*
X1026700Y1700D03*
X1017519Y-1858D03*
Y9114D03*
Y28014D03*
Y35942D03*
X1023200Y610700D03*
X1014173Y604614D03*
X1010826D03*
X1011572Y593642D03*
X1010826Y612242D03*
X1017519Y604614D03*
X1081212Y257600D03*
X1255118Y92599D03*
X1257800Y120800D03*
X1269000Y514700D03*
X1251771Y528899D03*
Y517999D03*
X1278573Y519596D03*
X1255120Y518000D03*
Y510158D03*
X1271300Y510600D03*
X1274576Y510235D03*
X1265157Y528876D03*
Y517999D03*
X1269800Y532978D03*
X1268500Y555800D03*
X1267900Y574300D03*
X1255120Y555144D03*
Y537034D03*
X1265157Y566676D03*
Y555799D03*
X1277200Y539100D03*
X1385608Y-17485D03*
X1388294Y-5675D03*
X1389523Y4966D03*
X1388627Y35032D03*
X1379025Y-9799D03*
X1397500Y51000D03*
X1389138Y58499D03*
X1389068Y78556D03*
X1389100Y74600D03*
X1371200Y402100D03*
X1375201Y396303D03*
X1463419Y606912D03*
X1470353Y592128D03*
X1518700Y406500D03*
X1497275Y443546D03*
X1495325Y453686D03*
Y446926D03*
X1497275Y450306D03*
X1503125Y453786D03*
X1497275Y436786D03*
X1495325Y440166D03*
X1501175Y436786D03*
X1493375Y450306D03*
X1516700Y409900D03*
X1524575Y407624D03*
X1512954Y407653D03*
X1499225Y440166D03*
Y446926D03*
Y453686D03*
X1549925Y446926D03*
X1549938Y453714D03*
X1551875Y450306D03*
X1553825Y440166D03*
Y446926D03*
X1532375Y407934D03*
X1551875Y436786D03*
X1549925Y440166D03*
X1532349Y455200D03*
X1551875Y443546D03*
X1720164Y97550D03*
X1742214Y111150D03*
X1731903Y133712D03*
X1745364Y114300D03*
X1735989Y133250D03*
X1728789Y136250D03*
X1726539Y139450D03*
X1734989Y142750D03*
X1731789Y139450D03*
X1746189Y134777D03*
X1748425Y119190D03*
X1745500Y104500D03*
G54D45*
X24400Y519500D03*
G54D41*
X40500Y-42250D03*
Y-52250D03*
X60500Y-42250D03*
X80500D03*
X100500D03*
X60500Y-52250D03*
X80500D03*
X100500D03*
X467246Y-52301D03*
Y-42301D03*
X487246Y-52301D03*
Y-42301D03*
X507246Y-52301D03*
Y-42301D03*
X527246Y-52301D03*
Y-42301D03*
X798984Y-52057D03*
Y-42057D03*
X818984Y-52057D03*
Y-42057D03*
X838984Y-52057D03*
Y-42057D03*
X858984Y-52057D03*
Y-42057D03*
X1135583Y-52285D03*
Y-42285D03*
X1392258Y-52257D03*
Y-42257D03*
X1412258Y-52257D03*
Y-42257D03*
G54D49*
X1287403Y532955D03*
Y514079D03*
G54D42*
X-7874Y216181D03*
Y325315D03*
G54D40*
X-3937Y-43307D03*
X1956693D03*
X-3937Y646063D03*
X1956693D03*
G54D48*
X224410Y301378D03*
X602362Y387992D03*
X874016Y301378D03*
%LPD*%
G75*
G36*
G01X1903400Y122500D02*
Y135250D01*
X1913800D01*
Y122500D01*
X1903400D01*
G37*
G54D10*
X-17936Y-49379D03*
Y-53779D03*
Y-44979D03*
Y-40579D03*
X-18079Y-35764D03*
Y-58764D03*
X-14186Y196989D03*
Y199989D03*
X-17179Y643156D03*
X-17194Y638753D03*
X-17179Y647556D03*
Y660756D03*
Y651956D03*
Y656356D03*
X-13636Y-40479D03*
Y-44879D03*
Y-53679D03*
X-9079Y-50164D03*
X-4679D03*
X-279D03*
X-9079Y-54264D03*
X-4679D03*
X-279D03*
X22964Y-40379D03*
Y-44779D03*
Y-53579D03*
Y-49179D03*
X18964Y-53579D03*
Y-49179D03*
X13964Y-53579D03*
Y-49179D03*
X8964Y-40379D03*
Y-44779D03*
Y-53579D03*
Y-49179D03*
X3964Y-40379D03*
Y-44779D03*
Y-53579D03*
Y-49179D03*
X25921Y-35764D03*
X30321D03*
X43521D03*
X39121D03*
X34721D03*
X8321D03*
X12721D03*
X21521D03*
X17121D03*
X-13679D03*
X-9279D03*
X3921D03*
X-4879D03*
X-479D03*
X17121Y-58764D03*
X21521D03*
X12721D03*
X8321D03*
X34721D03*
X39121D03*
X43521D03*
X30321D03*
X25921D03*
X-479D03*
X-13679D03*
X-4879D03*
X3921D03*
X-13636Y-49279D03*
X-9279Y-58764D03*
X875Y211336D03*
X6074Y211293D03*
X3474Y211263D03*
X875Y208352D03*
X36200Y208600D03*
X33200D03*
X20700D03*
X17700Y211600D03*
X20700D03*
X17700Y208600D03*
X23700Y211600D03*
Y208600D03*
X33200Y211600D03*
X30200D03*
Y208600D03*
X36200Y211600D03*
X6074Y208321D03*
X3474Y208263D03*
X5500Y218500D03*
X-5300Y200191D03*
X-7900D03*
X-2700Y200202D03*
X-11586Y196989D03*
Y199989D03*
X-2600Y232300D03*
X-5246Y232351D03*
X-7846D03*
X20500Y221000D03*
Y224000D03*
X17500Y221000D03*
Y224000D03*
X23500D03*
Y221000D03*
X33300Y224000D03*
Y221000D03*
X30300D03*
Y224000D03*
X36300D03*
Y221000D03*
X-14129Y235221D03*
X-11484Y235215D03*
Y232215D03*
X-14084D03*
X2678Y221018D03*
X5277Y221110D03*
X5173Y224042D03*
X2574Y223963D03*
X-26Y223982D03*
X22421Y647556D03*
X26821D03*
X31221D03*
X18021D03*
Y643156D03*
X31221D03*
X26821D03*
X22421D03*
X18006Y638753D03*
X9221Y647556D03*
X13621D03*
Y643156D03*
X9221D03*
X4821D03*
Y647556D03*
X22406Y638753D03*
X26806D03*
X31206D03*
X-12794D03*
X-12779Y647556D03*
Y643156D03*
X40006Y638753D03*
X44406D03*
X35606D03*
X35621Y647556D03*
Y643156D03*
X18021Y660756D03*
X35621Y656356D03*
X26821Y660756D03*
X18021Y651956D03*
X31221D03*
X22421Y660756D03*
X26821Y651956D03*
X22421D03*
X4821D03*
X13621D03*
X9221D03*
X-8379Y660756D03*
X4821Y656356D03*
X9221D03*
X13621D03*
X-3979D03*
X421D03*
X13621Y660756D03*
X-3979D03*
X421D03*
X4821D03*
X-12779Y651956D03*
X22421Y656356D03*
X26821D03*
X31221D03*
X18021D03*
X-8379D03*
X-12779D03*
X31221Y660756D03*
X35621Y651956D03*
Y660756D03*
X44421D03*
X40021D03*
X-12779D03*
X9221D03*
X107921Y-58764D03*
X102921D03*
X97921D03*
X92921D03*
X87921D03*
X82921D03*
X77921D03*
X72921D03*
X67921D03*
X62921D03*
X57921D03*
X52921D03*
X47921Y-35764D03*
Y-58764D03*
X107921Y-35764D03*
X102921D03*
X97921D03*
X92921D03*
X87921D03*
X82921D03*
X77921D03*
X72921D03*
X67921D03*
X62921D03*
X57921D03*
X52921D03*
X58200Y230400D03*
Y233400D03*
X55600Y230400D03*
X53000Y230300D03*
Y233300D03*
X55600Y233400D03*
X58200Y227400D03*
X53000Y227300D03*
X55600Y227400D03*
X58200Y239400D03*
X53000Y239300D03*
X55600Y239400D03*
X58200Y236400D03*
X55600D03*
X53000Y236300D03*
X71500Y263300D03*
X68800D03*
X53004Y244632D03*
X55275Y245900D03*
X57875D03*
X57457Y248537D03*
Y251237D03*
X57600Y262800D03*
X57500Y260200D03*
X62800Y265500D03*
X71500Y266000D03*
X65500Y265500D03*
X68800Y266000D03*
X60000Y265500D03*
X103700Y397200D03*
X106400D03*
X101000D03*
X109100D03*
Y399900D03*
X101000D03*
X106400D03*
X103700D03*
X104517Y406279D03*
X105761Y409208D03*
X108010Y411479D03*
X48806Y638753D03*
X75206D03*
X106006D03*
X70806D03*
X53206D03*
X66406D03*
X92806D03*
X97206D03*
X101606D03*
X57606D03*
X62006D03*
X79606D03*
X84006D03*
X88406D03*
X53221Y660756D03*
X101621D03*
X97221D03*
X92821D03*
X106021D03*
X48821D03*
X70821D03*
X66421D03*
X62021D03*
X57621D03*
X75221D03*
X88421D03*
X84021D03*
X79621D03*
X167921Y-58764D03*
X162921D03*
X157921D03*
X152921D03*
X147921D03*
X142921D03*
X137921D03*
X132921D03*
X127921D03*
X122921D03*
X117921D03*
X112921D03*
X162921Y-35764D03*
X157921D03*
X152921D03*
X147921D03*
X142921D03*
X137921D03*
X132921D03*
X127921D03*
X122921D03*
X117921D03*
X112921D03*
X167921D03*
X166000Y212900D03*
X168600D03*
X164300Y207870D03*
X160800Y212900D03*
X163400D03*
X157800Y207300D03*
X161216Y209533D03*
Y206933D03*
X154500Y205500D03*
X150600Y212900D03*
X151000Y205500D03*
X140889Y211972D03*
X137615Y212039D03*
X143900Y204600D03*
X147500Y205500D03*
X137300Y204500D03*
X140200Y204400D03*
X153200Y212900D03*
X139815Y268974D03*
X137900Y272800D03*
X139800Y237000D03*
X165825Y239543D03*
X168425Y236943D03*
Y239543D03*
X165825Y236943D03*
X163225D03*
X152825D03*
X145025D03*
X147625D03*
X150225D03*
X142425D03*
X122231Y234716D03*
X125564Y237816D03*
X122632D03*
X163225Y239543D03*
X158025Y236943D03*
X155425D03*
X160625D03*
X142371Y244384D03*
X122231Y266716D03*
X122531Y269816D03*
X125463D03*
X142466Y268982D03*
X142700Y276200D03*
X136729Y276386D03*
X139683Y276174D03*
X163225Y242143D03*
X168425Y244743D03*
X165825D03*
X163225D03*
X168425Y242143D03*
X165825D03*
X150700Y276800D03*
X169150Y259470D03*
Y255470D03*
X157633Y268727D03*
X162833D03*
X160233D03*
X165433D03*
X168033Y271327D03*
X162833Y276527D03*
Y273927D03*
Y271327D03*
X165433Y276527D03*
Y273927D03*
Y271327D03*
X159983Y276507D03*
X168033Y276527D03*
Y273927D03*
Y268727D03*
X153300Y276800D03*
X139866Y333016D03*
X160233Y306257D03*
Y308857D03*
Y303657D03*
X157518Y335391D03*
X157745Y332800D03*
X139900Y302400D03*
X142433Y301057D03*
X147633D03*
X150233D03*
X145033D03*
X125500Y333500D03*
X122231Y330716D03*
X122731Y333916D03*
X145200Y341300D03*
X148200D03*
X142465Y332940D03*
X152833Y301057D03*
X163233Y306257D03*
Y308857D03*
X168433Y306257D03*
Y308857D03*
Y301057D03*
X165833D03*
X163233D03*
X160633D03*
X158033D03*
X155433D03*
X169150Y287600D03*
Y291600D03*
X165833Y306257D03*
X163233Y303657D03*
X168433D03*
X165833D03*
Y308857D03*
X151000Y341300D03*
X169150Y323600D03*
Y319600D03*
X160501Y332965D03*
X160274Y335556D03*
X165701Y338165D03*
Y335565D03*
X163101Y332965D03*
X168301D03*
X165701D03*
X163101Y335565D03*
X168301Y340765D03*
Y338165D03*
Y335565D03*
X163101Y338165D03*
Y340765D03*
X165701D03*
X154200Y341100D03*
X125663Y301716D03*
X122231Y298716D03*
X122731Y301716D03*
X139767Y364883D03*
X147833Y364457D03*
X125600Y364900D03*
X122600Y365500D03*
X122331Y362716D03*
X142421Y364908D03*
X145033Y364457D03*
X142863Y402829D03*
X140219Y402894D03*
X137619Y402900D03*
X134992D03*
X142818Y400163D03*
X143073Y397194D03*
X140475Y397310D03*
X140218Y400163D03*
X137529Y400296D03*
X134929D03*
X111561Y398819D03*
X122000Y397600D03*
X125300Y397700D03*
X122231Y394716D03*
X150633Y364457D03*
X167433Y369657D03*
X169150Y355600D03*
Y351600D03*
X167700Y363900D03*
X161833Y364457D03*
X164633D03*
X159033D03*
X156233D03*
X153433D03*
X164633Y369657D03*
X161833D03*
X161933Y372357D03*
X164733D03*
X167533D03*
X166340Y374785D03*
X110406Y638753D03*
X145606D03*
X141206D03*
X136806D03*
X132406D03*
X158806D03*
X119206D03*
X123606D03*
X114806D03*
X128006D03*
X163206D03*
X154406D03*
X167606D03*
X150006D03*
X132421Y660756D03*
X145621D03*
X141221D03*
X136821D03*
X123621D03*
X114821D03*
X128021D03*
X110421D03*
X119221D03*
X150021D03*
X167621D03*
X163221D03*
X158821D03*
X154421D03*
X182921Y-58764D03*
X177921D03*
X172921D03*
X227921Y-35764D03*
X222921D03*
X217921D03*
X212921D03*
X207921D03*
X202921D03*
X197921D03*
X192921D03*
X187921D03*
X182921D03*
X177921D03*
X227921Y-58764D03*
X222921D03*
X217921D03*
X212921D03*
X207921D03*
X202921D03*
X197921D03*
X192921D03*
X187921D03*
X172921Y-35764D03*
X176300Y211900D03*
X182300Y216108D03*
X179300D03*
Y213208D03*
X176300Y217308D03*
Y214500D03*
X173300Y217700D03*
Y214800D03*
Y211900D03*
X176400Y234300D03*
X176508Y231609D03*
X179400Y234300D03*
X182400D03*
X176400Y239900D03*
X182400D03*
X179400D03*
X173400D03*
Y231400D03*
Y234300D03*
Y237000D03*
X176400D03*
X182400D03*
X179400D03*
X188200Y236800D03*
X188300Y234000D03*
X185250Y239850D03*
X204200Y249500D03*
X201100Y246500D03*
X198200Y249500D03*
Y246500D03*
X201200Y249500D03*
X203900Y246500D03*
X207200Y249500D03*
X185768Y270065D03*
X173835Y277804D03*
X198082Y277995D03*
X203847Y274933D03*
X203947Y277933D03*
X188510Y272666D03*
X176835Y277804D03*
X182935Y278204D03*
Y275604D03*
X191400Y278400D03*
X188475Y270065D03*
X185735Y275604D03*
X188600Y278300D03*
X188535Y275604D03*
X185735Y278204D03*
X195300Y229250D03*
X188100Y239800D03*
X185250Y234250D03*
Y236950D03*
X176835Y275204D03*
X185754Y272689D03*
X179835Y277804D03*
Y275204D03*
X195100Y252000D03*
X201200Y252500D03*
X198200D03*
X204200D03*
X207200D03*
X200947Y277933D03*
X200847Y274933D03*
X200947Y280933D03*
X173835Y275204D03*
X230800Y265200D03*
X224390Y258920D03*
X219500Y254500D03*
X190800Y295500D03*
X196956Y295583D03*
X193800Y295500D03*
X190665Y306877D03*
X198119Y339710D03*
X191792Y327743D03*
X197792Y327643D03*
X194792D03*
X184800Y295500D03*
X187956Y295583D03*
X181800Y295500D03*
X201177Y330728D03*
Y333728D03*
Y336728D03*
X201163Y339476D03*
Y342476D03*
X204177Y336728D03*
X204060Y342527D03*
X204163Y339476D03*
X188654Y330973D03*
Y327973D03*
X197684Y307227D03*
X200251Y306548D03*
X188630Y333923D03*
X190570Y309539D03*
X185630Y333923D03*
X172800Y295500D03*
Y298400D03*
X198182Y280995D03*
X178956Y295583D03*
X175800Y295500D03*
X187900Y306900D03*
X191300Y339800D03*
X172800Y304000D03*
X175800D03*
X178800D03*
X187800D03*
X181800D03*
X184800D03*
X172800Y301100D03*
X175800D03*
X178800D03*
X181800D03*
X187800D03*
X184800D03*
Y298400D03*
X181800D03*
X175800D03*
X178800D03*
X187800D03*
X185300Y336900D03*
X173300Y337000D03*
Y339900D03*
X188300D03*
Y336900D03*
X179300Y337000D03*
X176300Y339900D03*
X179300D03*
X182300D03*
Y337000D03*
X198223Y342430D03*
X176300Y337000D03*
X185300Y339900D03*
X224000Y330900D03*
X229100Y325900D03*
X219000Y335900D03*
X214000Y340900D03*
X197730Y309959D03*
X204060Y345527D03*
X191300Y343248D03*
X173300Y343448D03*
X188300Y343348D03*
X201045Y345449D03*
X198233Y345402D03*
X195233D03*
X176300Y343448D03*
X201045Y348449D03*
X198233Y348402D03*
Y351402D03*
X195233D03*
X173424Y359621D03*
X188424D03*
X182424D03*
X185424D03*
X176424D03*
X179424D03*
X182300Y343448D03*
X173471Y363281D03*
X188471D03*
X182471D03*
X185471D03*
X176471D03*
X179471D03*
X179300Y343448D03*
X185300Y343348D03*
X211606Y638753D03*
X224806D03*
X220406D03*
X216006D03*
X189606D03*
X198406D03*
X202806D03*
X207206D03*
X176406D03*
X172006D03*
X185206D03*
X180806D03*
X194006D03*
X226500Y649900D03*
X229206Y638753D03*
X224821Y660756D03*
X220421D03*
X198421D03*
X211621D03*
X189621D03*
X202821D03*
X207221D03*
X194021D03*
X185221D03*
X172021D03*
X176421D03*
X180821D03*
X229221D03*
X216021D03*
X292921Y-35764D03*
X287921D03*
X282921D03*
X277921D03*
X272921D03*
X267921D03*
X262921D03*
X257921D03*
X252921D03*
X247921D03*
X242921D03*
X237921D03*
X232921D03*
X292921Y-58764D03*
X287921D03*
X282921D03*
X277921D03*
X272921D03*
X267921D03*
X262921D03*
X257921D03*
X252921D03*
X247921D03*
X242921D03*
X237921D03*
X232921D03*
X234501Y270392D03*
X234000Y320900D03*
X251213Y646784D03*
X290806Y638753D03*
X268806D03*
X273206D03*
X277606D03*
X282006D03*
X260006D03*
X264406D03*
X255606D03*
X251206D03*
X286406D03*
X242406D03*
X246806D03*
X233606D03*
X238006D03*
X251213Y652784D03*
X286421Y660756D03*
X268821D03*
X282021D03*
X273221D03*
X277621D03*
X264421D03*
X251221D03*
X255621D03*
X260021D03*
X246821D03*
X242421D03*
X238021D03*
X233621D03*
X290821D03*
X352921Y-58764D03*
Y-35764D03*
X347921Y-58764D03*
Y-35764D03*
X342921Y-58764D03*
Y-35764D03*
X337921Y-58764D03*
Y-35764D03*
X332921Y-58764D03*
Y-35764D03*
X327921Y-58764D03*
Y-35764D03*
X322921Y-58764D03*
Y-35764D03*
X317921Y-58764D03*
Y-35764D03*
X312921Y-58764D03*
X307921D03*
Y-35764D03*
X302921Y-58764D03*
Y-35764D03*
X297921D03*
Y-58764D03*
X312921Y-35764D03*
X330406Y638753D03*
X348006D03*
X326006D03*
X312806D03*
X317206D03*
X321606D03*
X352406D03*
X295206D03*
X299606D03*
X308406D03*
X304006D03*
X334806D03*
X339206D03*
X343606D03*
X312821Y660756D03*
X317221D03*
X308421D03*
X304021D03*
X352421D03*
X295221D03*
X326021D03*
X321621D03*
X339221D03*
X299621D03*
X334821D03*
X330421D03*
X343621D03*
X348021D03*
X392921Y-35764D03*
X387921Y-58764D03*
Y-35764D03*
X382921Y-58764D03*
Y-35764D03*
X377921Y-58764D03*
Y-35764D03*
X372921Y-58764D03*
Y-35764D03*
X367921Y-58764D03*
Y-35764D03*
X362921Y-58764D03*
Y-35764D03*
X357921Y-58764D03*
Y-35764D03*
X392921Y-58764D03*
X402921Y-35764D03*
X397921Y-58764D03*
Y-35764D03*
X412921Y-58764D03*
Y-35764D03*
X407921Y-58764D03*
Y-35764D03*
X402921Y-58764D03*
X385494Y309904D03*
X367914Y309910D03*
X371237Y309846D03*
X389502Y309910D03*
X389528Y292910D03*
X392694Y292904D03*
X368116Y293087D03*
X371094Y292904D03*
X373736Y293068D03*
X382625Y293207D03*
X378294Y292904D03*
X385494D03*
X392694Y309904D03*
X374994Y309910D03*
X382497D03*
X378577Y309795D03*
X407094Y292904D03*
X396897Y293058D03*
X399894Y292904D03*
X404266Y293030D03*
X407094Y309904D03*
X396709Y309910D03*
X399894Y309904D03*
X404117Y309910D03*
X389473Y646508D03*
X383206Y638753D03*
X387606D03*
X392006D03*
X396406D03*
X400806D03*
X405206D03*
X409606D03*
X414006D03*
X370006D03*
X365606D03*
X374406D03*
X378806D03*
X356806D03*
X361206D03*
X389473Y652508D03*
X374421Y660756D03*
X387621D03*
X383221D03*
X400821D03*
X396421D03*
X392021D03*
X405221D03*
X409621D03*
X414021D03*
X361221D03*
X365621D03*
X356821D03*
X370021D03*
X378821D03*
X477921Y-58764D03*
Y-35764D03*
X472921Y-58764D03*
Y-35764D03*
X467921Y-58764D03*
Y-35764D03*
X462921Y-58764D03*
Y-35764D03*
X457921Y-58764D03*
Y-35764D03*
X452921Y-58764D03*
Y-35764D03*
X447921Y-58764D03*
Y-35764D03*
X442921Y-58764D03*
Y-35764D03*
X437921Y-58764D03*
Y-35764D03*
X432921Y-58764D03*
X422921Y-35764D03*
X417921Y-58764D03*
Y-35764D03*
X432921D03*
X427921Y-58764D03*
Y-35764D03*
X422921Y-58764D03*
X436519Y262232D03*
X436329Y264826D03*
X432643Y264508D03*
X466806Y638753D03*
X462406D03*
X475606D03*
X471206D03*
X418406D03*
X422806D03*
X427206D03*
X440406D03*
X436006D03*
X431606D03*
X449206D03*
X458006D03*
X453606D03*
X444806D03*
X458021Y660756D03*
X449221D03*
X462421D03*
X466821D03*
X471221D03*
X418421D03*
X475621D03*
X453621D03*
X422821D03*
X427221D03*
X440421D03*
X431621D03*
X436021D03*
X444821D03*
X537921Y-58764D03*
Y-35764D03*
X532921Y-58764D03*
Y-35764D03*
X527921Y-58764D03*
Y-35764D03*
X522921Y-58764D03*
Y-35764D03*
X517921Y-58764D03*
Y-35764D03*
X512921Y-58764D03*
Y-35764D03*
X507921Y-58764D03*
Y-35764D03*
X502921Y-58764D03*
Y-35764D03*
X497921Y-58764D03*
Y-35764D03*
X492921Y-58764D03*
Y-35764D03*
X487921Y-58764D03*
Y-35764D03*
X482921Y-58764D03*
Y-35764D03*
X480006Y638753D03*
X484406D03*
X488806D03*
X493206D03*
X497606D03*
X510806D03*
X537206D03*
X519606D03*
X524006D03*
X532806D03*
X528406D03*
X515206D03*
X502006D03*
X506406D03*
X524021Y660756D03*
X480021D03*
X484421D03*
X497621D03*
X493221D03*
X488821D03*
X519621D03*
X532821D03*
X537221D03*
X528421D03*
X515221D03*
X510821D03*
X506421D03*
X502021D03*
X597921Y-35764D03*
Y-58764D03*
X592921Y-35764D03*
Y-58764D03*
X587921Y-35764D03*
Y-58764D03*
X582921Y-35764D03*
Y-58764D03*
X577921Y-35764D03*
Y-58764D03*
X572921Y-35764D03*
Y-58764D03*
X567921Y-35764D03*
Y-58764D03*
X562921Y-35764D03*
Y-58764D03*
X557921Y-35764D03*
Y-58764D03*
X552921Y-35764D03*
Y-58764D03*
X547921D03*
Y-35764D03*
X542921Y-58764D03*
Y-35764D03*
X590006Y638753D03*
X572406D03*
X559206D03*
X568006D03*
X563606D03*
X550406D03*
X581206D03*
X585606D03*
X576806D03*
X598806D03*
X594406D03*
X601500Y649500D03*
X554806Y638753D03*
X541606D03*
X546006D03*
X559221Y660756D03*
X546021D03*
X554821D03*
X598821D03*
X572421D03*
X568021D03*
X563621D03*
X585621D03*
X541621D03*
X594421D03*
X576821D03*
X590021D03*
X581221D03*
X550421D03*
X637921Y-58764D03*
X632921Y-35764D03*
Y-58764D03*
X627921Y-35764D03*
Y-58764D03*
X622921Y-35764D03*
Y-58764D03*
X617921Y-35764D03*
Y-58764D03*
X612921Y-35764D03*
Y-58764D03*
X607921Y-35764D03*
Y-58764D03*
X602921Y-35764D03*
Y-58764D03*
X652921Y-35764D03*
Y-58764D03*
X647921Y-35764D03*
Y-58764D03*
X642921Y-35764D03*
Y-58764D03*
X637921Y-35764D03*
X662921D03*
Y-58764D03*
X657921Y-35764D03*
Y-58764D03*
X638406Y638753D03*
X634006D03*
X642806D03*
X629606D03*
X616406D03*
X612006D03*
X603206D03*
X625206D03*
X651606D03*
X647206D03*
X660406D03*
X620806D03*
X656006D03*
X607606D03*
X607621Y660756D03*
X638421D03*
X647221D03*
X616421D03*
X634021D03*
X612021D03*
X620821D03*
X625221D03*
X629621D03*
X642821D03*
X603221D03*
X656021D03*
X660421D03*
X651621D03*
X692921Y-58764D03*
X687921Y-35764D03*
Y-58764D03*
X682921Y-35764D03*
Y-58764D03*
X677921Y-35764D03*
Y-58764D03*
X672921Y-35764D03*
Y-58764D03*
X667921Y-35764D03*
Y-58764D03*
X697921Y-35764D03*
Y-58764D03*
X692921Y-35764D03*
X722921D03*
Y-58764D03*
X717921Y-35764D03*
Y-58764D03*
X712921Y-35764D03*
Y-58764D03*
X707921Y-35764D03*
Y-58764D03*
X702921Y-35764D03*
Y-58764D03*
X695606Y638753D03*
X673606D03*
X708806D03*
X704406D03*
X700006D03*
X722006D03*
X717606D03*
X713206D03*
X664806D03*
X669206D03*
X686806D03*
X682406D03*
X678006D03*
X691206D03*
X664821Y660756D03*
X695621D03*
X708821D03*
X700021D03*
X704421D03*
X669221D03*
X686821D03*
X691221D03*
X678021D03*
X673621D03*
X682421D03*
X722021D03*
X717621D03*
X713221D03*
X777921Y-58764D03*
X772921Y-35764D03*
Y-58764D03*
X767921Y-35764D03*
Y-58764D03*
X762921Y-35764D03*
Y-58764D03*
X757921Y-35764D03*
Y-58764D03*
X752921Y-35764D03*
Y-58764D03*
X787921Y-35764D03*
Y-58764D03*
X782921Y-35764D03*
Y-58764D03*
X777921Y-35764D03*
X747921D03*
Y-58764D03*
X742921Y-35764D03*
Y-58764D03*
X737921Y-35764D03*
Y-58764D03*
X732921Y-35764D03*
Y-58764D03*
X727921Y-35764D03*
Y-58764D03*
X786674Y211463D03*
X785920Y204763D03*
X786300Y207400D03*
X787200Y244200D03*
Y271900D03*
X787100Y241100D03*
X787200Y276400D03*
X787100Y303900D03*
X787000Y308300D03*
X787400Y340400D03*
X770406Y638753D03*
X779206D03*
X774806D03*
X730806D03*
X726406D03*
X739606D03*
X735206D03*
X748406D03*
X744006D03*
X766006D03*
X761606D03*
X757206D03*
X752806D03*
X783606D03*
X744021Y660756D03*
X735221D03*
X779221D03*
X770421D03*
X774821D03*
X726421D03*
X730821D03*
X739621D03*
X748421D03*
X783621D03*
X757221D03*
X761621D03*
X752821D03*
X766021D03*
X842921Y-35764D03*
X837921Y-58764D03*
Y-35764D03*
X832921Y-58764D03*
X847921D03*
Y-35764D03*
X842921Y-58764D03*
X832921Y-35764D03*
X827921Y-58764D03*
Y-35764D03*
X822921Y-58764D03*
Y-35764D03*
X817921Y-58764D03*
Y-35764D03*
X812921Y-58764D03*
Y-35764D03*
X807921Y-58764D03*
Y-35764D03*
X802921Y-58764D03*
Y-35764D03*
X797921D03*
Y-58764D03*
X792921Y-35764D03*
Y-58764D03*
X816900Y216300D03*
X816874Y212863D03*
X814274D03*
X811674D03*
X808818Y211179D03*
X808618Y208579D03*
X803200Y213100D03*
X800600D03*
X794474Y211463D03*
X791874D03*
X789274D03*
X788522Y204343D03*
X791122Y204339D03*
X829327Y214740D03*
X832276Y214754D03*
X827322Y217430D03*
X826700Y214802D03*
X824072Y214865D03*
X824446Y217476D03*
X821775Y217617D03*
X821466Y214925D03*
X789432Y236947D03*
X789400Y273700D03*
X811983Y244843D03*
Y242243D03*
X814583Y239643D03*
X815432Y237000D03*
X814583Y244843D03*
Y242243D03*
X812832Y237000D03*
X811983Y239643D03*
X802432Y237000D03*
X799832D03*
X792032D03*
X794632D03*
X810232D03*
X797232D03*
X805032D03*
X807632D03*
X791000Y244400D03*
X793600D03*
X816800Y234300D03*
X816900Y230900D03*
X817000Y252500D03*
X789800Y276400D03*
X792400D03*
X801991Y276557D03*
X804591D03*
X792191Y269101D03*
X789591D03*
X814891Y271657D03*
Y274257D03*
Y276857D03*
Y269057D03*
X812291D03*
Y274257D03*
Y276857D03*
Y271657D03*
X817000Y255100D03*
Y257700D03*
X848282Y251727D03*
X828180Y231748D03*
X828682Y237027D03*
X831682D03*
X828682Y234327D03*
X837500Y239500D03*
X845050Y229400D03*
X837500Y234050D03*
Y236650D03*
X834682Y236877D03*
X840155Y234245D03*
X834700Y234200D03*
X831682Y234327D03*
X834682Y239627D03*
X831682D03*
X828682D03*
X848282Y246427D03*
Y249027D03*
X825682Y239627D03*
Y234327D03*
Y237027D03*
X825313Y231753D03*
X848382Y279727D03*
Y277027D03*
Y274427D03*
X825464Y277510D03*
Y274910D03*
Y280110D03*
X822464D03*
Y277510D03*
Y274910D03*
X834464Y280110D03*
X831464D03*
X828464Y277510D03*
Y274910D03*
Y280110D03*
X834464Y277510D03*
X831464D03*
X834464Y274910D03*
X845050Y252250D03*
X817491Y276857D03*
Y274257D03*
Y271657D03*
Y269057D03*
X837264Y274910D03*
Y280110D03*
Y277510D03*
X840064D03*
Y280110D03*
X817183Y242243D03*
Y239643D03*
Y244843D03*
X818032Y237000D03*
X822682Y234327D03*
Y231727D03*
Y237027D03*
Y239627D03*
X831464Y274910D03*
X844400Y280500D03*
X848282Y254327D03*
X788600Y306100D03*
X789500Y301200D03*
X797300D03*
X799900D03*
X810300D03*
X802500D03*
X812900D03*
X807700D03*
X805100D03*
X815500D03*
X811991Y308957D03*
Y306357D03*
Y303757D03*
X814591Y306357D03*
Y308957D03*
Y303757D03*
X792900Y308400D03*
X789900D03*
X794700Y301200D03*
X792100D03*
X793000Y340400D03*
X790300Y340300D03*
X816991Y337357D03*
Y334757D03*
Y339957D03*
X814391D03*
Y337357D03*
Y334757D03*
X811791Y337357D03*
Y339957D03*
Y334757D03*
X791879Y332798D03*
X794600Y332600D03*
X816938Y319888D03*
Y323888D03*
X817100Y317000D03*
X848382Y282327D03*
X834682Y298527D03*
X828682D03*
X825682D03*
Y295527D03*
Y301227D03*
Y303927D03*
X822682D03*
Y301227D03*
Y295527D03*
Y298527D03*
X844300Y312450D03*
X831682Y298527D03*
X837782Y298127D03*
Y301027D03*
Y303927D03*
X818100Y301200D03*
X817191Y303757D03*
Y306357D03*
Y308957D03*
X834682Y301227D03*
X831682D03*
X828682D03*
X831682Y303927D03*
X834682D03*
X822482Y339827D03*
Y337027D03*
X831482D03*
X834482D03*
X828482Y339827D03*
X831482D03*
X834482D03*
X840282Y340227D03*
X840382Y337427D03*
X837382Y339877D03*
Y337077D03*
X847682Y314627D03*
X847982Y338327D03*
Y341327D03*
X828482Y337027D03*
X828682Y303927D03*
X847682Y309327D03*
Y312027D03*
Y306727D03*
X825482Y339827D03*
Y337027D03*
X789860Y364947D03*
X816591Y369857D03*
Y372457D03*
X811391Y369857D03*
X813991D03*
Y372457D03*
X811391D03*
X790900Y372300D03*
X788300Y372400D03*
X802759Y364575D03*
X816672Y358809D03*
X795310Y364721D03*
X816593Y356210D03*
X807959Y364575D03*
X805359D03*
X810559D03*
X815759D03*
X813159D03*
X816900Y361400D03*
X792610Y364821D03*
X816591Y375057D03*
X792238Y396753D03*
X789600Y396809D03*
X792000Y399409D03*
X789400D03*
X822089Y362782D03*
Y359782D03*
X822482Y342827D03*
X828482D03*
X831482D03*
X834482D03*
X828089Y359841D03*
X834089D03*
X831089D03*
X844350Y344000D03*
X840262Y343011D03*
X837382Y342877D03*
X821658Y366863D03*
X847982Y344327D03*
X834089Y362782D03*
X831089D03*
X828089D03*
X825482Y342827D03*
X825089Y359841D03*
Y362782D03*
X849606Y638753D03*
X836406D03*
X832006D03*
X796806D03*
X801206D03*
X792406D03*
X827606D03*
X818806D03*
X823206D03*
X810006D03*
X788006D03*
X845206D03*
X814406D03*
X805606D03*
X840806D03*
X849621Y660756D03*
X832021D03*
X810021D03*
X818821D03*
X836421D03*
X788021D03*
X814421D03*
X801221D03*
X805621D03*
X823221D03*
X827621D03*
X840821D03*
X796821D03*
X792421D03*
X845221D03*
X907921Y-58764D03*
Y-35764D03*
X902921Y-58764D03*
Y-35764D03*
X897921Y-58764D03*
Y-35764D03*
X892921Y-58764D03*
Y-35764D03*
X887921Y-58764D03*
Y-35764D03*
X882921Y-58764D03*
Y-35764D03*
X877921Y-58764D03*
Y-35764D03*
X872921Y-58764D03*
Y-35764D03*
X867921Y-58764D03*
Y-35764D03*
X862921Y-58764D03*
Y-35764D03*
X857921Y-58764D03*
Y-35764D03*
X852921Y-58764D03*
Y-35764D03*
X854282Y251727D03*
X857282D03*
X851282D03*
X857282Y249027D03*
Y246427D03*
X851282D03*
Y249027D03*
X854282D03*
Y246427D03*
X851382Y277027D03*
Y274427D03*
X857382Y277027D03*
X854382Y279727D03*
X857382D03*
X854382Y274427D03*
X857382D03*
X854382Y277027D03*
X874586Y259278D03*
X854282Y254327D03*
X857282D03*
X869586Y254278D03*
X851282Y254327D03*
X851382Y279727D03*
X884586Y269278D03*
X879586Y264278D03*
X889586Y274278D03*
X851382Y282327D03*
X854382D03*
X857382D03*
X851075Y335405D03*
X857075D03*
X856982Y338327D03*
X853982D03*
X856682Y314627D03*
X853682D03*
X850682D03*
X856982Y341327D03*
X853982D03*
X862008Y341100D03*
X850982Y338327D03*
Y341327D03*
X872008Y331100D03*
X867008Y336100D03*
X850682Y306727D03*
Y309327D03*
Y312027D03*
X856682Y309327D03*
X853682D03*
X856682Y306727D03*
X853682D03*
X856682Y312027D03*
X853682D03*
X877008Y326100D03*
X854075Y335405D03*
X856982Y344327D03*
X853982D03*
X850982D03*
X858406Y638753D03*
X854006D03*
X884806D03*
X880406D03*
X876006D03*
X871606D03*
X867206D03*
X911206D03*
X906806D03*
X889206D03*
X898006D03*
X902406D03*
X893606D03*
X862806D03*
X854021Y660756D03*
X858421D03*
X862821D03*
X898021D03*
X902421D03*
X871621D03*
X884821D03*
X893621D03*
X867221D03*
X889221D03*
X911221D03*
X906821D03*
X880421D03*
X876021D03*
X937921Y-35764D03*
X932921Y-58764D03*
Y-35764D03*
X927921Y-58764D03*
Y-35764D03*
X922921Y-58764D03*
Y-35764D03*
X917921Y-58764D03*
Y-35764D03*
X912921Y-58764D03*
Y-35764D03*
X942921D03*
X967921D03*
X962921Y-58764D03*
Y-35764D03*
X957921Y-58764D03*
Y-35764D03*
X952921Y-58764D03*
Y-35764D03*
X947921Y-58764D03*
Y-35764D03*
X942921Y-58764D03*
X972921D03*
Y-35764D03*
X967921Y-58764D03*
X937921D03*
X951795Y646234D03*
X924406Y638753D03*
X920006D03*
X915606D03*
X972806D03*
X968406D03*
X964006D03*
X917100Y649300D03*
X942006Y638753D03*
X937606D03*
X933206D03*
X928806D03*
X959606D03*
X955206D03*
X950806D03*
X946406D03*
X951795Y652234D03*
X959621Y660756D03*
X964021D03*
X968421D03*
X972821D03*
X920021D03*
X915621D03*
X924421D03*
X946421D03*
X942021D03*
X937621D03*
X933221D03*
X928821D03*
X955221D03*
X950821D03*
X1002921Y-58764D03*
Y-35764D03*
X997921Y-58764D03*
Y-35764D03*
X992921Y-58764D03*
Y-35764D03*
X987921Y-58764D03*
Y-35764D03*
X982921Y-58764D03*
Y-35764D03*
X977921Y-58764D03*
Y-35764D03*
X1032921Y-58764D03*
Y-35764D03*
X1027921Y-58764D03*
Y-35764D03*
X1022921Y-58764D03*
Y-35764D03*
X1017921Y-58764D03*
Y-35764D03*
X1012921Y-58764D03*
Y-35764D03*
X1007921Y-58764D03*
Y-35764D03*
X1024994Y292918D03*
X1017630Y292910D03*
X1020702Y292904D03*
X1027902D03*
X1031953Y292910D03*
X1024140Y309910D03*
X1021065Y309759D03*
X1017083Y309910D03*
X1032042D03*
X1028136Y309815D03*
X1003606Y638753D03*
X1012406D03*
X977206D03*
X990406D03*
X986006D03*
X994806D03*
X1016806D03*
X1021206D03*
X981606D03*
X999206D03*
X1025606D03*
X1008006D03*
X1030006D03*
X1034406D03*
X999221Y660756D03*
X1034421D03*
X1030021D03*
X1008021D03*
X1012421D03*
X1003621D03*
X1016821D03*
X977221D03*
X981621D03*
X1021221D03*
X1025621D03*
X994821D03*
X986021D03*
X990421D03*
X1067921Y-58764D03*
Y-35764D03*
X1062921Y-58764D03*
Y-35764D03*
X1057921Y-58764D03*
Y-35764D03*
X1052921Y-58764D03*
Y-35764D03*
X1047921Y-58764D03*
Y-35764D03*
X1042921Y-58764D03*
Y-35764D03*
X1037921Y-58764D03*
Y-35764D03*
X1092921Y-58764D03*
Y-35764D03*
X1087921Y-58764D03*
Y-35764D03*
X1082921Y-58764D03*
Y-35764D03*
X1077921Y-58764D03*
Y-35764D03*
X1072921Y-58764D03*
Y-35764D03*
X1082432Y264620D03*
X1086061Y262300D03*
X1086000Y264900D03*
X1046276Y292910D03*
X1049502Y292904D03*
X1053684Y292910D03*
X1056702Y292904D03*
X1039182Y292919D03*
X1042302Y292904D03*
X1035102D03*
X1049547Y309904D03*
X1046612Y309910D03*
X1056747Y309904D03*
X1053594Y309910D03*
X1042347Y309904D03*
X1039383Y309910D03*
X1035147Y309904D03*
X1086126Y338758D03*
X1083301Y338841D03*
X1096006Y638753D03*
X1078406D03*
X1082806D03*
X1074006D03*
X1069606D03*
X1091606D03*
X1052006D03*
X1038806D03*
X1087206D03*
X1060806D03*
X1056406D03*
X1065206D03*
X1043206D03*
X1047606D03*
X1078421Y660756D03*
X1060821D03*
X1087221D03*
X1038821D03*
X1091621D03*
X1052021D03*
X1074021D03*
X1065221D03*
X1096021D03*
X1056421D03*
X1043221D03*
X1047621D03*
X1082821D03*
X1069621D03*
X1157921Y-58764D03*
Y-35764D03*
X1152921Y-58764D03*
Y-35764D03*
X1147921Y-58764D03*
Y-35764D03*
X1142921Y-58764D03*
Y-35764D03*
X1137921Y-58764D03*
Y-35764D03*
X1132921Y-58764D03*
Y-35764D03*
X1127921Y-58764D03*
Y-35764D03*
X1122921Y-58764D03*
Y-35764D03*
X1117921Y-58764D03*
Y-35764D03*
X1112921Y-58764D03*
Y-35764D03*
X1107921Y-58764D03*
Y-35764D03*
X1102921Y-58764D03*
Y-35764D03*
X1097921Y-58764D03*
Y-35764D03*
X1135606Y638753D03*
X1126806D03*
X1144406D03*
X1140006D03*
X1118006D03*
X1122406D03*
X1153206D03*
X1157606D03*
X1104806D03*
X1100406D03*
X1131206D03*
X1148806D03*
X1109206D03*
X1113606D03*
X1157621Y660756D03*
X1148821D03*
X1122421D03*
X1126821D03*
X1100421D03*
X1118021D03*
X1140021D03*
X1113621D03*
X1109221D03*
X1153221D03*
X1144421D03*
X1104821D03*
X1131221D03*
X1135621D03*
X1217921Y-58764D03*
Y-35764D03*
X1212921Y-58764D03*
Y-35764D03*
X1207921Y-58764D03*
Y-35764D03*
X1202921Y-58764D03*
Y-35764D03*
X1197921Y-58764D03*
Y-35764D03*
X1192921Y-58764D03*
Y-35764D03*
X1187921Y-58764D03*
Y-35764D03*
X1182921Y-58764D03*
Y-35764D03*
X1177921Y-58764D03*
Y-35764D03*
X1172921Y-58764D03*
Y-35764D03*
X1167921Y-58764D03*
Y-35764D03*
X1162921Y-58764D03*
Y-35764D03*
X1196198Y646206D03*
X1188406Y638753D03*
X1214806D03*
X1197206D03*
X1201606D03*
X1192806D03*
X1170806D03*
X1162006D03*
X1166406D03*
X1206006D03*
X1219206D03*
X1179606D03*
X1175206D03*
X1210406D03*
X1184006D03*
X1196198Y652206D03*
X1184021Y660756D03*
X1219221D03*
X1192821D03*
X1188421D03*
X1201621D03*
X1179621D03*
X1214821D03*
X1206021D03*
X1166421D03*
X1210421D03*
X1170821D03*
X1162021D03*
X1175221D03*
X1197221D03*
X1232921Y-58764D03*
Y-35764D03*
X1227921Y-58764D03*
Y-35764D03*
X1222921Y-58764D03*
Y-35764D03*
X1252921Y-58764D03*
Y-35764D03*
X1247921Y-58764D03*
Y-35764D03*
X1242921Y-58764D03*
Y-35764D03*
X1237921Y-58764D03*
Y-35764D03*
X1257921D03*
X1272921Y-58764D03*
Y-35764D03*
X1267921Y-58764D03*
Y-35764D03*
X1262921Y-58764D03*
Y-35764D03*
X1257921Y-58764D03*
X1277921D03*
Y-35764D03*
X1263206Y638753D03*
X1223606D03*
X1228006D03*
X1258806D03*
X1241206D03*
X1236806D03*
X1250006D03*
X1245606D03*
X1276406D03*
X1254406D03*
X1280806D03*
X1272006D03*
X1267606D03*
X1232406D03*
X1228021Y660756D03*
X1232421D03*
X1280821D03*
X1245621D03*
X1236821D03*
X1223621D03*
X1276421D03*
X1241221D03*
X1272021D03*
X1258821D03*
X1250021D03*
X1254421D03*
X1263221D03*
X1267621D03*
X1342921Y-35764D03*
Y-58764D03*
X1317921D03*
X1312921Y-35764D03*
Y-58764D03*
X1307921Y-35764D03*
Y-58764D03*
X1302921Y-35764D03*
Y-58764D03*
X1297921D03*
Y-35764D03*
X1292921Y-58764D03*
Y-35764D03*
X1287921Y-58764D03*
Y-35764D03*
X1282921Y-58764D03*
Y-35764D03*
X1322921D03*
Y-58764D03*
X1317921Y-35764D03*
X1337921D03*
Y-58764D03*
X1332921Y-35764D03*
Y-58764D03*
X1327921Y-35764D03*
Y-58764D03*
X1324806Y638753D03*
X1298406D03*
X1285206D03*
X1294006D03*
X1302806D03*
X1333606D03*
X1338006D03*
X1320406D03*
X1311606D03*
X1329206D03*
X1307206D03*
X1342406D03*
X1289606D03*
X1316006D03*
X1329221Y660756D03*
X1311621D03*
X1316021D03*
X1333621D03*
X1342421D03*
X1285221D03*
X1324821D03*
X1338021D03*
X1298421D03*
X1289621D03*
X1294021D03*
X1320421D03*
X1302821D03*
X1307221D03*
X1402921Y-58764D03*
X1397921D03*
X1402921Y-35764D03*
X1392921Y-58764D03*
X1397921Y-35764D03*
X1387921Y-58764D03*
X1392921Y-35764D03*
X1382921Y-58764D03*
X1387921Y-35764D03*
X1377921Y-58764D03*
X1382921Y-35764D03*
X1372921Y-58764D03*
X1377921Y-35764D03*
X1367921Y-58764D03*
X1362921Y-35764D03*
Y-58764D03*
X1357921Y-35764D03*
Y-58764D03*
X1352921Y-35764D03*
Y-58764D03*
X1347921Y-35764D03*
Y-58764D03*
X1351206Y638753D03*
X1360006D03*
X1404506Y638853D03*
X1355606Y638753D03*
X1386906Y638853D03*
X1364406Y638753D03*
X1391306Y638853D03*
X1346806Y638753D03*
X1400106Y638853D03*
X1382006Y638753D03*
X1377606D03*
X1373206D03*
X1395706Y638853D03*
X1368806Y638753D03*
X1368821Y660756D03*
X1346821D03*
X1355621D03*
X1360021D03*
X1364421D03*
X1351221D03*
X1404521Y660856D03*
X1400121D03*
X1395721D03*
X1386921D03*
X1377621Y660756D03*
X1382021D03*
X1373221D03*
X1391321Y660856D03*
X1407921Y-58764D03*
X1412921Y-35764D03*
X1407921D03*
X1442921Y-58764D03*
X1447921Y-35764D03*
X1437921Y-58764D03*
X1442921Y-35764D03*
X1432921Y-58764D03*
X1437921Y-35764D03*
X1427921Y-58764D03*
X1432921Y-35764D03*
X1422921Y-58764D03*
X1427921Y-35764D03*
X1417921Y-58764D03*
X1422921Y-35764D03*
X1412921Y-58764D03*
X1417921Y-35764D03*
X1462921Y-58764D03*
X1457921D03*
X1462921Y-35764D03*
X1452921Y-58764D03*
X1457921Y-35764D03*
X1447921Y-58764D03*
X1452921Y-35764D03*
X1422106Y638853D03*
X1466106D03*
X1448506D03*
X1457306D03*
X1417706D03*
X1413306D03*
X1461706D03*
X1452906D03*
X1408906D03*
X1444106D03*
X1435306D03*
X1426506D03*
X1430906D03*
X1439706D03*
X1457321Y660856D03*
X1417721D03*
X1413321D03*
X1408921D03*
X1422121D03*
X1426521D03*
X1435321D03*
X1444121D03*
X1439721D03*
X1430921D03*
X1448521D03*
X1452921D03*
X1466121D03*
X1461721D03*
X1502921Y-58764D03*
X1507921Y-35764D03*
X1497921Y-58764D03*
X1502921Y-35764D03*
X1492921Y-58764D03*
X1497921Y-35764D03*
X1487921Y-58764D03*
X1492921Y-35764D03*
X1482921Y-58764D03*
X1487921Y-35764D03*
X1477921Y-58764D03*
X1482921Y-35764D03*
X1472921Y-58764D03*
X1477921Y-35764D03*
X1467921Y-58764D03*
X1472921Y-35764D03*
X1467921D03*
X1527921Y-58764D03*
X1522921D03*
X1527921Y-35764D03*
X1517921Y-58764D03*
X1522921Y-35764D03*
X1512921Y-58764D03*
X1517921Y-35764D03*
X1507921Y-58764D03*
X1512921Y-35764D03*
X1496906Y638853D03*
X1492506D03*
X1501706Y638753D03*
X1506106D03*
X1514906D03*
X1483706Y638853D03*
X1523706Y638753D03*
X1510506D03*
X1488106Y638853D03*
X1474906D03*
X1519306Y638753D03*
X1479306Y638853D03*
X1528106Y638753D03*
X1470506Y638853D03*
X1496921Y660856D03*
X1483721D03*
X1488121D03*
X1492521D03*
X1479321D03*
X1510521Y660756D03*
X1528121D03*
X1523721D03*
X1501721D03*
X1506121D03*
X1514921D03*
X1519321D03*
X1474921Y660856D03*
X1470521D03*
X1587921Y-58764D03*
X1582921D03*
X1587921Y-35764D03*
X1532921D03*
X1542921D03*
X1532921Y-58764D03*
X1537921Y-35764D03*
X1577921Y-58764D03*
X1582921Y-35764D03*
X1572921Y-58764D03*
X1577921Y-35764D03*
X1567921Y-58764D03*
X1572921Y-35764D03*
X1562921Y-58764D03*
X1567921Y-35764D03*
X1557921Y-58764D03*
X1562921Y-35764D03*
X1552921Y-58764D03*
X1557921Y-35764D03*
X1547921Y-58764D03*
X1552921Y-35764D03*
X1542921Y-58764D03*
X1547921Y-35764D03*
X1537921Y-58764D03*
X1580121Y647556D03*
X1555106Y638753D03*
X1555121Y647556D03*
X1590121D03*
X1590106Y638753D03*
X1590121Y643156D03*
X1585121Y647556D03*
X1585106Y638753D03*
X1585121Y643156D03*
X1565121Y647556D03*
X1570121Y643156D03*
X1570106Y638753D03*
X1565106D03*
X1565121Y643156D03*
X1570121Y647556D03*
X1560121D03*
X1560106Y638753D03*
X1560121Y643156D03*
X1575121D03*
X1575106Y638753D03*
X1575121Y647556D03*
X1555121Y643156D03*
X1580106Y638753D03*
X1580121Y643156D03*
X1550121Y647556D03*
X1541306Y638753D03*
X1545706D03*
X1550106D03*
X1550121Y643156D03*
X1536906Y638753D03*
X1532506D03*
X1565121Y651956D03*
X1570121Y660756D03*
Y656356D03*
X1565121Y660756D03*
X1555121Y651956D03*
X1590121Y660756D03*
Y656356D03*
Y651956D03*
X1585121Y660756D03*
Y656356D03*
Y651956D03*
X1580121Y660756D03*
Y656356D03*
Y651956D03*
X1560121Y660756D03*
Y656356D03*
Y651956D03*
X1555121Y660756D03*
Y656356D03*
X1570121Y651956D03*
X1575121D03*
Y656356D03*
Y660756D03*
X1565121Y656356D03*
X1550121Y651956D03*
Y656356D03*
X1541321Y660756D03*
X1550121D03*
X1545721D03*
X1532521D03*
X1536921D03*
X1642921Y-35764D03*
Y-58764D03*
X1637921Y-35764D03*
Y-58764D03*
X1632921Y-35764D03*
Y-58764D03*
X1627921D03*
X1622921D03*
X1627921Y-35764D03*
X1617921Y-58764D03*
X1622921Y-35764D03*
X1612921Y-58764D03*
X1617921Y-35764D03*
X1607921Y-58764D03*
X1612921Y-35764D03*
X1602921Y-58764D03*
X1607921Y-35764D03*
X1597921Y-58764D03*
X1602921Y-35764D03*
X1592921Y-58764D03*
X1597921Y-35764D03*
X1592921D03*
X1647921D03*
Y-58764D03*
X1625106Y638753D03*
X1625121Y647556D03*
X1630121Y643156D03*
X1630106Y638753D03*
X1630121Y647556D03*
X1635121Y643156D03*
X1635106Y638753D03*
X1635121Y647556D03*
X1640121Y643156D03*
Y647556D03*
X1640106Y638753D03*
X1650121Y647556D03*
X1650106Y638753D03*
X1650121Y643156D03*
X1645121Y647556D03*
X1645106Y638753D03*
X1645121Y643156D03*
X1625121D03*
X1620121Y647556D03*
X1620106Y638753D03*
X1620121Y643156D03*
X1615121Y647556D03*
X1615106Y638753D03*
X1615121Y643156D03*
X1610121Y647556D03*
X1610106Y638753D03*
X1610121Y643156D03*
X1605121Y647556D03*
X1605106Y638753D03*
X1605121Y643156D03*
X1600121Y647556D03*
X1600106Y638753D03*
X1600121Y643156D03*
X1595121Y647556D03*
X1595106Y638753D03*
X1595121Y643156D03*
X1625121Y651956D03*
Y660756D03*
X1630121Y651956D03*
Y656356D03*
Y660756D03*
X1635121Y651956D03*
Y656356D03*
Y660756D03*
X1625121Y656356D03*
X1640121D03*
Y651956D03*
X1650121Y660756D03*
Y656356D03*
Y651956D03*
X1645121Y660756D03*
Y656356D03*
Y651956D03*
X1640121Y660756D03*
X1620121D03*
Y656356D03*
Y651956D03*
X1615121Y660756D03*
Y656356D03*
Y651956D03*
X1610121Y660756D03*
Y656356D03*
Y651956D03*
X1605121Y660756D03*
Y656356D03*
Y651956D03*
X1600121Y660756D03*
Y656356D03*
Y651956D03*
X1595121Y660756D03*
Y656356D03*
Y651956D03*
X1692921Y-40764D03*
X1702921Y-54764D03*
X1687921D03*
X1682921D03*
X1677921D03*
X1672921D03*
X1692921D03*
X1697921D03*
X1707921D03*
X1712921D03*
X1697921Y-40764D03*
X1692921Y-50764D03*
X1687921D03*
X1682921D03*
X1677921D03*
X1672921D03*
X1712921D03*
X1707921D03*
X1702921D03*
X1697921Y-45764D03*
X1707921D03*
X1702921D03*
X1712921D03*
X1697921Y-50764D03*
X1667921Y-35764D03*
X1712921D03*
Y-58764D03*
X1707921Y-35764D03*
Y-58764D03*
X1702921Y-35764D03*
Y-58764D03*
X1697921Y-35764D03*
Y-58764D03*
X1687921Y-40764D03*
X1672921Y-45764D03*
X1677921D03*
X1682921D03*
Y-40764D03*
X1687921Y-45764D03*
X1692921D03*
X1667921Y-58764D03*
X1662921Y-35764D03*
Y-58764D03*
X1657921Y-35764D03*
Y-58764D03*
X1652921Y-35764D03*
Y-58764D03*
X1712921Y-40764D03*
X1707921D03*
X1702921D03*
X1677921D03*
X1672921D03*
X1677921Y-35764D03*
Y-58764D03*
X1672921Y-35764D03*
Y-58764D03*
X1682921Y-35764D03*
Y-58764D03*
X1692921Y-35764D03*
Y-58764D03*
X1687921Y-35764D03*
Y-58764D03*
X1690121Y647556D03*
X1710121D03*
X1710106Y638753D03*
X1710121Y643156D03*
X1705121Y647556D03*
X1705106Y638753D03*
X1695121Y643156D03*
X1695106Y638753D03*
X1695121Y647556D03*
X1700121Y643156D03*
X1700106Y638753D03*
X1685121Y647556D03*
X1685106Y638753D03*
X1685121Y643156D03*
X1680121Y647556D03*
X1680106Y638753D03*
X1680121Y643156D03*
X1675121Y647556D03*
X1675106Y638753D03*
X1675121Y643156D03*
X1670121Y647556D03*
X1670106Y638753D03*
X1670121Y643156D03*
X1665121Y647556D03*
X1665106Y638753D03*
X1665121Y643156D03*
X1660121Y647556D03*
X1660106Y638753D03*
X1660121Y643156D03*
X1655121Y647556D03*
X1655106Y638753D03*
X1655121Y643156D03*
X1690121D03*
X1690106Y638753D03*
X1700121Y647556D03*
X1705121Y643156D03*
X1690121Y656356D03*
Y651956D03*
X1710121Y660756D03*
Y656356D03*
Y651956D03*
X1705121Y660756D03*
Y656356D03*
Y651956D03*
X1690121Y660756D03*
X1695121Y651956D03*
Y656356D03*
Y660756D03*
X1685121Y651956D03*
X1680121Y660756D03*
Y656356D03*
Y651956D03*
X1675121Y660756D03*
Y656356D03*
Y651956D03*
X1670121Y660756D03*
Y656356D03*
Y651956D03*
X1665121Y660756D03*
Y656356D03*
Y651956D03*
X1660121Y660756D03*
Y656356D03*
Y651956D03*
X1655121Y660756D03*
Y656356D03*
Y651956D03*
X1685121Y660756D03*
Y656356D03*
X1700121Y651956D03*
Y656356D03*
Y660756D03*
X1737921Y-50764D03*
X1722921Y-45764D03*
X1727921D03*
X1732921D03*
X1747921D03*
X1752921D03*
X1727921Y-54764D03*
X1757921D03*
X1717921D03*
X1722921D03*
X1767921Y-40764D03*
Y-50764D03*
X1762921D03*
X1757921D03*
X1762921Y-54764D03*
X1752921D03*
X1747921D03*
X1742921D03*
X1737921D03*
X1732921D03*
X1772921D03*
X1767921D03*
X1762921Y-40764D03*
X1772921D03*
X1722921Y-50764D03*
X1717921D03*
X1732921D03*
X1757921Y-40764D03*
X1717921Y-45764D03*
Y-58764D03*
X1742921Y-50764D03*
X1747921D03*
X1752921D03*
X1742921Y-58764D03*
X1737921Y-35764D03*
Y-58764D03*
X1732921Y-35764D03*
Y-58764D03*
X1727921Y-35764D03*
Y-58764D03*
X1722921Y-35764D03*
Y-58764D03*
X1717921Y-35764D03*
X1757921Y-45764D03*
X1762921D03*
X1742921D03*
X1752921Y-40764D03*
X1747921D03*
X1742921D03*
X1737921D03*
X1732921D03*
X1727921D03*
X1722921D03*
X1717921D03*
X1727921Y-50764D03*
X1767921Y-45764D03*
X1772921D03*
X1737921D03*
X1772921Y-35764D03*
Y-58764D03*
X1767921Y-35764D03*
Y-58764D03*
X1762921Y-35764D03*
Y-58764D03*
X1757921Y-35764D03*
Y-58764D03*
X1752921Y-35764D03*
Y-58764D03*
X1747921Y-35764D03*
Y-58764D03*
X1742921Y-35764D03*
X1772921Y-50764D03*
X1758000Y250000D03*
X1775121Y643156D03*
Y647556D03*
X1775106Y638753D03*
X1730121Y647556D03*
X1730106Y638753D03*
X1730121Y643156D03*
X1725121Y647556D03*
X1725106Y638753D03*
X1725121Y643156D03*
X1720121Y647556D03*
X1720106Y638753D03*
X1720121Y643156D03*
X1715121Y647556D03*
X1715106Y638753D03*
X1715121Y643156D03*
X1770121Y647556D03*
X1770106Y638753D03*
X1770121Y643156D03*
X1765121Y647556D03*
X1765106Y638753D03*
X1765121Y643156D03*
X1760121Y647556D03*
X1760106Y638753D03*
X1760121Y643156D03*
X1755121Y647556D03*
X1755106Y638753D03*
X1755121Y643156D03*
X1750121Y647556D03*
X1750106Y638753D03*
X1750121Y643156D03*
X1745121Y647556D03*
X1745106Y638753D03*
X1745121Y643156D03*
X1740121Y647556D03*
X1740106Y638753D03*
X1740121Y643156D03*
X1735121Y647556D03*
X1735106Y638753D03*
X1735121Y643156D03*
X1770121Y660756D03*
X1775121D03*
Y656356D03*
Y651956D03*
X1725121Y660756D03*
Y656356D03*
Y651956D03*
X1720121Y660756D03*
Y656356D03*
Y651956D03*
X1715121Y660756D03*
Y656356D03*
Y651956D03*
X1770121D03*
X1765121Y660756D03*
Y656356D03*
Y651956D03*
X1760121Y660756D03*
Y656356D03*
Y651956D03*
X1755121Y660756D03*
Y656356D03*
Y651956D03*
X1750121Y660756D03*
Y656356D03*
Y651956D03*
X1745121Y660756D03*
Y656356D03*
Y651956D03*
X1740121Y660756D03*
Y656356D03*
Y651956D03*
X1735121Y660756D03*
Y656356D03*
Y651956D03*
X1730121Y660756D03*
Y656356D03*
X1770121D03*
X1730121Y651956D03*
X1817921Y-40764D03*
X1832921Y-45764D03*
Y-54764D03*
X1827921D03*
X1822921D03*
X1817921D03*
X1812921D03*
X1807921D03*
X1802921D03*
X1797921D03*
X1792921D03*
X1787921D03*
X1782921D03*
X1777921D03*
X1832921Y-50764D03*
X1827921D03*
X1822921D03*
X1817921D03*
X1812921D03*
X1807921D03*
X1802921D03*
X1797921D03*
X1792921D03*
X1787921D03*
X1782921Y-40764D03*
X1792921D03*
X1802921D03*
X1807921D03*
X1822921D03*
X1827921D03*
X1832921D03*
X1812921D03*
X1797921D03*
X1777921Y-45764D03*
X1782921D03*
X1787921D03*
X1792921D03*
X1797921D03*
X1802921D03*
X1807921D03*
X1812921D03*
X1817921D03*
X1822921D03*
X1787921Y-40764D03*
X1832921Y-35764D03*
Y-58764D03*
X1827921Y-35764D03*
Y-58764D03*
X1822921Y-35764D03*
Y-58764D03*
X1817921Y-35764D03*
Y-58764D03*
X1812921Y-35764D03*
Y-58764D03*
X1807921Y-35764D03*
Y-58764D03*
X1802921Y-35764D03*
Y-58764D03*
X1797921Y-35764D03*
Y-58764D03*
X1792921Y-35764D03*
Y-58764D03*
X1787921Y-35764D03*
Y-58764D03*
X1782921Y-35764D03*
Y-58764D03*
X1777921Y-35764D03*
Y-58764D03*
X1782921Y-50764D03*
X1777921D03*
Y-40764D03*
X1827921Y-45764D03*
X1780121Y643156D03*
X1780106Y638753D03*
X1780121Y647556D03*
X1785121Y643156D03*
X1790121D03*
X1835121Y647556D03*
X1835106Y638753D03*
X1835121Y643156D03*
X1830121Y647556D03*
X1830106Y638753D03*
X1830121Y643156D03*
X1825121Y647556D03*
X1825106Y638753D03*
X1825121Y643156D03*
X1820121Y647556D03*
X1820106Y638753D03*
X1820121Y643156D03*
X1815121Y647556D03*
X1815106Y638753D03*
X1815121Y643156D03*
X1810121Y647556D03*
X1810106Y638753D03*
X1810121Y643156D03*
X1805121Y647556D03*
X1805106Y638753D03*
X1805121Y643156D03*
X1800121Y647556D03*
X1800106Y638753D03*
X1800121Y643156D03*
X1795121Y647556D03*
X1795106Y638753D03*
X1795121Y643156D03*
X1790121Y647556D03*
X1790106Y638753D03*
X1785121Y647556D03*
X1785106Y638753D03*
X1800121Y656356D03*
X1780121Y651956D03*
Y656356D03*
Y660756D03*
X1835121D03*
Y656356D03*
Y651956D03*
X1830121Y660756D03*
Y656356D03*
Y651956D03*
X1825121Y660756D03*
Y656356D03*
Y651956D03*
X1820121Y660756D03*
Y656356D03*
Y651956D03*
X1815121Y660756D03*
Y656356D03*
Y651956D03*
X1810121Y660756D03*
Y656356D03*
Y651956D03*
X1805121Y660756D03*
Y656356D03*
Y651956D03*
X1800121Y660756D03*
Y651956D03*
X1795121Y660756D03*
Y656356D03*
Y651956D03*
X1790121Y660756D03*
Y656356D03*
Y651956D03*
X1785121Y660756D03*
Y656356D03*
Y651956D03*
X1857921Y-45764D03*
X1837921D03*
X1897921D03*
X1892921D03*
X1887921D03*
X1882921D03*
X1877921D03*
X1872921D03*
X1867921D03*
X1862921D03*
X1842921Y-54764D03*
X1852921Y-45764D03*
X1847921D03*
X1842921D03*
X1897921Y-54764D03*
X1892921D03*
X1887921D03*
X1882921D03*
X1877921D03*
X1872921D03*
X1867921D03*
X1862921D03*
X1857921D03*
X1852921D03*
X1847921D03*
X1837921D03*
X1897921Y-50764D03*
X1892921D03*
X1887921D03*
X1882921D03*
X1877921D03*
X1872921D03*
X1867921D03*
X1862921D03*
X1857921D03*
X1852921D03*
X1847921D03*
X1842921D03*
X1837921D03*
X1892921Y-40764D03*
X1897921D03*
X1877921D03*
X1882921D03*
X1887921D03*
X1857921D03*
X1862921D03*
X1867921D03*
X1872921D03*
X1837921D03*
X1842921D03*
X1847921D03*
X1852921D03*
Y-35764D03*
Y-58764D03*
X1847921Y-35764D03*
Y-58764D03*
X1842921Y-35764D03*
Y-58764D03*
X1837921Y-35764D03*
Y-58764D03*
X1862921D03*
X1857921Y-35764D03*
Y-58764D03*
X1882921D03*
X1877921Y-35764D03*
Y-58764D03*
X1872921Y-35764D03*
Y-58764D03*
X1867921Y-35764D03*
Y-58764D03*
X1862921Y-35764D03*
X1897921D03*
Y-58764D03*
X1892921Y-35764D03*
Y-58764D03*
X1887921Y-35764D03*
Y-58764D03*
X1882921Y-35764D03*
X1895121Y647556D03*
X1895106Y638753D03*
X1895121Y643156D03*
X1890121Y647556D03*
X1890106Y638753D03*
X1890121Y643156D03*
X1885121Y647556D03*
X1885106Y638753D03*
X1885121Y643156D03*
X1880121Y647556D03*
X1880106Y638753D03*
X1880121Y643156D03*
X1875121Y647556D03*
X1875106Y638753D03*
X1875121Y643156D03*
X1870121Y647556D03*
X1870106Y638753D03*
X1870121Y643156D03*
X1865121Y647556D03*
X1865106Y638753D03*
X1865121Y643156D03*
X1860121Y647556D03*
X1860106Y638753D03*
X1860121Y643156D03*
X1855121Y647556D03*
X1855106Y638753D03*
X1855121Y643156D03*
X1850121Y647556D03*
X1850106Y638753D03*
X1850121Y643156D03*
X1845121Y647556D03*
X1845106Y638753D03*
X1845121Y643156D03*
X1840121Y647556D03*
X1840106Y638753D03*
X1840121Y643156D03*
X1895121Y660756D03*
Y656356D03*
Y651956D03*
X1890121Y660756D03*
Y656356D03*
Y651956D03*
X1885121Y660756D03*
Y656356D03*
Y651956D03*
X1880121Y660756D03*
Y656356D03*
Y651956D03*
X1875121Y660756D03*
Y656356D03*
Y651956D03*
X1870121Y660756D03*
Y656356D03*
Y651956D03*
X1865121Y660756D03*
Y656356D03*
Y651956D03*
X1860121Y660756D03*
Y656356D03*
Y651956D03*
X1855121Y660756D03*
Y656356D03*
Y651956D03*
X1850121Y660756D03*
Y656356D03*
Y651956D03*
X1845121Y660756D03*
Y656356D03*
Y651956D03*
X1840121Y660756D03*
Y656356D03*
Y651956D03*
X1927921Y-40764D03*
X1947921Y-45764D03*
X1942921D03*
X1937921D03*
X1932921D03*
X1927921D03*
X1922921D03*
X1917921D03*
X1912921D03*
X1907921D03*
X1902921D03*
X1927921Y-50764D03*
X1932921D03*
Y-40764D03*
X1937921D03*
X1942921D03*
X1947921D03*
X1907921Y-50764D03*
X1902921D03*
X1922921Y-40764D03*
X1917921D03*
X1912921D03*
X1907921D03*
X1902921D03*
X1922921Y-54764D03*
X1917921D03*
X1912921D03*
X1907921D03*
X1902921D03*
X1927921D03*
X1932921D03*
X1937921D03*
X1942921D03*
X1947921D03*
X1952921D03*
X1957921D03*
Y-50764D03*
X1952921D03*
X1947921D03*
X1942921D03*
X1937921D03*
X1922921D03*
X1917921D03*
X1912921D03*
X1957921Y-35764D03*
Y-58764D03*
X1952921Y-35764D03*
Y-58764D03*
X1947921Y-35764D03*
Y-58764D03*
X1942921Y-35764D03*
Y-58764D03*
X1937921Y-35764D03*
Y-58764D03*
X1932921Y-35764D03*
Y-58764D03*
X1927921Y-35764D03*
Y-58764D03*
X1922921Y-35764D03*
Y-58764D03*
X1917921Y-35764D03*
Y-58764D03*
X1912921Y-35764D03*
Y-58764D03*
X1907921Y-35764D03*
Y-58764D03*
X1902921Y-35764D03*
Y-58764D03*
X1938150Y70447D03*
X1937950Y73247D03*
X1940750Y73347D03*
X1929961Y73247D03*
X1935350D03*
X1932730Y73310D03*
X1942390Y76040D03*
X1943550Y73347D03*
X1946350Y73447D03*
X1948951Y73448D03*
X1945020Y76060D03*
X1954271Y80449D03*
X1936706Y75987D03*
X1939470Y76000D03*
X1930150Y70447D03*
X1932950D03*
X1935550D03*
X1940950Y70547D03*
X1943750D03*
X1960106Y638753D03*
X1955106D03*
X1950106D03*
X1945121Y647556D03*
Y643156D03*
X1945106Y638753D03*
X1940121Y647556D03*
Y643156D03*
X1940106Y638753D03*
X1935121Y647556D03*
Y643156D03*
X1935106Y638753D03*
X1930106D03*
X1925106D03*
X1920121Y647556D03*
X1910121Y643156D03*
X1910106Y638753D03*
X1905121Y647556D03*
Y643156D03*
X1905106Y638753D03*
X1900121Y647556D03*
X1900106Y638753D03*
X1900121Y643156D03*
X1920106Y638753D03*
X1915121Y647556D03*
X1920121Y643156D03*
X1910121Y647556D03*
X1915106Y638753D03*
X1915121Y643156D03*
X1960121Y656356D03*
Y660756D03*
X1955121Y656356D03*
Y660756D03*
X1950121Y651956D03*
Y656356D03*
Y660756D03*
X1945121Y651956D03*
Y656356D03*
Y660756D03*
X1940121Y651956D03*
Y656356D03*
Y660756D03*
X1935121Y651956D03*
Y656356D03*
Y660756D03*
X1930121Y651956D03*
Y656356D03*
Y660756D03*
X1925121Y651956D03*
Y656356D03*
Y660756D03*
X1920121Y651956D03*
Y656356D03*
X1905121Y651956D03*
Y656356D03*
Y660756D03*
X1900121D03*
Y656356D03*
Y651956D03*
X1915121D03*
Y656356D03*
Y660756D03*
X1920121D03*
X1910121D03*
Y656356D03*
Y651956D03*
X1967921Y-45764D03*
X1962921D03*
Y-40764D03*
X1967921D03*
Y-54764D03*
X1962921D03*
X1967921Y-50764D03*
X1962921D03*
X1967921Y-35764D03*
Y-58764D03*
X1962921Y-35764D03*
Y-58764D03*
X1970121Y647556D03*
Y643156D03*
X1970106Y638753D03*
X1965121Y647556D03*
Y643156D03*
X1965106Y638753D03*
X1970121Y651956D03*
Y656356D03*
Y660756D03*
X1965121Y651956D03*
Y656356D03*
Y660756D03*
G54D20*
X72074Y243282D03*
X65180Y243368D03*
X61800Y243400D03*
X68498Y243368D03*
X49560Y649770D03*
Y644670D03*
X54360D03*
X49560Y649570D03*
Y644670D03*
X54360D03*
X49560Y654670D03*
X54360D03*
X49560D03*
X54360D03*
X214820Y649570D03*
Y644670D03*
X210020D03*
X214820Y649770D03*
Y644670D03*
X210020D03*
X214820Y654670D03*
X210020D03*
X214820D03*
X210020D03*
X238282Y649670D03*
Y644770D03*
Y649870D03*
Y644770D03*
Y654770D03*
D03*
X402404Y649650D03*
Y644550D03*
Y649450D03*
Y644550D03*
Y654550D03*
D03*
X425750Y649400D03*
Y644500D03*
X430550D03*
X425750Y649600D03*
Y644500D03*
X430550D03*
X425750Y654500D03*
X430550D03*
X425750D03*
X430550D03*
X589871Y649379D03*
Y644279D03*
X585071D03*
X589872Y649180D03*
Y644280D03*
X585072D03*
X589871Y654279D03*
X585071D03*
X589872Y654280D03*
X585072D03*
X613298Y649331D03*
Y644231D03*
X618098D03*
X613298Y649131D03*
Y644231D03*
X618098D03*
X613298Y654231D03*
X618098D03*
X613298D03*
X618098D03*
X905515Y649159D03*
Y644259D03*
X900715D03*
X905515Y649359D03*
Y644259D03*
X900715D03*
X905515Y654259D03*
X900715D03*
X905515D03*
X900715D03*
X928952Y649120D03*
Y644220D03*
Y649320D03*
Y644220D03*
Y654220D03*
D03*
X1219041Y649348D03*
Y644248D03*
Y649148D03*
Y644248D03*
Y654248D03*
D03*
X1242450Y649150D03*
Y644250D03*
X1247250D03*
X1242450Y649350D03*
Y644250D03*
X1247250D03*
X1242450Y654250D03*
X1247250D03*
X1242450D03*
X1247250D03*
X1527739Y644278D03*
D03*
Y654278D03*
D03*
X1532539Y649378D03*
Y644278D03*
Y649178D03*
Y644278D03*
Y654278D03*
D03*
G54D11*
X-15354Y109095D03*
X22835Y101221D03*
X17716Y109095D03*
X22835Y116969D03*
X23228Y124843D03*
X17716D03*
X23228Y109095D03*
X-9843D03*
X28346Y101221D03*
Y116969D03*
G54D30*
G01X548049Y-193422D02*
Y-210922D01*
G01X543027Y-193422D02*
X553071D01*
G01X565549Y-199256D02*
Y-210922D01*
G01Y-194589D02*
X565112Y-194297D01*
Y-193714D01*
X565549Y-193422D01*
X565986Y-193714D01*
Y-194297D01*
X565549Y-194589D01*
G01X583049Y-210922D02*
X581739Y-210630D01*
X580429Y-209464D01*
X579555Y-207422D01*
X579119Y-205089D01*
X579555Y-202755D01*
X580429Y-200714D01*
X581739Y-199547D01*
X583049Y-199256D01*
X584359Y-199547D01*
X585669Y-200714D01*
X586542Y-202755D01*
X586761Y-205089D01*
X586542Y-207422D01*
X585669Y-209464D01*
X584359Y-210630D01*
X583049Y-210922D01*
G01X597492Y-215297D02*
X599021Y-216464D01*
X600767Y-216755D01*
X602295Y-216464D01*
X603606Y-215006D01*
X604479Y-212964D01*
Y-199256D01*
G01Y-201589D02*
X603606Y-200422D01*
X602295Y-199547D01*
X600767Y-199256D01*
X599021Y-199839D01*
X597929Y-201005D01*
X597055Y-203047D01*
X596619Y-205089D01*
X596837Y-206839D01*
X597711Y-208881D01*
X599021Y-210339D01*
X600767Y-210922D01*
X602077Y-210630D01*
X603606Y-209464D01*
X604479Y-208298D01*
G01X621979Y-210922D02*
Y-199256D01*
G01Y-201297D02*
X621106Y-200131D01*
X619795Y-199547D01*
X618267Y-199256D01*
X616739Y-199839D01*
X615429Y-201005D01*
X614555Y-202755D01*
X614119Y-205089D01*
X614555Y-207422D01*
X615429Y-209172D01*
X616739Y-210339D01*
X618267Y-210922D01*
X619795Y-210630D01*
X621106Y-209756D01*
X621979Y-208589D01*
G01X648682Y-210922D02*
Y-193422D01*
X653922D01*
X655669Y-194297D01*
X656979Y-196339D01*
X657416Y-198672D01*
X656979Y-201005D01*
X655887Y-202755D01*
X653922Y-203631D01*
X648682D01*
G01X674479Y-210922D02*
Y-199256D01*
G01Y-201297D02*
X673606Y-200131D01*
X672295Y-199547D01*
X670767Y-199256D01*
X669239Y-199839D01*
X667929Y-201005D01*
X667055Y-202755D01*
X666619Y-205089D01*
X667055Y-207422D01*
X667929Y-209172D01*
X669239Y-210339D01*
X670767Y-210922D01*
X672295Y-210630D01*
X673606Y-209756D01*
X674479Y-208589D01*
G01X684774Y-208881D02*
X685866Y-210047D01*
X687394Y-210922D01*
X688704D01*
X690014Y-210339D01*
X690887Y-209464D01*
X691324Y-208298D01*
X691106Y-206547D01*
X690232Y-205672D01*
X686302Y-203922D01*
X685429Y-201880D01*
X685866Y-200422D01*
X686739Y-199547D01*
X688049Y-199256D01*
X689359Y-199547D01*
X690669Y-200422D01*
G01X702274Y-208881D02*
X703366Y-210047D01*
X704894Y-210922D01*
X706204D01*
X707514Y-210339D01*
X708387Y-209464D01*
X708824Y-208298D01*
X708606Y-206547D01*
X707732Y-205672D01*
X703802Y-203922D01*
X702929Y-201880D01*
X703366Y-200422D01*
X704239Y-199547D01*
X705549Y-199256D01*
X706859Y-199547D01*
X708169Y-200422D01*
G01X735746Y-210922D02*
Y-193422D01*
X740112D01*
X741859Y-194297D01*
X743169Y-195464D01*
X744261Y-197213D01*
X745134Y-199256D01*
X745352Y-202172D01*
X745134Y-205089D01*
X744261Y-207131D01*
X743169Y-208881D01*
X741859Y-210047D01*
X740112Y-210922D01*
X735746D01*
G01X752590Y-193422D02*
X758049Y-210922D01*
X763508Y-193422D01*
G01X775549D02*
Y-210922D01*
G01X770527Y-193422D02*
X780571D01*
G01X804872Y-210922D02*
Y-193422D01*
X810549Y-208005D01*
X816226Y-193422D01*
Y-210922D01*
G01X829795Y-201589D02*
X830669Y-200714D01*
X831324Y-199256D01*
X831761Y-197213D01*
X831324Y-195464D01*
X830451Y-194297D01*
X828922Y-193422D01*
X823027D01*
Y-210922D01*
X830232D01*
X831761Y-209756D01*
X832634Y-208005D01*
X833071Y-205964D01*
X832634Y-203922D01*
X831324Y-202172D01*
X829795Y-201589D01*
X823027D01*
G01X647372Y-165922D02*
Y-148422D01*
X653049Y-163005D01*
X658726Y-148422D01*
Y-165922D01*
G01X670549D02*
X669239Y-165630D01*
X667929Y-164464D01*
X667055Y-162422D01*
X666619Y-160089D01*
X667055Y-157755D01*
X667929Y-155714D01*
X669239Y-154547D01*
X670549Y-154256D01*
X671859Y-154547D01*
X673169Y-155714D01*
X674042Y-157755D01*
X674261Y-160089D01*
X674042Y-162422D01*
X673169Y-164464D01*
X671859Y-165630D01*
X670549Y-165922D01*
G01X691979Y-148422D02*
Y-165922D01*
G01Y-163298D02*
X691106Y-164756D01*
X689795Y-165630D01*
X688267Y-165922D01*
X686521Y-165339D01*
X685211Y-163881D01*
X684337Y-162131D01*
X684119Y-160089D01*
X684337Y-158047D01*
X685211Y-156297D01*
X686521Y-154839D01*
X688267Y-154256D01*
X689795Y-154547D01*
X690887Y-155131D01*
X691979Y-156297D01*
G01X702274Y-158047D02*
X709261D01*
X708606Y-156005D01*
X707514Y-154839D01*
X705986Y-154256D01*
X704457Y-154547D01*
X703147Y-155422D01*
X702274Y-157464D01*
X701837Y-159214D01*
Y-160964D01*
X702274Y-162714D01*
X703366Y-164464D01*
X704676Y-165630D01*
X706204Y-165922D01*
X707732Y-165339D01*
X709261Y-163589D01*
G01X723049Y-165922D02*
Y-148422D01*
G01X975549Y-210922D02*
Y-193422D01*
X972929Y-196922D01*
G01Y-210922D02*
X978169D01*
G01X988246Y-208298D02*
X989555Y-209756D01*
X991084Y-210630D01*
X993049Y-210922D01*
X995014Y-210339D01*
X996542Y-209172D01*
X997634Y-207131D01*
X997852Y-204797D01*
X997416Y-202464D01*
X996324Y-201005D01*
X994795Y-199839D01*
X993267Y-199547D01*
X991739Y-199839D01*
X989774Y-201005D01*
X990429Y-193422D01*
X996324D01*
G01X1010549Y-210922D02*
Y-193422D01*
X1007929Y-196922D01*
G01Y-210922D02*
X1013169D01*
G01X1023901Y-196339D02*
X1025211Y-194589D01*
X1026739Y-193714D01*
X1028486Y-193422D01*
X1030669Y-194005D01*
X1032197Y-195464D01*
X1032634Y-197213D01*
X1032416Y-198964D01*
X1031542Y-200422D01*
X1027176Y-203339D01*
X1025211Y-205380D01*
X1023901Y-208298D01*
X1023464Y-210922D01*
X1032634D01*
G01X1041401Y-203631D02*
X1042929Y-201589D01*
X1044239Y-200422D01*
X1045986Y-199839D01*
X1047514Y-200422D01*
X1048606Y-201589D01*
X1049479Y-203339D01*
X1049697Y-205380D01*
X1049479Y-207131D01*
X1048606Y-208881D01*
X1047295Y-210339D01*
X1045767Y-210922D01*
X1044021Y-210339D01*
X1042492Y-208589D01*
X1041619Y-205964D01*
X1041401Y-203047D01*
X1041837Y-199256D01*
X1042492Y-197213D01*
X1043584Y-195172D01*
X1045112Y-193714D01*
X1046641Y-193422D01*
X1048169Y-194005D01*
X1049261Y-195464D01*
G01X962432Y-165922D02*
Y-148422D01*
X967672D01*
X969419Y-149297D01*
X970729Y-151339D01*
X971166Y-153672D01*
X970729Y-156005D01*
X969637Y-157755D01*
X967672Y-158631D01*
X962432D01*
G01X989102Y-149881D02*
X987792Y-149005D01*
X986264Y-148422D01*
X984517D01*
X982552Y-149297D01*
X981024Y-150755D01*
X979932Y-152506D01*
X979059Y-155422D01*
X978840Y-158047D01*
X979277Y-160672D01*
X979932Y-162422D01*
X981242Y-164172D01*
X982771Y-165339D01*
X984299Y-165922D01*
X985827D01*
X987356Y-165339D01*
X988666Y-164464D01*
X989758Y-163298D01*
G01X1003545Y-156589D02*
X1004419Y-155714D01*
X1005074Y-154256D01*
X1005511Y-152213D01*
X1005074Y-150464D01*
X1004201Y-149297D01*
X1002672Y-148422D01*
X996777D01*
Y-165922D01*
X1003982D01*
X1005511Y-164756D01*
X1006384Y-163005D01*
X1006821Y-160964D01*
X1006384Y-158922D01*
X1005074Y-157172D01*
X1003545Y-156589D01*
X996777D01*
G01X1012749Y-171755D02*
X1025849D01*
G01X1031777Y-165922D02*
Y-148422D01*
X1041821Y-165922D01*
Y-148422D01*
G01X1054299Y-165922D02*
X1052552Y-165630D01*
X1051024Y-164464D01*
X1049714Y-162714D01*
X1048840Y-160672D01*
X1048404Y-158339D01*
Y-156005D01*
X1048840Y-153672D01*
X1049714Y-151630D01*
X1051024Y-149881D01*
X1052552Y-148714D01*
X1054299Y-148422D01*
X1056045Y-148714D01*
X1057574Y-149881D01*
X1058884Y-151630D01*
X1059758Y-153672D01*
X1060194Y-156005D01*
Y-158339D01*
X1059758Y-160672D01*
X1058884Y-162714D01*
X1057574Y-164464D01*
X1056045Y-165630D01*
X1054299Y-165922D01*
G01X1128099Y-210922D02*
Y-193422D01*
X1125479Y-196922D01*
G01Y-210922D02*
X1130719D01*
G01X1147345Y-201589D02*
X1148219Y-200714D01*
X1148874Y-199256D01*
X1149311Y-197213D01*
X1148874Y-195464D01*
X1148001Y-194297D01*
X1146472Y-193422D01*
X1140577D01*
Y-210922D01*
X1147782D01*
X1149311Y-209756D01*
X1150184Y-208005D01*
X1150621Y-205964D01*
X1150184Y-203922D01*
X1148874Y-202172D01*
X1147345Y-201589D01*
X1140577D01*
G01X1105140Y-148422D02*
X1110599Y-165922D01*
X1116058Y-148422D01*
G01X1132466Y-165922D02*
X1123732D01*
Y-148422D01*
X1132466D01*
G01X1128972Y-156880D02*
X1123732D01*
G01X1141232Y-165922D02*
Y-148422D01*
X1146691D01*
X1148437Y-149297D01*
X1149529Y-150464D01*
X1149966Y-152797D01*
X1149529Y-155131D01*
X1148219Y-156589D01*
X1146691Y-157464D01*
X1141232D01*
G01X1146691D02*
X1149966Y-165922D01*
G01X1163099Y-166505D02*
X1162662Y-166214D01*
Y-165630D01*
X1163099Y-165339D01*
X1163536Y-165630D01*
Y-166214D01*
X1163099Y-166505D01*
G01X1299916Y-193422D02*
Y-210922D01*
X1291182D01*
G01X1278049D02*
Y-193422D01*
X1280669Y-196922D01*
G01Y-210922D02*
X1275429D01*
G01X1264697Y-196339D02*
X1263387Y-194589D01*
X1261859Y-193714D01*
X1260112Y-193422D01*
X1257929Y-194005D01*
X1256401Y-195464D01*
X1255964Y-197213D01*
X1256182Y-198964D01*
X1257056Y-200422D01*
X1261422Y-203339D01*
X1263387Y-205380D01*
X1264697Y-208298D01*
X1265134Y-210922D01*
X1255964D01*
G01X1238682Y-148422D02*
Y-165922D01*
X1247416D01*
G01X1264479D02*
Y-154256D01*
G01Y-156297D02*
X1263606Y-155131D01*
X1262295Y-154547D01*
X1260767Y-154256D01*
X1259239Y-154839D01*
X1257929Y-156005D01*
X1257055Y-157755D01*
X1256619Y-160089D01*
X1257055Y-162422D01*
X1257929Y-164172D01*
X1259239Y-165339D01*
X1260767Y-165922D01*
X1262295Y-165630D01*
X1263606Y-164756D01*
X1264479Y-163589D01*
G01X1273464Y-171172D02*
X1274774Y-171755D01*
X1276521Y-171172D01*
X1277612Y-170006D01*
X1278486Y-168547D01*
X1279795Y-163881D01*
X1282634Y-154256D01*
G01X1275647D02*
X1279795Y-163881D01*
G01X1292274Y-158047D02*
X1299261D01*
X1298606Y-156005D01*
X1297514Y-154839D01*
X1295986Y-154256D01*
X1294457Y-154547D01*
X1293147Y-155422D01*
X1292274Y-157464D01*
X1291837Y-159214D01*
Y-160964D01*
X1292274Y-162714D01*
X1293366Y-164464D01*
X1294676Y-165630D01*
X1296204Y-165922D01*
X1297732Y-165339D01*
X1299261Y-163589D01*
G01X1309992Y-165922D02*
Y-154256D01*
G01Y-156589D02*
X1311084Y-155422D01*
X1312176Y-154547D01*
X1313704Y-154256D01*
X1314795Y-154547D01*
X1316106Y-155422D01*
G01X1380796Y-165922D02*
Y-148422D01*
X1385162D01*
X1386909Y-149297D01*
X1388219Y-150464D01*
X1389311Y-152213D01*
X1390184Y-154256D01*
X1390402Y-157172D01*
X1390184Y-160089D01*
X1389311Y-162131D01*
X1388219Y-163881D01*
X1386909Y-165047D01*
X1385162Y-165922D01*
X1380796D01*
G01X1399824Y-158047D02*
X1406811D01*
X1406156Y-156005D01*
X1405064Y-154839D01*
X1403536Y-154256D01*
X1402007Y-154547D01*
X1400697Y-155422D01*
X1399824Y-157464D01*
X1399387Y-159214D01*
Y-160964D01*
X1399824Y-162714D01*
X1400916Y-164464D01*
X1402226Y-165630D01*
X1403754Y-165922D01*
X1405282Y-165339D01*
X1406811Y-163589D01*
G01X1417324Y-163881D02*
X1418416Y-165047D01*
X1419944Y-165922D01*
X1421254D01*
X1422564Y-165339D01*
X1423437Y-164464D01*
X1423874Y-163298D01*
X1423656Y-161547D01*
X1422782Y-160672D01*
X1418852Y-158922D01*
X1417979Y-156880D01*
X1418416Y-155422D01*
X1419289Y-154547D01*
X1420599Y-154256D01*
X1421909Y-154547D01*
X1423219Y-155422D01*
G01X1438099Y-154256D02*
Y-165922D01*
G01Y-149589D02*
X1437662Y-149297D01*
Y-148714D01*
X1438099Y-148422D01*
X1438536Y-148714D01*
Y-149297D01*
X1438099Y-149589D01*
G01X1452542Y-170297D02*
X1454071Y-171464D01*
X1455817Y-171755D01*
X1457345Y-171464D01*
X1458656Y-170006D01*
X1459529Y-167964D01*
Y-154256D01*
G01Y-156589D02*
X1458656Y-155422D01*
X1457345Y-154547D01*
X1455817Y-154256D01*
X1454071Y-154839D01*
X1452979Y-156005D01*
X1452105Y-158047D01*
X1451669Y-160089D01*
X1451887Y-161839D01*
X1452761Y-163881D01*
X1454071Y-165339D01*
X1455817Y-165922D01*
X1457127Y-165630D01*
X1458656Y-164464D01*
X1459529Y-163298D01*
G01X1469387Y-165922D02*
Y-154256D01*
G01Y-157172D02*
X1470261Y-155714D01*
X1471571Y-154547D01*
X1473317Y-154256D01*
X1474845Y-154547D01*
X1476156Y-155714D01*
X1476811Y-157755D01*
Y-165922D01*
G01X1487324Y-158047D02*
X1494311D01*
X1493656Y-156005D01*
X1492564Y-154839D01*
X1491036Y-154256D01*
X1489507Y-154547D01*
X1488197Y-155422D01*
X1487324Y-157464D01*
X1486887Y-159214D01*
Y-160964D01*
X1487324Y-162714D01*
X1488416Y-164464D01*
X1489726Y-165630D01*
X1491254Y-165922D01*
X1492782Y-165339D01*
X1494311Y-163589D01*
G01X1505042Y-165922D02*
Y-154256D01*
G01Y-156589D02*
X1506134Y-155422D01*
X1507226Y-154547D01*
X1508754Y-154256D01*
X1509845Y-154547D01*
X1511156Y-155422D01*
G01X1426729Y-193422D02*
X1431969D01*
G01X1429349D02*
Y-210922D01*
G01X1426729D02*
X1431969D01*
G01X1441390Y-193422D02*
X1446849Y-210922D01*
X1452308Y-193422D01*
G01X1464349Y-210922D02*
Y-203047D01*
X1459982Y-193422D01*
G01X1468716D02*
X1464349Y-203047D01*
G01X1551799Y-193422D02*
X1550052Y-194005D01*
X1548742Y-195464D01*
X1547869Y-197213D01*
X1547214Y-199547D01*
X1546996Y-202172D01*
X1547214Y-204797D01*
X1547869Y-207131D01*
X1548742Y-208881D01*
X1550052Y-210339D01*
X1551799Y-210922D01*
X1553545Y-210339D01*
X1554856Y-208881D01*
X1555729Y-207131D01*
X1556384Y-204797D01*
X1556602Y-202172D01*
X1556384Y-199547D01*
X1555729Y-197213D01*
X1554856Y-195464D01*
X1553545Y-194005D01*
X1551799Y-193422D01*
G01X1565151Y-196339D02*
X1566461Y-194589D01*
X1567989Y-193714D01*
X1569736Y-193422D01*
X1571919Y-194005D01*
X1573447Y-195464D01*
X1573884Y-197213D01*
X1573666Y-198964D01*
X1572792Y-200422D01*
X1568426Y-203339D01*
X1566461Y-205380D01*
X1565151Y-208298D01*
X1564714Y-210922D01*
X1573884D01*
G01X1582869Y-211505D02*
X1590729Y-193422D01*
G01X1604299Y-210922D02*
Y-193422D01*
X1601679Y-196922D01*
G01Y-210922D02*
X1606919D01*
G01X1621799Y-193422D02*
X1620052Y-194005D01*
X1618742Y-195464D01*
X1617869Y-197213D01*
X1617214Y-199547D01*
X1616996Y-202172D01*
X1617214Y-204797D01*
X1617869Y-207131D01*
X1618742Y-208881D01*
X1620052Y-210339D01*
X1621799Y-210922D01*
X1623545Y-210339D01*
X1624856Y-208881D01*
X1625729Y-207131D01*
X1626384Y-204797D01*
X1626602Y-202172D01*
X1626384Y-199547D01*
X1625729Y-197213D01*
X1624856Y-195464D01*
X1623545Y-194005D01*
X1621799Y-193422D01*
G01X1635369Y-211505D02*
X1643229Y-193422D01*
G01X1652651Y-196339D02*
X1653961Y-194589D01*
X1655489Y-193714D01*
X1657236Y-193422D01*
X1659419Y-194005D01*
X1660947Y-195464D01*
X1661384Y-197213D01*
X1661166Y-198964D01*
X1660292Y-200422D01*
X1655926Y-203339D01*
X1653961Y-205380D01*
X1652651Y-208298D01*
X1652214Y-210922D01*
X1661384D01*
G01X1674299Y-193422D02*
X1672552Y-194005D01*
X1671242Y-195464D01*
X1670369Y-197213D01*
X1669714Y-199547D01*
X1669496Y-202172D01*
X1669714Y-204797D01*
X1670369Y-207131D01*
X1671242Y-208881D01*
X1672552Y-210339D01*
X1674299Y-210922D01*
X1676045Y-210339D01*
X1677356Y-208881D01*
X1678229Y-207131D01*
X1678884Y-204797D01*
X1679102Y-202172D01*
X1678884Y-199547D01*
X1678229Y-197213D01*
X1677356Y-195464D01*
X1676045Y-194005D01*
X1674299Y-193422D01*
G01X1691799Y-210922D02*
Y-193422D01*
X1689179Y-196922D01*
G01Y-210922D02*
X1694419D01*
G01X1708862D02*
X1709299Y-207131D01*
X1709954Y-203922D01*
X1710827Y-201005D01*
X1711919Y-197797D01*
X1713666Y-193422D01*
X1704932D01*
G01X1599496Y-165922D02*
Y-148422D01*
X1603862D01*
X1605609Y-149297D01*
X1606919Y-150464D01*
X1608011Y-152213D01*
X1608884Y-154256D01*
X1609102Y-157172D01*
X1608884Y-160089D01*
X1608011Y-162131D01*
X1606919Y-163881D01*
X1605609Y-165047D01*
X1603862Y-165922D01*
X1599496D01*
G01X1625729D02*
Y-154256D01*
G01Y-156297D02*
X1624856Y-155131D01*
X1623545Y-154547D01*
X1622017Y-154256D01*
X1620489Y-154839D01*
X1619179Y-156005D01*
X1618305Y-157755D01*
X1617869Y-160089D01*
X1618305Y-162422D01*
X1619179Y-164172D01*
X1620489Y-165339D01*
X1622017Y-165922D01*
X1623545Y-165630D01*
X1624856Y-164756D01*
X1625729Y-163589D01*
G01X1639299Y-148422D02*
Y-165922D01*
G01X1636242Y-154256D02*
X1642356D01*
G01X1653524Y-158047D02*
X1660511D01*
X1659856Y-156005D01*
X1658764Y-154839D01*
X1657236Y-154256D01*
X1655707Y-154547D01*
X1654397Y-155422D01*
X1653524Y-157464D01*
X1653087Y-159214D01*
Y-160964D01*
X1653524Y-162714D01*
X1654616Y-164464D01*
X1655926Y-165630D01*
X1657454Y-165922D01*
X1658982Y-165339D01*
X1660511Y-163589D01*
G54D21*
X324407Y9114D03*
X307675Y17057D03*
Y28014D03*
X331100D03*
Y17057D03*
X334446Y9114D03*
Y28014D03*
X334447Y17057D03*
X307928Y67802D03*
X307675Y54857D03*
X314368Y65814D03*
X331100D03*
X324407Y35957D03*
Y46914D03*
X331100Y54857D03*
X324407Y73757D03*
X334446Y46914D03*
X334447Y54857D03*
Y73757D03*
X334446Y65814D03*
X334447Y35957D03*
X308198Y528863D03*
X307675Y555857D03*
X307984Y566743D03*
X327754Y536957D03*
X334447Y555857D03*
X331100D03*
X334446Y547914D03*
X324407D03*
X334446Y529014D03*
X331100D03*
X311021Y536957D03*
X324407D03*
Y574757D03*
X347833Y585722D03*
X354525D03*
X327754Y585714D03*
X334446Y566814D03*
X331100D03*
X334447Y574757D03*
Y536957D03*
X307675Y593657D03*
X334447D03*
X331100D03*
X401376Y9121D03*
X404722D03*
X401377Y46922D03*
Y35957D03*
X404723Y46922D03*
X401377Y73757D03*
X404723D03*
Y35957D03*
Y547922D03*
X401376D03*
X404723Y536957D03*
X401377Y574757D03*
X404723Y585722D03*
X401377D03*
X404723Y574757D03*
X401377Y536957D03*
X438187Y9120D03*
X428147D03*
X434840D03*
X421456Y28022D03*
Y17057D03*
Y65822D03*
X438189Y46922D03*
Y35957D03*
X428149D03*
Y46922D03*
X421456Y54857D03*
X434842Y46922D03*
Y35957D03*
X438189Y73757D03*
X428149D03*
X434842D03*
X438189Y536957D03*
X434842Y547922D03*
X421456Y555857D03*
X428149Y547922D03*
X438189D03*
X428149Y536957D03*
X438189Y585722D03*
X434842Y574757D03*
X421456Y566822D03*
X428149Y574757D03*
X438189D03*
X434842Y585722D03*
X428149D03*
X434842Y536957D03*
X421456Y529022D03*
Y593657D03*
X957283Y28014D03*
Y17057D03*
X957536Y67802D03*
X957283Y54857D03*
X963976Y65814D03*
X957806Y528863D03*
X957283Y555857D03*
X957592Y566743D03*
X960629Y536957D03*
X957283Y593657D03*
X984055Y17057D03*
X980708D03*
X984054Y9114D03*
X974015D03*
X984054Y28014D03*
X980708D03*
X984054Y65814D03*
X980708D03*
X984055Y73757D03*
X974015D03*
Y35957D03*
Y46914D03*
X984055Y54857D03*
X980708D03*
X984054Y46914D03*
X984055Y35957D03*
X977362Y536957D03*
X974015D03*
X984055D03*
X980708Y529014D03*
X974015Y547914D03*
X984054D03*
X997441Y585722D03*
X974015Y574757D03*
X984055D03*
X980708Y555857D03*
Y566814D03*
X984055Y555857D03*
X984054Y566814D03*
X977362Y585714D03*
X1004133Y585722D03*
X984054Y529014D03*
X980708Y593657D03*
X984055D03*
X1071064Y17057D03*
X1087797Y9122D03*
X1050985D03*
X1071064Y28022D03*
X1084450Y9122D03*
X1077757D03*
X1054331D03*
X1071064Y65822D03*
X1054331Y73757D03*
X1050985D03*
X1087797D03*
X1084450D03*
X1077757D03*
X1084450Y35957D03*
Y46922D03*
X1071064Y54857D03*
X1077757Y35957D03*
Y46922D03*
X1054331Y35957D03*
Y46922D03*
X1087797Y35957D03*
Y46922D03*
X1050985Y35957D03*
Y46922D03*
Y536957D03*
X1054331D03*
X1050984Y547922D03*
X1054331D03*
X1050985Y574757D03*
X1054331D03*
X1050985Y585722D03*
X1054331D03*
X1084450Y547922D03*
X1087797Y536957D03*
X1077757D03*
X1071064Y529022D03*
X1084450Y536957D03*
X1087797Y547922D03*
X1071064Y555857D03*
Y566822D03*
X1084450Y574757D03*
X1087797Y585722D03*
X1084450D03*
X1087797Y574757D03*
X1077757Y547922D03*
Y585722D03*
Y574757D03*
X1071064Y593657D03*
X1445454Y276753D03*
X1442304Y279902D03*
X1448603Y270454D03*
X1461300Y270400D03*
X1442304Y273603D03*
X1454902D03*
X1464351Y279902D03*
X1461202Y311397D03*
X1445454D03*
X1458052Y314546D03*
X1448603Y317696D03*
X1458400Y318500D03*
X1454902Y301948D03*
X1461202D03*
X1458052Y286202D03*
X1483247Y270454D03*
X1470649Y305098D03*
X1480098Y298798D03*
X1495651Y311350D03*
X1493400Y300800D03*
X1489546Y286202D03*
X1497509Y303120D03*
X1489546Y311397D03*
X1492700Y311376D03*
X1476948Y286202D03*
X1604000Y93925D03*
X1594565Y148720D03*
X1595390Y151778D03*
X1642084Y115494D03*
X1648387Y112341D03*
X1645237Y109191D03*
X1607441Y112341D03*
X1610591Y118640D03*
X1600490Y110766D03*
X1607441Y115491D03*
X1616848Y115449D03*
X1629489Y115491D03*
X1607239Y131358D03*
X1604292Y137538D03*
X1626364Y121765D03*
X1623200Y153100D03*
X1626339Y109191D03*
Y115491D03*
X1613741Y150137D03*
Y134389D03*
Y137538D03*
X1610591Y150137D03*
Y137538D03*
Y140688D03*
Y156436D03*
X1642101Y162749D03*
X1648386Y165885D03*
X1613741Y159585D03*
X1626339Y165884D03*
Y159585D03*
X1643662Y172609D03*
X1660985Y118640D03*
X1667284Y115491D03*
X1670434D03*
X1657835Y112341D03*
X1664135Y115491D03*
X1660985Y162735D03*
Y165885D03*
X1717014Y148950D03*
Y97550D03*
Y104850D03*
Y111150D03*
Y133200D03*
X1743500Y96400D03*
X1735914Y101700D03*
X1745364Y117450D03*
Y98550D03*
X1745363Y108004D03*
X1746189Y131624D03*
X1745364Y142650D03*
X1726464Y117450D03*
X1720164Y117451D03*
Y123750D03*
X1723314D03*
X1745768Y111743D03*
X1745364Y123750D03*
X1742214D03*
Y114300D03*
G54D12*
G01X38645Y172740D02*
X44291Y178386D01*
G01X38645Y184032D02*
X44291Y178386D01*
G01X-7615Y172740D02*
X-1969Y178386D01*
G01D02*
X3677Y184032D01*
G01X-7615D02*
X-1969Y178386D01*
G01D02*
X3677Y172740D01*
G01X12582D02*
X18228Y178386D01*
G01D02*
X23874Y184032D01*
G01X12582D02*
X18228Y178386D01*
G01D02*
X23874Y172740D01*
G01X430749Y-124922D02*
G02I-12000J0D01*
G01X425599D02*
G02I-6850J0D01*
G01X434749D02*
X402749D01*
G01X434749Y-140922D02*
Y-220922D01*
G01D02*
X1729349D01*
G01X434749Y-176422D02*
X1729349D01*
G01X418749Y-140922D02*
Y-108922D01*
G01X434749Y-140922D02*
X1729349D01*
G01X771232Y214033D02*
X773232Y216033D01*
X778547D01*
X780547Y218033D01*
Y235999D01*
X782411Y237863D01*
Y244940D01*
X780924Y246427D01*
X780435D01*
X780411Y246451D01*
X771650D01*
G01Y278451D02*
Y275550D01*
X767100Y271000D01*
Y262500D01*
X770200Y259400D01*
Y247901D01*
X771650Y246451D01*
G01Y278451D02*
X770144Y279957D01*
Y289877D01*
X760448Y299573D01*
Y303426D01*
X763850Y306828D01*
X766793D01*
X770283Y310318D01*
X771318D01*
X771600Y310600D01*
G01D02*
X769507Y312693D01*
Y322029D01*
X763153Y328383D01*
Y336116D01*
X769538Y342501D01*
X771700D01*
G01X771400Y374400D02*
X773200Y376200D01*
X779110D01*
X782282Y373028D01*
Y371768D01*
X786368Y367682D01*
X794706D01*
X795088Y367300D01*
X818401D01*
X818838Y366863D01*
X821658D01*
G01X941849Y-140922D02*
Y-220922D01*
G01X1079349Y-140922D02*
Y-220922D01*
G01X1194349Y-140922D02*
Y-220922D01*
G01X1325125Y100001D02*
Y97375D01*
X1317350Y89600D01*
X1317300D01*
G01X1336500Y81100D02*
X1332608Y77208D01*
Y62459D01*
X1328788Y58639D01*
X1326127D01*
X1324127Y56639D01*
Y50827D01*
G01X1336500Y81100D02*
X1342400D01*
X1343956Y79544D01*
X1349479D01*
X1351500Y81565D01*
Y83000D01*
G01X1361849Y-140922D02*
Y-220922D01*
G01X1448800Y427800D02*
X1446500D01*
G01X1531849Y-140922D02*
Y-220922D01*
G01X1729349Y-140922D02*
Y-220922D01*
G01X1757349Y-124922D02*
G02I-12000J0D01*
G01X1752199D02*
G02I-6850J0D01*
G01X1745349Y-140922D02*
Y-108922D01*
G01X1761349Y-124922D02*
X1729349D01*
G01X1719560Y501770D02*
Y503900D01*
X1716490Y506970D01*
G01X1905092Y150170D02*
X1902230D01*
X1891400Y161000D01*
X1886200D01*
G01X1920472Y447930D02*
X1929892Y457350D01*
X1936300D01*
X1951550Y472600D01*
Y486790D01*
X1946310Y492030D01*
Y509430D01*
X1949500Y512620D01*
Y536093D01*
X1950905Y537498D01*
Y549195D01*
X1946900Y553200D01*
X1943400D01*
X1940300Y556300D01*
Y568305D01*
X1937600Y571005D01*
Y572995D01*
X1940300Y575695D01*
Y584416D01*
X1934790Y589926D01*
Y591095D01*
X1933385Y592500D01*
X1932216D01*
X1926516Y598200D01*
X1900450D01*
X1897505Y595255D01*
X1896358D01*
G01X1946500Y104974D02*
X1940986Y110488D01*
Y131614D01*
X1937800Y134800D01*
Y138100D01*
X1942200Y142500D01*
Y152695D01*
X1958500Y168995D01*
Y200103D01*
X1957334Y201269D01*
G01X1939300Y204300D02*
X1918282D01*
X1913914Y208668D01*
Y213558D01*
X1910123Y217349D01*
G01X1924754Y495775D02*
X1927254Y493275D01*
G01X1924754Y492523D02*
Y495775D01*
G01X1932097Y493275D02*
X1934597Y495775D01*
G01D02*
X1937097Y493275D01*
X-15000Y247400D03*
Y262700D03*
X-17014Y455604D03*
X-18160Y522609D03*
X-16726Y503651D03*
X-10850Y30800D03*
X-8610Y59810D03*
X-1750Y43320D03*
X-1920Y47290D03*
X8700Y49700D03*
X-3560Y34620D03*
X-13610Y64360D03*
X-9987Y50899D03*
X-7050Y50900D03*
X-10470Y64450D03*
X-8370Y62600D03*
X-6010Y61030D03*
X-9390Y67410D03*
X5500Y77444D03*
X5600Y80444D03*
X11625Y81267D03*
X9125D03*
X11200Y49600D03*
X14010Y49570D03*
X11925Y74867D03*
X11864Y71294D03*
X11539Y39927D03*
X11500Y43400D03*
X11539Y47127D03*
X11864Y78494D03*
X46900Y139750D03*
Y144750D03*
Y130750D03*
Y116750D03*
Y111750D03*
Y125750D03*
X7995Y285385D03*
X-6100Y464840D03*
X2350Y469650D03*
X-6650Y487800D03*
X-5690Y467840D03*
X34300Y482890D03*
X31477Y482788D03*
X6748Y517021D03*
X3354Y517143D03*
X-4100Y554400D03*
X-8318Y542216D03*
X6200Y531300D03*
X-8200Y578600D03*
X6200Y567300D03*
X-2500Y569500D03*
X-4300Y558400D03*
X1400Y556500D03*
X-1200D03*
X1439Y546583D03*
Y553783D03*
X1539Y550183D03*
Y586183D03*
X1439Y582583D03*
X-900Y592500D03*
X1600D03*
X-4500Y594000D03*
X1439Y589783D03*
X67564Y-20745D03*
X65164Y-19456D03*
X104500Y-1850D03*
X63683Y-12866D03*
X66061Y-13689D03*
X62008Y13249D03*
X62536Y-2379D03*
X61994Y362D03*
X75660Y152380D03*
X78950Y152810D03*
X51381Y104750D03*
Y109750D03*
X102507Y211047D03*
X107700Y211040D03*
X61800Y191600D03*
X64187Y176332D03*
X86731Y189148D03*
X74800Y338850D03*
X69000Y338800D03*
X72000D03*
X64000Y313900D03*
Y316500D03*
X77600Y320800D03*
X100550Y335140D03*
X66350Y347950D03*
X63800Y348600D03*
X50510Y359240D03*
X47970Y359550D03*
X55500Y521800D03*
X53000Y524300D03*
Y521800D03*
X58000D03*
X55500Y519300D03*
X52992Y516846D03*
X58000Y524300D03*
X57936Y519212D03*
X53900Y505450D03*
X57100D03*
X60300D03*
X55500Y524300D03*
X53000Y519300D03*
X53900Y502250D03*
X60300D03*
X57100D03*
X102236Y614167D03*
X91150Y618250D03*
X93800Y618111D03*
X63500Y602000D03*
X132959Y-4100D03*
X130313Y-9901D03*
X126580Y-4100D03*
X123620Y-9901D03*
X147045D03*
X141880Y-7260D03*
X136806Y-7050D03*
X136780Y-4401D03*
X130313Y17157D03*
X132959Y12114D03*
X123620Y17157D03*
X126666Y12114D03*
X147045Y17157D03*
X141880Y14514D03*
X136780Y14300D03*
X141880Y11914D03*
X136780Y11700D03*
X163391Y-4100D03*
X160431Y-9901D03*
X157084Y-3700D03*
X153738Y-9901D03*
X150391Y-3700D03*
X169770Y-4100D03*
X167124Y-9901D03*
X160431Y17157D03*
X163477Y12114D03*
X153738Y17157D03*
X157084Y12114D03*
X150391D03*
X167124Y17157D03*
X169770Y12114D03*
X141880Y-4651D03*
X124340Y197750D03*
X141263Y215216D03*
X137763Y217716D03*
X141263D03*
X137763Y215216D03*
X169150Y223600D03*
Y227600D03*
X141263Y234216D03*
X141200Y229600D03*
X141211Y225615D03*
X141300Y221700D03*
X139763Y231700D03*
Y227600D03*
Y223700D03*
X139582Y219800D03*
X125563Y234316D03*
X125663Y230716D03*
X125563Y227116D03*
X141263Y249716D03*
Y247216D03*
X137763D03*
Y249716D03*
X125563Y259116D03*
X125663Y262716D03*
X125563Y266316D03*
X141300Y253700D03*
X139631Y251900D03*
X137763Y279216D03*
X141263Y266216D03*
X139763Y255700D03*
Y259600D03*
X139800Y263700D03*
X141313Y257533D03*
X141263Y279216D03*
X141200Y261600D03*
X137300Y337200D03*
X125663Y294716D03*
X125563Y298316D03*
Y291116D03*
X141263Y311216D03*
X137763D03*
X141263Y281716D03*
X139730Y284200D03*
X139763Y288200D03*
Y292000D03*
Y296000D03*
X141200Y286100D03*
X141261Y290076D03*
X141300Y294000D03*
X141263Y298216D03*
X137763Y281716D03*
X141211Y325515D03*
X141263Y330216D03*
X139763Y327800D03*
X141300Y317500D03*
Y321500D03*
X139582Y315800D03*
X139763Y319400D03*
X125563Y323116D03*
X125663Y326716D03*
X125563Y330316D03*
X141263Y313716D03*
X137763D03*
X139763Y323600D03*
X141289Y349488D03*
X141300Y353300D03*
X141200Y357200D03*
X137763Y345716D03*
X141263D03*
Y343216D03*
X137763D03*
X125563Y362316D03*
Y355116D03*
X125663Y358716D03*
X141263Y362216D03*
X139582Y347800D03*
X139763Y351400D03*
Y355200D03*
Y359500D03*
X141300Y381800D03*
X139763Y384000D03*
X141263Y394216D03*
Y390416D03*
X141261Y385876D03*
X139736Y392300D03*
X125663Y390716D03*
X125563Y387116D03*
Y394316D03*
X137763Y375216D03*
X141263D03*
Y377716D03*
X137763D03*
X139631Y379900D03*
X139900Y388000D03*
X121981Y405573D03*
X119100Y411600D03*
X119016Y414201D03*
X119398Y406348D03*
X122242Y419199D03*
X123441Y421795D03*
X111961Y499877D03*
X112427Y497225D03*
X132959Y588714D03*
X136780Y588300D03*
X141880Y588514D03*
X169770Y588714D03*
X150391D03*
X126666D03*
X157084D03*
X163477D03*
X130313Y604499D03*
X136780Y609999D03*
X141880Y607140D03*
Y591114D03*
X136806Y607350D03*
X136780Y590900D03*
X167124Y604499D03*
Y593757D03*
X169770Y610300D03*
X147045Y604499D03*
X150391Y610700D03*
X147045Y593757D03*
X123620Y604499D03*
X126580Y610300D03*
X123620Y593757D03*
X153738Y604499D03*
X157084Y610700D03*
X153738Y593757D03*
X160431Y604499D03*
X163391Y610300D03*
X160431Y593757D03*
X132959Y610300D03*
X130313Y593757D03*
X141880Y609749D03*
X193895Y-3700D03*
X190549Y-9901D03*
X187202Y-3700D03*
X183856Y-9901D03*
X206581Y-4100D03*
X203935Y-9901D03*
X200202Y-4100D03*
X197242Y-9901D03*
X173617Y-7050D03*
X210428D03*
X173591Y-4401D03*
X210402D03*
X178691Y-4651D03*
X190549Y17157D03*
X193895Y12114D03*
X183856Y17157D03*
X187202Y12114D03*
X203935Y17157D03*
X206581Y12114D03*
X197242Y17157D03*
X200288Y12114D03*
X173591Y14300D03*
X210402D03*
X178691Y14514D03*
X173591Y11700D03*
X210402D03*
X178691Y11914D03*
X224013Y-3700D03*
X220667Y-9901D03*
X215502Y-7260D03*
Y-4651D03*
X230706Y-3700D03*
X227360Y-9901D03*
Y17157D03*
X230706Y12114D03*
X220667Y17157D03*
X224013Y12114D03*
X215502Y14514D03*
Y11914D03*
X178691Y-7260D03*
X206800Y246500D03*
X203947Y280933D03*
X195233Y348402D03*
X210402Y588300D03*
X173591D03*
X215502Y588514D03*
X178691D03*
X224013Y588714D03*
X200288D03*
X230706D03*
X206581D03*
X187202D03*
X193895D03*
X173617Y607350D03*
X173591Y590900D03*
X215502Y607140D03*
Y591114D03*
X178691D03*
X173591Y609999D03*
X215502Y609749D03*
X178691D03*
X210402Y590900D03*
X210428Y607350D03*
X220667Y604499D03*
X224013Y610700D03*
X220667Y593761D03*
X197242Y604499D03*
Y593757D03*
X200202Y610300D03*
X227360Y604499D03*
X230706Y610700D03*
X227360Y593757D03*
X203935Y604499D03*
X206581Y610300D03*
X203935Y593757D03*
X183856Y604499D03*
Y593757D03*
X187202Y610700D03*
X190549Y604499D03*
Y593757D03*
X193895Y610700D03*
X178691Y607140D03*
X210402Y609999D03*
X243392Y-4100D03*
X240746Y-9901D03*
X267517Y-3700D03*
X264171Y-9901D03*
X237013Y-4100D03*
X234053Y-9901D03*
X260824Y-3700D03*
X257478Y-9901D03*
X252313Y-7260D03*
X247213Y-4401D03*
X252313Y-4651D03*
X270864Y-9901D03*
Y27899D03*
X240746Y17157D03*
X243392Y12114D03*
X264171Y17157D03*
X267517Y12114D03*
X234053Y17157D03*
X237099Y12114D03*
X257478Y17157D03*
X260824Y12114D03*
X247213Y14300D03*
X252313Y14514D03*
X247213Y11700D03*
X252313Y11914D03*
X270864Y17157D03*
X284050Y-7050D03*
X289124Y-7260D03*
Y-4651D03*
X280203Y-4100D03*
X277557Y-9901D03*
X273824Y-4100D03*
X289124Y33149D03*
X284024Y33399D03*
X280203Y33700D03*
X277557Y27899D03*
X273824Y33700D03*
X284024Y14300D03*
X289124Y14514D03*
X284024Y11700D03*
X289124Y11914D03*
X277557Y17157D03*
X280203Y12114D03*
X273910D03*
X247239Y-7050D03*
X284024Y-4401D03*
X284050Y30750D03*
X289124Y30540D03*
X270864Y54957D03*
X284024Y52100D03*
X289124Y49714D03*
X284024Y49500D03*
X289124Y52314D03*
X277557Y54957D03*
X280203Y49914D03*
X273910D03*
X270864Y112327D03*
X284024Y110514D03*
X289124Y107655D03*
X284050Y107865D03*
X289150Y110264D03*
X277557Y112327D03*
X280203Y106934D03*
X273910Y107284D03*
X271239Y277360D03*
X267392Y276000D03*
X267359Y279310D03*
X288139D03*
X274619D03*
X281379D03*
X239778Y274478D03*
X270939Y316160D03*
X270892Y304660D03*
Y311960D03*
Y300760D03*
Y308560D03*
Y292959D03*
Y289060D03*
X271239Y281260D03*
X270892Y285500D03*
Y296860D03*
X267359Y283209D03*
X281379Y302709D03*
X288139D03*
X291519Y304660D03*
X281379Y306609D03*
Y310509D03*
X288139Y306609D03*
X284759Y304660D03*
X281379Y287109D03*
X288139Y291009D03*
X284759Y289060D03*
Y281260D03*
X291519Y289060D03*
Y281260D03*
Y296860D03*
X288139Y298809D03*
X274619Y306609D03*
Y310509D03*
X277999Y304660D03*
X274619Y302709D03*
Y298809D03*
Y294909D03*
X277999Y289060D03*
Y281260D03*
X274619Y283209D03*
Y287109D03*
Y291009D03*
X277999Y296860D03*
X288139Y283209D03*
Y287109D03*
X281379Y298809D03*
Y294909D03*
X288139D03*
X284759Y296860D03*
X281379Y291009D03*
Y283209D03*
X277999Y312460D03*
X274619Y314409D03*
X289124Y493344D03*
X284039Y495944D03*
X273992Y493744D03*
X271092Y498644D03*
X280203Y493244D03*
X277557Y498644D03*
X289124Y495944D03*
X284039Y493344D03*
X284024Y588300D03*
X289124Y550714D03*
X284024Y553100D03*
X273910Y550914D03*
X270864Y555957D03*
X280203Y550914D03*
X277557Y555957D03*
X289124Y553314D03*
X284024Y550500D03*
X280203Y588714D03*
X247213Y588300D03*
X289124Y588514D03*
X252313D03*
X260824Y588714D03*
X237099D03*
X267517D03*
X243392D03*
X273910D03*
X247213Y590900D03*
X247239Y607350D03*
X277557Y604499D03*
X280203Y610300D03*
X277557Y593757D03*
X289124Y607140D03*
Y591114D03*
X252313Y607140D03*
Y591114D03*
X289124Y609749D03*
X252313D03*
X284050Y607350D03*
X284024Y590900D03*
X257478Y604499D03*
Y593757D03*
X260824Y610700D03*
X234053Y604499D03*
Y593757D03*
X237013Y610300D03*
X264171Y604499D03*
X267517Y610700D03*
X264171Y593757D03*
X240746Y604499D03*
Y593757D03*
X243392Y610300D03*
X270864Y604499D03*
X273824Y610300D03*
X270864Y593757D03*
X284024Y609999D03*
X247213D03*
X308157Y-7180D03*
X324407Y-4536D03*
X304328Y-3700D03*
X300982Y-9901D03*
X297635Y-3700D03*
X294289Y-9901D03*
X300982Y27899D03*
X294289D03*
X300982Y17157D03*
X304328Y12114D03*
X294289Y17157D03*
X297635Y12114D03*
X334447Y-1743D03*
Y-7108D03*
X331100Y-9786D03*
X300982Y54957D03*
X304328Y34100D03*
Y49914D03*
X294289Y54957D03*
X297635Y34100D03*
Y49914D03*
X331100Y89964D03*
X307675Y92657D03*
X324407Y84599D03*
X334447Y92757D03*
Y87392D03*
X300982Y109700D03*
X304178Y107684D03*
X294889Y110927D03*
X297635Y105084D03*
X327092Y103021D03*
X352357Y218860D03*
X342218Y205210D03*
X348978D03*
X355737Y213009D03*
X345598Y207159D03*
X342218Y209109D03*
X294899Y232509D03*
X301659Y244209D03*
Y232509D03*
X318558Y222760D03*
X311798Y234460D03*
X305039Y238360D03*
X294899Y240309D03*
X311798Y226660D03*
X318558Y230559D03*
X305039Y257860D03*
X328698Y255909D03*
X325318Y261760D03*
X294899Y252009D03*
X301659Y263709D03*
Y252009D03*
X294899Y259809D03*
X332078Y261760D03*
X348978Y224709D03*
X345598Y242260D03*
X338838Y261760D03*
X335458Y255909D03*
X298279Y230559D03*
X305039Y242260D03*
X294899Y236409D03*
X311798Y230559D03*
X318558Y234460D03*
X321938Y224709D03*
X315178Y236409D03*
Y224709D03*
X321938Y228610D03*
X298279Y250060D03*
Y242260D03*
X305039Y234460D03*
X321938Y232509D03*
X298279Y238360D03*
X315178Y228610D03*
X301659Y236409D03*
X298279Y261760D03*
X328698Y263709D03*
X325318Y257860D03*
X305039Y261760D03*
X294899Y255909D03*
X305039Y253960D03*
X332078D03*
Y265660D03*
X301659Y255909D03*
X332078Y257860D03*
X298279D03*
X301659Y279310D03*
X308418D03*
X294899D03*
X352357Y222760D03*
Y246160D03*
X345598D03*
X338838Y257860D03*
X335458Y263709D03*
X348978Y267609D03*
X345598Y277360D03*
X348978Y279310D03*
Y275409D03*
Y271509D03*
X352357Y265660D03*
X355737Y263709D03*
X298279Y335860D03*
X335458Y341709D03*
X301659D03*
X294899D03*
X305039Y335860D03*
X338838D03*
X328698Y341709D03*
X342218D03*
X332078Y335860D03*
X308418Y306609D03*
X301659D03*
X311798Y304660D03*
X305039D03*
X321938Y306609D03*
X325318Y304660D03*
Y308560D03*
X298279Y304660D03*
X294899Y302709D03*
X308418D03*
X301659D03*
X315178D03*
X321938D03*
X294899Y306609D03*
X318558Y304660D03*
Y308560D03*
X321938Y291009D03*
X318558Y296860D03*
X315178Y294909D03*
X321938D03*
X301659D03*
X325318Y285160D03*
Y289060D03*
Y296860D03*
X298279D03*
Y289060D03*
Y281260D03*
X308418Y298809D03*
X301659D03*
X308418Y283209D03*
X305039Y281260D03*
Y289060D03*
X308418Y291009D03*
Y287109D03*
X311798Y281260D03*
Y289060D03*
X308418Y294909D03*
X311798Y296860D03*
X305039D03*
X315178Y287109D03*
X318558Y285160D03*
X321938Y287109D03*
X301659Y283209D03*
Y287109D03*
Y291009D03*
X294899Y298809D03*
Y294909D03*
Y291009D03*
Y283209D03*
Y287109D03*
X315178Y298809D03*
X321938D03*
X318558Y289060D03*
X315178Y291009D03*
X332078Y308560D03*
Y304660D03*
X328698Y302709D03*
Y306609D03*
Y287109D03*
Y291009D03*
Y294909D03*
Y298809D03*
X332078Y296860D03*
Y285160D03*
Y289060D03*
X315178Y306609D03*
X308418Y310509D03*
X311798Y312460D03*
X335458Y298809D03*
X348978Y287109D03*
X345598Y285160D03*
Y281260D03*
X348978Y283209D03*
Y298809D03*
Y291009D03*
X345598Y289060D03*
Y292959D03*
Y296860D03*
X348978Y294909D03*
X345598Y300760D03*
X348978Y302709D03*
Y306609D03*
X345598Y304660D03*
Y308560D03*
X348978Y310509D03*
X342218Y302709D03*
Y306609D03*
Y291009D03*
Y287109D03*
Y294909D03*
Y298809D03*
X338838Y308560D03*
X335458Y302709D03*
X338838Y304660D03*
X335458Y306609D03*
Y287109D03*
X338838Y289060D03*
Y285160D03*
X335458Y291009D03*
X338838Y296860D03*
X335458Y294909D03*
X348978Y314409D03*
X345598Y312460D03*
X348978Y322209D03*
X355737Y333909D03*
X345598Y316360D03*
X348978Y318309D03*
Y330009D03*
X352357Y331960D03*
X348978Y326110D03*
X335458Y337809D03*
X305039Y339760D03*
X335458Y333909D03*
X298279Y339760D03*
X294899Y337809D03*
X301659Y333909D03*
X328698Y337809D03*
X342218D03*
X355737Y345609D03*
X301659Y361209D03*
X345598Y386560D03*
X341892Y396301D03*
X311798Y363160D03*
X318558Y374860D03*
Y363160D03*
X294899Y361209D03*
X305039Y355360D03*
X298279Y367060D03*
X348978Y357309D03*
X352357Y374860D03*
X351192Y402800D03*
X342218Y380709D03*
X352357Y363160D03*
X315178Y369010D03*
X298279Y355360D03*
Y347560D03*
X321938Y369010D03*
X315178Y349509D03*
Y353409D03*
X311798Y355360D03*
Y347560D03*
Y351460D03*
X342218Y384609D03*
X315178Y361209D03*
X321938Y372909D03*
X311798Y367060D03*
X294899Y365109D03*
X301659Y353409D03*
Y365109D03*
X355737Y384609D03*
X352357Y378760D03*
X348978Y372909D03*
Y388509D03*
X305039Y343660D03*
X298279Y359260D03*
X321938Y365109D03*
X305039Y363160D03*
X335458Y345609D03*
X311798Y370959D03*
X294899Y357309D03*
X318558Y367060D03*
X305039Y359260D03*
X301659Y345609D03*
X294899D03*
X338838Y343660D03*
X332078D03*
X315178Y372909D03*
X307675Y518057D03*
X327754Y512792D03*
X297835Y494944D03*
X294392Y493100D03*
X304392Y494700D03*
X301092Y493300D03*
X334447Y518157D03*
X331100Y515364D03*
X334447Y512792D03*
X324407Y509999D03*
X326922Y497170D03*
X297635Y550914D03*
X294289Y555957D03*
X304328Y550914D03*
X300982Y555957D03*
X297635Y588714D03*
X304328D03*
X308157Y607220D03*
X334447Y607292D03*
X347833Y612357D03*
X354525Y612358D03*
X331100Y604614D03*
X294289Y604499D03*
X297635Y610700D03*
X294289Y593757D03*
X300982Y604499D03*
X304328Y610700D03*
X300982Y593757D03*
X327754Y612457D03*
X371258Y-1858D03*
X376700Y-1300D03*
X373670Y17580D03*
X374773Y19819D03*
X404722Y-4536D03*
X401375Y-1743D03*
X380600Y37400D03*
X401375Y87392D03*
X404722Y84599D03*
X379397Y218860D03*
X372637Y211060D03*
X392916D03*
Y218860D03*
X369257Y213009D03*
Y216909D03*
X382777D03*
X372637Y207159D03*
X389537Y213009D03*
X399676Y207159D03*
X396296Y213009D03*
Y216909D03*
X407706Y236409D03*
X365877Y242260D03*
X372637D03*
X369257Y240309D03*
X376017D03*
X359117Y246160D03*
X372637Y253960D03*
X357057Y277360D03*
X368127Y264300D03*
X364747Y266300D03*
X361492Y268100D03*
X362497Y259809D03*
X365877Y257860D03*
X369257Y255909D03*
X357092Y270700D03*
X359648Y269777D03*
X374887Y260300D03*
X359117Y261760D03*
X371507Y262300D03*
X378267Y258400D03*
X357057Y273460D03*
X399676Y238360D03*
X357057Y281260D03*
Y296860D03*
Y285160D03*
Y292959D03*
Y300760D03*
Y308560D03*
Y304660D03*
Y289060D03*
Y312460D03*
X364747Y331509D03*
X361367Y329560D03*
X357987Y327609D03*
X371507Y335409D03*
X362497Y337809D03*
X369257Y341709D03*
X368127Y333460D03*
X365877Y339760D03*
X374887Y337360D03*
X381647Y341260D03*
X378267Y339309D03*
X359117Y335860D03*
X357057Y320260D03*
Y324160D03*
Y316360D03*
X362497Y345609D03*
X359117Y343660D03*
X382777Y380709D03*
X369257D03*
X396296D03*
X392916Y386560D03*
X372637D03*
X359117Y351460D03*
X362497Y357309D03*
X369257D03*
X376017D03*
X372637Y343660D03*
X365877Y347560D03*
X396296Y384609D03*
X372637Y390460D03*
X403056Y361209D03*
X365877Y355360D03*
X392916Y378760D03*
X379397D03*
X369257Y384609D03*
X399676Y390460D03*
X389537Y384609D03*
X359117Y367060D03*
X399676Y359260D03*
X372637Y355360D03*
X401375Y512792D03*
X404722Y509999D03*
X370596Y585614D03*
X376892Y581127D03*
X378600Y606200D03*
X371134Y612453D03*
X370659Y593691D03*
X371312Y604709D03*
X404722Y609864D03*
X401376Y612658D03*
X438187Y-4536D03*
X451573Y-9901D03*
X428147Y-1743D03*
X421454Y-7108D03*
X434840Y-1743D03*
X451573Y17157D03*
X460912Y-4100D03*
X458266Y-9901D03*
X454533Y-4100D03*
X478344Y-3700D03*
X474998Y-9901D03*
X464758Y-7050D03*
X469832Y-7260D03*
X464732Y-4401D03*
X469832Y-4651D03*
X458266Y17157D03*
X460912Y12114D03*
X454619D03*
X474998Y17157D03*
X478344Y12114D03*
X464732Y14300D03*
X469832Y14514D03*
X464732Y11700D03*
X469832Y11914D03*
X438187Y84714D03*
X428147Y87392D03*
X421454Y92757D03*
X434840Y87392D03*
X436113Y235696D03*
X429354Y231797D03*
X453013Y253247D03*
X456393Y247396D03*
X463153D03*
X476672D03*
X466533Y253247D03*
X473292D03*
X459773D03*
X422594Y235696D03*
Y247396D03*
X429354Y239596D03*
X425974Y233746D03*
Y241547D03*
X436113Y239596D03*
X422594D03*
X432733Y233746D03*
X429354Y251296D03*
X425974Y245447D03*
Y249347D03*
X429354Y247396D03*
X422594Y251296D03*
X419214Y249347D03*
X432733Y241547D03*
X453013Y249347D03*
X429354Y243496D03*
Y235696D03*
X451883Y265246D03*
X434983Y255497D03*
X438363Y257446D03*
X448503Y263297D03*
X445123Y261346D03*
X441743Y259397D03*
X429781Y264793D03*
X466533Y249347D03*
X473292D03*
X459773Y245447D03*
Y249347D03*
X456393Y255196D03*
X463153D03*
X476672D03*
X459773Y257147D03*
X465100Y280300D03*
X455263Y267197D03*
X477792Y276646D03*
Y280547D03*
X474413Y274696D03*
X469913Y278596D03*
X458400Y276400D03*
X466734Y287074D03*
X442020Y339220D03*
X438240Y339380D03*
X469913Y298096D03*
Y301996D03*
X477792Y284447D03*
Y296147D03*
Y300047D03*
Y292247D03*
X469913Y282496D03*
Y294196D03*
Y290296D03*
X463671Y319386D03*
X474413Y329296D03*
X468783Y332897D03*
X474413Y333196D03*
Y325396D03*
X477792Y323446D03*
X463800Y289500D03*
X443993Y354647D03*
X423714Y366347D03*
Y358547D03*
X437233Y366347D03*
X467653Y360496D03*
X447373D03*
X430474Y362447D03*
Y370247D03*
X471033Y354647D03*
X460893Y360496D03*
X474413D03*
X464273Y354647D03*
X450753D03*
X440613Y360496D03*
X454133D03*
X447373Y356596D03*
X430474Y374146D03*
X454133Y356596D03*
X443993Y362447D03*
X433854Y372197D03*
Y364396D03*
X437233Y370247D03*
X423714D03*
X427094Y364396D03*
X467653Y352696D03*
X447373D03*
X467653Y364396D03*
X447373D03*
X467653Y356596D03*
X430474Y366347D03*
X471033Y362447D03*
X460893Y356596D03*
X474413D03*
X464273Y362447D03*
X450753D03*
X440613Y356596D03*
X438187Y510114D03*
X434840Y512792D03*
X421454Y518157D03*
X428147Y512792D03*
X478344Y588714D03*
X454619D03*
X460912D03*
X464732Y588300D03*
X469832Y588514D03*
Y591114D03*
X469833Y607140D03*
X478344Y610700D03*
X474998Y593757D03*
X451573Y604499D03*
X454533Y610300D03*
X451573Y593757D03*
X458266Y604499D03*
Y593757D03*
X460912Y610300D03*
X434840Y612657D03*
X421454Y607292D03*
X428147Y612657D03*
X464732Y609999D03*
X469832Y609749D03*
X464732Y590900D03*
X474998Y604499D03*
X464758Y607350D03*
X438187Y609864D03*
X485037Y-3700D03*
X481691Y-9901D03*
X497723Y-4100D03*
X495077Y-9901D03*
X491344Y-4100D03*
X488384Y-9901D03*
X511809D03*
X501570Y-7050D03*
X506644Y-7260D03*
X501544Y-4401D03*
X506644Y-4651D03*
X497723Y33700D03*
X495077Y27899D03*
X491344Y33700D03*
X488384Y27899D03*
X511809D03*
X501569Y30750D03*
X506643Y33149D03*
X481691Y17157D03*
X485037Y12114D03*
X495077Y17157D03*
X497723Y12114D03*
X488384Y17157D03*
X491430Y12114D03*
X511809Y17157D03*
X501544Y14300D03*
X506644Y14514D03*
X501544Y11700D03*
X506644Y11914D03*
X521848Y-3700D03*
X518502Y-9901D03*
X515155Y-3700D03*
X534534Y-4100D03*
X531888Y-9901D03*
X528155Y-4100D03*
X525195Y-9901D03*
X538381Y-7050D03*
X518502Y27899D03*
Y17157D03*
X521848Y12114D03*
X515155D03*
X531888Y17157D03*
X534534Y12114D03*
X525195Y17157D03*
X528241Y12114D03*
X538355Y14300D03*
Y11700D03*
X501543Y33399D03*
X506643Y30540D03*
X538355Y-4401D03*
X495077Y54957D03*
X497723Y49914D03*
X488384Y54957D03*
X491430Y49914D03*
X511809Y54957D03*
X501543Y52100D03*
X506643Y49714D03*
X501543Y49500D03*
X506643Y52314D03*
X521848Y34100D03*
X518502Y54957D03*
X521848Y49914D03*
X515155Y34100D03*
Y49914D03*
X494927Y112357D03*
X497723Y106964D03*
X488634Y112357D03*
X491430Y106964D03*
X512024Y112357D03*
X501544Y110514D03*
X506644Y107655D03*
X501570Y107865D03*
X506670Y110264D03*
X518317Y112357D03*
X521113Y106964D03*
X514820D03*
X528491Y204496D03*
X538631Y202247D03*
X483432Y247396D03*
X486812Y253247D03*
X480052D03*
X511592Y272747D03*
X525111Y249347D03*
X504832Y257147D03*
X508212Y251296D03*
X486812Y249347D03*
X480052Y245447D03*
Y249347D03*
X483432Y255196D03*
X480052Y257147D03*
X508707Y258532D03*
X484552Y280547D03*
X511592Y253247D03*
X508212Y266896D03*
X513857Y260881D03*
X518352Y245447D03*
Y241547D03*
Y237647D03*
X521731Y239596D03*
Y243496D03*
X525111Y245447D03*
X518352Y249347D03*
X521731Y255196D03*
X531871Y257147D03*
X528491Y255196D03*
X525111Y268847D03*
X528491Y262996D03*
X514972Y251296D03*
X521731D03*
X511592Y245447D03*
Y311747D03*
X518352D03*
X528491Y305896D03*
X504832Y300045D03*
Y303947D03*
Y311747D03*
X508212Y301996D03*
Y305896D03*
X487932Y286396D03*
X481172Y298096D03*
Y305896D03*
X487932Y290296D03*
X484552Y288347D03*
Y296147D03*
X481172Y294196D03*
X508212Y309797D03*
X481172Y329296D03*
X491312Y323446D03*
X494692Y317596D03*
X487932Y321496D03*
X484552Y327347D03*
X487932Y325396D03*
X514972Y305896D03*
Y309797D03*
X528491Y301996D03*
Y309797D03*
X525111Y311747D03*
Y307847D03*
Y303947D03*
X521731Y305896D03*
Y309797D03*
X518352Y307847D03*
X514972Y313696D03*
X528491D03*
X521731D03*
X518352Y303947D03*
X484552Y284447D03*
X506644Y496167D03*
X501560Y493467D03*
X506644Y493567D03*
X501560Y496167D03*
X514755Y493744D03*
X511809Y498487D03*
X491430Y491144D03*
X488384Y498487D03*
X521048Y493844D03*
X517902Y498487D03*
X497723Y490894D03*
X494777Y498487D03*
X506644Y553314D03*
X501544Y550500D03*
X506644Y550714D03*
X501544Y553100D03*
X515155Y550914D03*
X511809Y555957D03*
X491430Y550914D03*
X488384Y555957D03*
X521848Y550914D03*
X518502Y555957D03*
X497723Y550914D03*
X495077Y555957D03*
X497723Y588714D03*
X485037D03*
X538355Y588300D03*
X501544D03*
X506644Y588514D03*
X528241Y588714D03*
X534534D03*
X515155D03*
X491430D03*
X521848D03*
X538355Y590900D03*
X521848Y610700D03*
X495077Y604499D03*
Y593757D03*
X498092Y611200D03*
X481691Y604499D03*
Y593757D03*
X485037Y610700D03*
X506644Y591114D03*
Y607140D03*
X538355Y609999D03*
X501544D03*
Y590900D03*
X525195Y604499D03*
Y593757D03*
X531888Y604499D03*
X534534Y610300D03*
X531888Y593757D03*
X511809Y604499D03*
X515155Y610700D03*
X511809Y593757D03*
X488384Y604499D03*
Y593757D03*
X491724Y611668D03*
X518502Y604499D03*
Y593757D03*
X538381Y607350D03*
X506644Y609749D03*
X501570Y607350D03*
X528155Y610300D03*
X558659Y-3700D03*
X555313Y-9901D03*
X551966Y-3700D03*
X548620Y-9901D03*
X571345Y-4100D03*
X568699Y-9901D03*
X564966Y-4100D03*
X562006Y-9901D03*
X543455Y-7260D03*
Y-4651D03*
X555313Y17157D03*
X558659Y12114D03*
X548620Y17157D03*
X551966Y12114D03*
X568699Y17157D03*
X571345Y12114D03*
X561868Y17019D03*
X565052Y12114D03*
X543455Y14514D03*
Y11914D03*
X595470Y-3700D03*
X592124Y-9901D03*
X588777Y-3700D03*
X585431Y-9901D03*
X575192Y-7050D03*
X580266Y-7260D03*
Y-4651D03*
X592124Y17157D03*
X595470Y12114D03*
X585431Y17157D03*
X588777Y12114D03*
X575166Y14300D03*
X580266Y14514D03*
X575166Y11700D03*
X580266Y11914D03*
X575166Y-4401D03*
X562591Y348796D03*
X575166Y588300D03*
X580266Y588514D03*
X543455D03*
X588777Y588714D03*
X565052D03*
X595470D03*
X571345D03*
X551966D03*
X558659D03*
X580266Y591114D03*
Y607140D03*
X543455Y591114D03*
Y607140D03*
X575166Y609999D03*
Y590900D03*
X585431Y604499D03*
Y593757D03*
X588777Y610700D03*
X562006Y604499D03*
Y593757D03*
X592124Y604499D03*
Y593757D03*
X595470Y610700D03*
X568699Y604499D03*
X571345Y610300D03*
X568699Y593757D03*
X548620Y604499D03*
X551966Y610700D03*
X548620Y593757D03*
X555313Y604499D03*
X558659Y610700D03*
X555313Y593757D03*
X580266Y609749D03*
X543455D03*
X575192Y607350D03*
X564966Y610300D03*
X662700Y-17900D03*
X648867Y31258D03*
X651442Y31225D03*
X612203Y92599D03*
X608856D03*
X652718Y93881D03*
X662352Y89566D03*
X608600Y103000D03*
X662786Y278084D03*
X660901Y279856D03*
X621165Y256075D03*
X620850Y253416D03*
X654950Y253446D03*
X643591Y266983D03*
X643500Y274868D03*
X642855Y269660D03*
X624500Y240500D03*
X627529Y280441D03*
X618279Y251393D03*
X662238Y296146D03*
X661232Y287321D03*
X655000Y284600D03*
X646700Y308850D03*
X646800Y326100D03*
X646272Y328800D03*
X658900Y339150D03*
X662200Y284800D03*
X628525Y287832D03*
X636799Y285670D03*
X636985Y288264D03*
X634407Y287915D03*
X609191Y451454D03*
X624600Y419400D03*
X626737Y421000D03*
X619800Y416200D03*
X624300Y422100D03*
X627000Y423436D03*
X622900Y424200D03*
X619680Y422600D03*
X625200Y425400D03*
X621800Y421100D03*
X619700Y419500D03*
X640300Y437600D03*
X629600Y425100D03*
X622100Y417900D03*
X656050Y489500D03*
X659070Y488709D03*
X653800Y496600D03*
X641150Y484300D03*
X605510Y517999D03*
Y510157D03*
X636500Y493924D03*
X627000Y478300D03*
X605510Y566699D03*
Y528899D03*
Y555799D03*
Y585757D03*
Y574857D03*
Y537057D03*
Y547957D03*
X631741Y615759D03*
X644500Y594400D03*
X648180Y590702D03*
X646760Y592992D03*
X605510Y604499D03*
Y612657D03*
Y593599D03*
X718975Y-4451D03*
X692400Y20800D03*
X710327Y-11968D03*
X710800Y7100D03*
X705250Y8600D03*
X704150Y19650D03*
X701120Y19619D03*
X698470Y19669D03*
X710107Y-19839D03*
X708330Y-17806D03*
X664471Y86061D03*
X694600Y85000D03*
X713300Y86000D03*
X707329Y88955D03*
X705972Y86660D03*
X715130Y79574D03*
X703845Y88830D03*
X716268Y88683D03*
X716894Y84047D03*
X713115Y88629D03*
X701500Y85500D03*
X698300Y85300D03*
X709560Y84648D03*
X670795Y89189D03*
X720572Y88700D03*
X724888Y188930D03*
X714391Y215809D03*
X701700Y226600D03*
X725725Y241560D03*
X715200Y258900D03*
X704090Y256080D03*
X697255Y267098D03*
X700400Y257200D03*
X717420Y249920D03*
X688100Y308600D03*
X674700Y339200D03*
X687400Y328200D03*
X687300Y325200D03*
X713970Y310860D03*
X711900Y327700D03*
X712400Y324400D03*
X701100Y339000D03*
X698600Y338900D03*
X690048Y284053D03*
X665000Y284800D03*
X690048Y281053D03*
X705800Y301600D03*
X674194Y358467D03*
X677563Y365496D03*
X683100Y392200D03*
X678730Y362841D03*
X686619Y392600D03*
X691240Y390039D03*
X680200Y432100D03*
X680370Y427770D03*
X687400Y411200D03*
X674300Y489500D03*
X693604Y494303D03*
X676600Y501300D03*
X679049Y503746D03*
X671500Y501300D03*
X674000Y501200D03*
X720300Y485800D03*
X723792Y489148D03*
X721301Y488200D03*
X708700Y499400D03*
X708500Y512500D03*
X701500Y505500D03*
X710643Y505496D03*
X703800Y507100D03*
X696000Y496800D03*
X731210Y-15134D03*
X729600Y17991D03*
X734256D03*
X756176Y-4300D03*
X776274Y12114D03*
X773228Y-9901D03*
X776188Y-4100D03*
X773228Y17157D03*
X782567Y12114D03*
X779921Y-9901D03*
X782567Y-4100D03*
X779921Y17157D03*
X786388Y11700D03*
Y-4401D03*
X786414Y-7050D03*
X786388Y14300D03*
X751600Y41000D03*
X730923Y75315D03*
X733671Y75412D03*
X766824Y85943D03*
X763930Y85100D03*
X730038Y88408D03*
X732599D03*
X735241Y88329D03*
X763350Y81220D03*
X732734Y82626D03*
X746600Y103900D03*
X741700Y102000D03*
X752900Y101000D03*
X744200Y102800D03*
X766500Y102900D03*
X756800Y99400D03*
Y102000D03*
X727776Y188811D03*
X771232Y214033D03*
X765116Y216512D03*
X769044Y191348D03*
X787371Y215216D03*
Y217716D03*
X765144Y213508D03*
X748700Y254000D03*
X751363Y254207D03*
X754758Y273356D03*
X749100Y279500D03*
X765116Y248512D03*
X771650Y246451D03*
X765116Y280512D03*
X771650Y278451D03*
X748990Y267450D03*
X787371Y247216D03*
Y249716D03*
Y279216D03*
X748700Y257500D03*
X754263Y254207D03*
X754846Y276340D03*
X765144Y245508D03*
X749090Y270250D03*
X765144Y277508D03*
X741250Y298856D03*
X771600Y310600D03*
X765116Y312512D03*
X787371Y281716D03*
Y311216D03*
Y313716D03*
X749800Y282300D03*
X743600Y304100D03*
X737750Y298894D03*
X765144Y309508D03*
Y341508D03*
X732000Y380000D03*
X765116Y344512D03*
X771700Y342501D03*
X764131Y376747D03*
X771400Y374400D03*
X764957Y380363D03*
X787371Y343216D03*
Y345716D03*
X787321Y374916D03*
Y377316D03*
X764159Y373743D03*
X747950Y441600D03*
X748500Y438900D03*
X766200Y417005D03*
X766394Y414397D03*
X763706Y514250D03*
X728373Y488356D03*
X731339Y489319D03*
X763544Y522236D03*
X782567Y588714D03*
X776274D03*
X786388Y588300D03*
X763450Y585200D03*
X765900Y587300D03*
X726857Y610871D03*
X729616Y610863D03*
X753300Y593600D03*
X732500Y611000D03*
X782567Y610300D03*
X779921Y593757D03*
Y604499D03*
X776188Y610300D03*
X773228Y593757D03*
Y604499D03*
X786414Y607350D03*
X786388Y590900D03*
Y609999D03*
X755900Y593650D03*
X796653Y-9901D03*
X833464D03*
X840157D03*
X843503Y-3700D03*
X799999Y12114D03*
X836810D03*
X843503D03*
X840157Y17157D03*
X828299Y-4651D03*
Y11914D03*
X823199Y-4401D03*
Y11700D03*
X791488Y-4651D03*
Y11914D03*
X828299Y14514D03*
Y-7260D03*
X823199Y14300D03*
X823225Y-7050D03*
X791488Y-7260D03*
Y14514D03*
X819378Y12114D03*
X816732Y-9901D03*
Y17157D03*
X819378Y-4100D03*
X799999Y-3700D03*
X796653Y17157D03*
X803346Y-9901D03*
X806692Y12114D03*
Y-3700D03*
X803346Y17157D03*
X846850Y-9901D03*
Y17157D03*
X833464D03*
X836810Y-3700D03*
X810039Y-9901D03*
X813085Y12114D03*
X812999Y-4100D03*
X810039Y17157D03*
X822400Y212400D03*
X790871Y215216D03*
Y217716D03*
X789500Y231800D03*
X790900Y234000D03*
Y229700D03*
X790846Y225774D03*
X790882Y221723D03*
X790871Y247216D03*
Y249716D03*
X789471Y227742D03*
X789576Y223737D03*
X789554Y219723D03*
X790900Y253900D03*
X789432Y252000D03*
X790871Y266216D03*
X789432Y255800D03*
X790867Y257724D03*
X789432Y259800D03*
X789500Y263900D03*
X790885Y261711D03*
X790871Y279216D03*
Y311216D03*
X789432Y284200D03*
Y288300D03*
Y292400D03*
X789400Y296200D03*
X790871Y298216D03*
X790937Y294270D03*
X790900Y290300D03*
Y286200D03*
X790871Y281716D03*
Y313716D03*
X789432Y319900D03*
Y323900D03*
X790900Y322000D03*
Y326000D03*
X790871Y330216D03*
X789500Y328000D03*
X789478Y315671D03*
X790800Y317700D03*
X840871Y391380D03*
X837272Y391420D03*
X789432Y348100D03*
Y352100D03*
X789597Y356105D03*
X789500Y360200D03*
X790900Y358200D03*
X790835Y354048D03*
X790867Y350024D03*
X790871Y345716D03*
Y343216D03*
Y362216D03*
X790821Y374916D03*
X790900Y389300D03*
X789500Y391300D03*
X790900Y393400D03*
Y381100D03*
X789582Y383200D03*
X790900Y385300D03*
X789500Y387300D03*
X790821Y377316D03*
X789282Y379200D03*
X813085Y588714D03*
X806692D03*
X799999D03*
X791488Y588514D03*
X843503Y588714D03*
X836810D03*
X819378D03*
X828299Y588514D03*
X823199Y588300D03*
X812999Y610300D03*
X810039Y593757D03*
Y604499D03*
X806692Y610700D03*
X803346Y593757D03*
Y604499D03*
X799999Y610700D03*
X796653Y593757D03*
Y604499D03*
X816732Y593757D03*
Y604499D03*
X791488Y609749D03*
Y591114D03*
X840157Y593757D03*
X843503Y610700D03*
X840157Y604499D03*
X833464Y593757D03*
X836810Y610700D03*
X833464Y604499D03*
X846850Y593757D03*
X819378Y610300D03*
X823199Y590900D03*
X828299Y609749D03*
X823199Y609999D03*
X828299Y591114D03*
Y607140D03*
X791488D03*
X846850Y604499D03*
X823225Y607350D03*
X870275Y-9901D03*
X876968D03*
X880314Y-3700D03*
X907086Y-9901D03*
X873621Y12114D03*
X880314D03*
X876968Y17157D03*
X910432Y12114D03*
X901921Y11914D03*
Y-4651D03*
X865110Y11914D03*
Y-4651D03*
X896821Y-4401D03*
Y11700D03*
X860010D03*
Y-4401D03*
X901921Y-7260D03*
Y14514D03*
X865110Y-7260D03*
Y14514D03*
X896847Y-7050D03*
X896821Y14300D03*
X860036Y-7050D03*
X860010Y14300D03*
X907086Y17157D03*
X886707Y12114D03*
X883661Y-9901D03*
Y17157D03*
X886621Y-4100D03*
X893000Y12114D03*
X890354Y-9901D03*
X893000Y-4100D03*
X890354Y17157D03*
X873621Y-3700D03*
X870275Y17157D03*
X849896Y12114D03*
X849810Y-4100D03*
X853543Y-9901D03*
X856189Y12114D03*
Y-4100D03*
X853543Y17157D03*
X910432Y-3700D03*
X882008Y321100D03*
X856189Y588714D03*
X849896D03*
X873621D03*
X865110Y588514D03*
X860010Y588300D03*
X880314Y588714D03*
X893000D03*
X886707D03*
X896821Y588300D03*
X901921Y588514D03*
X910432Y588714D03*
X853543Y593757D03*
X856189Y610300D03*
X853543Y604499D03*
X876968Y593757D03*
Y604499D03*
X849810Y610300D03*
X870275Y593761D03*
X873621Y610700D03*
X870275Y604499D03*
X860010Y590900D03*
X860036Y607350D03*
X865110Y609749D03*
X860010Y609999D03*
X865110Y591114D03*
X880314Y610700D03*
X893000Y610300D03*
X890354Y593757D03*
Y604499D03*
X886621Y610300D03*
X883661Y593757D03*
X896847Y607350D03*
X896821Y590900D03*
Y609999D03*
X901921Y591114D03*
Y609749D03*
X907086Y604499D03*
Y593757D03*
X910432Y610700D03*
X865110Y607140D03*
X883661Y604499D03*
X901921Y607140D03*
X933658Y-7050D03*
X933632Y-4401D03*
X929811Y-4100D03*
X927165Y-9901D03*
X923432Y-4100D03*
X920472Y-9901D03*
X933658Y30750D03*
X933632Y33399D03*
X929811Y33700D03*
X927165Y27899D03*
X923432Y33700D03*
X920472Y27899D03*
X933632Y14300D03*
Y11700D03*
X927165Y17157D03*
X929811Y12114D03*
X920472Y17157D03*
X923518Y12114D03*
X957765Y-7180D03*
X938732Y-7260D03*
Y-4651D03*
X953936Y-3700D03*
X950590Y-9901D03*
X947243Y-3700D03*
X943897Y-9901D03*
X938732Y33149D03*
Y30540D03*
X950590Y27899D03*
X943897D03*
X938732Y14514D03*
Y11914D03*
X950590Y17157D03*
X953936Y12114D03*
X943897Y17157D03*
X947243Y12114D03*
X913779Y-9901D03*
X917125Y-3700D03*
Y12114D03*
X913779Y17157D03*
X933632Y52100D03*
Y49500D03*
X927165Y54957D03*
X929811Y49914D03*
X920472Y54957D03*
X923518Y49914D03*
X938732Y49714D03*
Y52314D03*
X953936Y34100D03*
X950590Y54957D03*
X953936Y49914D03*
X947243Y34100D03*
X943897Y54957D03*
X947243Y49914D03*
X957283Y92657D03*
X933632Y110514D03*
X933658Y107865D03*
X927165Y112327D03*
X929811Y106934D03*
X920472Y112327D03*
X923518Y107284D03*
X938732Y107655D03*
X938758Y110264D03*
X950590Y109700D03*
X953786Y107684D03*
X944497Y110927D03*
X947243Y105084D03*
X944507Y232509D03*
X971546Y228610D03*
X968166Y222760D03*
X951267Y232509D03*
Y252009D03*
Y244209D03*
X947887Y257860D03*
X968166Y230559D03*
X964786Y228610D03*
X944507Y259809D03*
X954647Y234460D03*
X961406Y226660D03*
X944507Y240309D03*
X954647Y253960D03*
Y238360D03*
Y261760D03*
X951267Y263709D03*
X947887Y250060D03*
X944507Y252009D03*
X964786Y236409D03*
X961406Y234460D03*
X954647Y257860D03*
X968166Y234460D03*
X937747Y279310D03*
X917000Y276000D03*
X920847Y277360D03*
X924227Y279310D03*
X916967D03*
X930987D03*
X944507D03*
X958026D03*
X951267D03*
X947887Y230559D03*
X971546Y224709D03*
X944507Y236409D03*
X954647Y242260D03*
X947887Y261760D03*
X951267Y236409D03*
X947887Y238360D03*
X951267Y255909D03*
X971546Y232509D03*
X947887Y242260D03*
X944507Y255909D03*
X964786Y224709D03*
X961406Y230559D03*
X947887Y335860D03*
X954647D03*
X944507Y341709D03*
X951267D03*
X947887Y320260D03*
X937747Y287109D03*
X920500Y304660D03*
Y300760D03*
X930987Y302709D03*
X924227D03*
X920500Y311960D03*
X927607Y304660D03*
X924227Y306609D03*
X930987D03*
Y310509D03*
X934367Y304660D03*
X924227Y310509D03*
X920500Y308560D03*
Y289060D03*
X934367Y296860D03*
X930987Y294909D03*
X920500Y296860D03*
Y292959D03*
X927607Y296860D03*
X924227Y298809D03*
X930987D03*
X924227Y283209D03*
X927607Y281260D03*
X920500Y285500D03*
X924227Y287109D03*
X920847Y281260D03*
X930987Y287109D03*
X934367Y289060D03*
Y281260D03*
X930987Y283209D03*
X924227Y291009D03*
X930987D03*
X927607Y289060D03*
X937747Y302709D03*
Y306609D03*
Y310509D03*
Y283209D03*
Y291009D03*
Y294909D03*
Y298809D03*
Y314409D03*
X924227D03*
X930987D03*
X934367Y312460D03*
X927607D03*
X920847Y324160D03*
X924227Y318309D03*
X920547Y316160D03*
X917167Y318309D03*
Y322209D03*
X917467Y326110D03*
X920847Y320260D03*
X971546Y294909D03*
X944507Y283209D03*
X964786Y291009D03*
X954647Y281260D03*
X958026Y283209D03*
X951267Y287109D03*
X958026D03*
X951267Y283209D03*
X961406Y281260D03*
Y296860D03*
X964786Y298809D03*
Y302709D03*
X971546D03*
X961406Y304660D03*
X958026Y302709D03*
X951267D03*
X968166Y308560D03*
X964786Y306609D03*
X968166Y304660D03*
X971546Y306609D03*
X951267Y310509D03*
X954647Y304660D03*
X958026Y306609D03*
Y310509D03*
X951267Y306609D03*
X944507Y302709D03*
Y306609D03*
Y310509D03*
X941127Y304660D03*
X947887D03*
X944507Y294909D03*
Y287109D03*
X971546Y298809D03*
X968166Y285160D03*
X964786Y287109D03*
X944507Y291009D03*
X941127Y281260D03*
Y289060D03*
Y296860D03*
X944507Y298809D03*
X947887Y289060D03*
Y296860D03*
Y281260D03*
X968166Y296860D03*
X964786Y294909D03*
X971546Y291009D03*
Y287109D03*
X968166Y289060D03*
X961406D03*
X958026Y298809D03*
X951267D03*
Y291009D03*
X958026D03*
X954647Y289060D03*
Y296860D03*
X958026Y294909D03*
X951267D03*
X954647Y339760D03*
X951267Y333909D03*
X944507Y337809D03*
X947887Y339760D03*
X944507Y314409D03*
X951267D03*
X958026D03*
X961406Y312460D03*
X954647D03*
X941127D03*
X947887D03*
X951267Y365109D03*
Y353409D03*
X944507Y365109D03*
X961406Y367060D03*
X964786Y361209D03*
X947887Y347560D03*
X954647Y359260D03*
X944507Y357309D03*
X971546Y365109D03*
Y372909D03*
X964786D03*
X947887Y367060D03*
X954647Y355360D03*
X944507Y361209D03*
X968166Y363160D03*
X961406D03*
X971546Y369010D03*
X944507Y345609D03*
X951267D03*
X947887Y355360D03*
X951267Y361209D03*
X968166Y367060D03*
X961406Y370959D03*
X954647Y363160D03*
X947887Y359260D03*
X964786Y369010D03*
X954647Y343660D03*
X968166Y374860D03*
X957283Y518057D03*
X947443Y494944D03*
X944000Y493100D03*
X923600Y493744D03*
X929811Y493244D03*
X933647Y493344D03*
X938732D03*
X920700Y498644D03*
X927165D03*
X938732Y495944D03*
X933647D03*
X954000Y494700D03*
X950700Y493300D03*
X953936Y588714D03*
X938732Y588514D03*
X933632Y588300D03*
X929811Y588714D03*
X923518D03*
X947243D03*
Y550914D03*
X923518D03*
X929811D03*
X938732Y553314D03*
X933632Y550500D03*
X938732Y550714D03*
X933632Y553100D03*
X943897Y555957D03*
X920472D03*
X927165D03*
X953936Y550914D03*
X950590Y555957D03*
X917125Y588714D03*
Y610700D03*
X913779Y593757D03*
X929811Y610300D03*
X927165Y593757D03*
X950590Y604499D03*
X957765Y607220D03*
X938732Y609749D03*
Y607140D03*
Y591114D03*
X953936Y610700D03*
X950590Y593757D03*
X933632Y590900D03*
Y609999D03*
X927165Y604499D03*
X923432Y610300D03*
X920472Y593757D03*
Y604499D03*
X947243Y610700D03*
X943897Y593757D03*
Y604499D03*
X913779D03*
X933658Y607350D03*
X1025670Y6640D03*
X1023740Y18150D03*
X1020866Y-1858D03*
X1025291Y20734D03*
X984055Y-7108D03*
X980708Y-9786D03*
X984055Y-1743D03*
X974015Y-4536D03*
X984055Y92757D03*
X980708Y89964D03*
X984055Y87392D03*
X974015Y84599D03*
X976700Y103021D03*
X991826Y209109D03*
X995206Y207159D03*
X1022245D03*
X1005345Y213009D03*
X1029005Y218860D03*
X1001965D03*
X1018865Y213009D03*
X998586Y205210D03*
X991826D03*
X1022245Y211060D03*
X1018865Y216909D03*
X1032385D03*
X985066Y263709D03*
X988446Y257860D03*
X1022245Y242260D03*
X995206D03*
X1015485D03*
X998586Y224709D03*
X1008725Y246160D03*
X1001965D03*
X981686Y257860D03*
Y265660D03*
Y253960D03*
X974926Y261760D03*
Y257860D03*
X978306Y263709D03*
X995206Y277360D03*
X998586Y267609D03*
Y271509D03*
Y275409D03*
Y279310D03*
X1022245Y253960D03*
X1017735Y264300D03*
X1014355Y266300D03*
X1021115Y262300D03*
X1024495Y260300D03*
X1027875Y258400D03*
X1005345Y263709D03*
X1001965Y265660D03*
X1009256Y269777D03*
X1008725Y261760D03*
X1006665Y277360D03*
X1006700Y270700D03*
X1006665Y273460D03*
X1011100Y268100D03*
X1015485Y257860D03*
X1018865Y255909D03*
X1012105Y259809D03*
X988446Y261760D03*
X1001965Y222760D03*
X1025625Y240309D03*
X995206Y246160D03*
X1018865Y240309D03*
X981686Y261760D03*
X985066Y255909D03*
X978306D03*
X991826Y337809D03*
X978306D03*
X985066Y333909D03*
X995206Y296860D03*
X985066Y294909D03*
Y287109D03*
X988446Y285160D03*
X991826Y287109D03*
X995206Y281260D03*
X978306Y298809D03*
Y287109D03*
X981686Y285160D03*
X978306Y294909D03*
X981686Y296860D03*
Y289060D03*
X978306Y291009D03*
X998586Y302709D03*
Y306609D03*
Y310509D03*
Y287109D03*
Y294909D03*
Y291009D03*
Y298809D03*
Y283209D03*
X985066Y302709D03*
X978306D03*
X988446Y304660D03*
Y308560D03*
X985066Y306609D03*
X995206Y304660D03*
Y308560D03*
X991826Y306609D03*
X978306D03*
X981686Y308560D03*
Y304660D03*
X974926D03*
Y308560D03*
X995206Y300760D03*
X991826Y302709D03*
X974926Y285160D03*
Y296860D03*
Y289060D03*
X995206Y292959D03*
X988446Y296860D03*
X991826Y294909D03*
X995206Y289060D03*
X988446D03*
X991826Y291009D03*
X985066D03*
X995206Y285160D03*
X985066Y298809D03*
X991826D03*
X981686Y335860D03*
X978306Y341709D03*
X985066Y337809D03*
Y341709D03*
X998586Y314409D03*
X995206Y312460D03*
X998586Y318309D03*
Y322209D03*
Y326110D03*
Y330009D03*
X995206Y316360D03*
X1006665Y300760D03*
Y304660D03*
Y308560D03*
Y285160D03*
Y296860D03*
Y289060D03*
Y281260D03*
Y292959D03*
X1008725Y335860D03*
X1005345Y333909D03*
X1001965Y331960D03*
X1007595Y327609D03*
X1021115Y335409D03*
X1018865Y341709D03*
X1017735Y333460D03*
X1015485Y339760D03*
X1024495Y337360D03*
X1012105Y337809D03*
X1006665Y312460D03*
X1014355Y331509D03*
X1010975Y329560D03*
X1006665Y324160D03*
Y316360D03*
Y320260D03*
X991826Y341709D03*
X988446Y335860D03*
X981686Y343660D03*
X998586Y372909D03*
X991826Y384609D03*
X991500Y396301D03*
X1015485Y355360D03*
X1008725Y367060D03*
X1022245Y390460D03*
X1000800Y402800D03*
X1018865Y384609D03*
X1001965Y378760D03*
X1029005D03*
X1005345Y384609D03*
X988446Y343660D03*
X998586Y357309D03*
Y388509D03*
X991826Y380709D03*
X995206Y386560D03*
X1022245Y343660D03*
X1005345Y345609D03*
X1018865Y357309D03*
X1001965Y363160D03*
X1022245Y355360D03*
X1012105Y357309D03*
X1008725Y351460D03*
X1022245Y386560D03*
X1018865Y380709D03*
X1001965Y374860D03*
X985066Y345609D03*
X1025625Y357309D03*
X1032385Y380709D03*
X977362Y512792D03*
X974015Y509999D03*
X984055Y512792D03*
X980708Y515364D03*
X984055Y518157D03*
X976530Y497170D03*
X1026500Y581000D03*
X1020800Y612600D03*
X1029777Y613581D03*
X980708Y604614D03*
X997441Y612357D03*
X977362Y612457D03*
X1020700Y604600D03*
X1020300Y593700D03*
X1004133Y612358D03*
X984055Y607292D03*
X1071062Y-7108D03*
X1087795Y-4536D03*
X1050983Y-1743D03*
X1084448D03*
X1077755D03*
X1054330Y-4536D03*
X1071062Y92757D03*
X1054330Y84599D03*
X1050983Y87392D03*
X1087795Y84714D03*
X1084448Y87392D03*
X1077755D03*
X1039145Y213009D03*
X1042524Y211060D03*
X1049284Y207159D03*
X1045904Y216909D03*
X1042524Y218860D03*
X1045904Y213009D03*
X1072202Y247396D03*
X1078962Y231797D03*
X1082341Y241547D03*
X1085721Y235696D03*
X1075582Y241547D03*
X1072202Y235696D03*
X1057314Y236409D03*
X1078962Y235696D03*
Y243496D03*
X1072202D03*
Y251296D03*
X1078962D03*
X1082341Y245447D03*
Y249347D03*
X1078962Y247396D03*
X1075582Y245447D03*
X1085721Y251296D03*
X1075582Y249347D03*
X1079859Y265000D03*
X1087971Y257800D03*
X1091351Y259600D03*
X1094731Y261500D03*
X1078962Y239596D03*
X1082341Y233746D03*
X1085721Y239596D03*
X1075582Y233746D03*
X1049284Y238360D03*
X1072202Y239596D03*
X1052664Y361209D03*
X1045904Y384609D03*
X1039145D03*
X1049284Y390460D03*
X1042524Y378760D03*
X1086841Y370247D03*
X1073322Y358547D03*
X1083462Y364396D03*
X1093601Y354647D03*
X1090221Y360496D03*
X1076702Y364396D03*
X1073322Y370247D03*
X1080082Y374146D03*
X1076435Y343595D03*
X1049284Y359260D03*
X1042524Y386560D03*
X1045904Y380709D03*
X1086841Y366347D03*
X1073322D03*
X1083462Y372197D03*
X1093601Y362447D03*
X1090221Y356596D03*
X1080082Y366347D03*
Y362447D03*
Y370247D03*
X1050983Y512792D03*
X1054330Y509999D03*
X1087795Y510114D03*
X1077755Y512792D03*
X1071062Y518157D03*
X1084448Y512792D03*
Y612657D03*
X1050984Y612658D03*
X1046500Y623500D03*
X1054330Y609864D03*
X1087795D03*
X1071062Y607292D03*
X1077755Y612657D03*
X1147331Y-4100D03*
X1144685Y-9901D03*
X1140952Y-4100D03*
X1137992Y-9901D03*
X1151178Y-7050D03*
X1156252Y-7260D03*
X1151152Y-4401D03*
X1156252Y-4651D03*
X1147331Y33700D03*
X1144685Y27899D03*
X1140952Y33700D03*
X1137992Y27899D03*
X1151177Y30750D03*
X1156251Y33149D03*
X1151151Y33399D03*
X1156251Y30540D03*
X1144685Y17157D03*
X1147331Y12114D03*
X1137992Y17157D03*
X1141038Y12114D03*
X1151152Y14300D03*
X1156252Y14514D03*
X1151152Y11700D03*
X1156252Y11914D03*
X1119440Y-4651D03*
X1114340Y-4401D03*
X1119440Y-7260D03*
X1114366Y-7050D03*
X1124606Y-9901D03*
X1127952Y-3700D03*
X1131299Y-9901D03*
X1107874D03*
X1110520Y-4100D03*
X1134645Y-3700D03*
X1119440Y11914D03*
X1114340Y11700D03*
X1119440Y14514D03*
X1114340Y14300D03*
X1127952Y12114D03*
X1124606Y17157D03*
X1131299D03*
X1110520Y12114D03*
X1107874Y17157D03*
X1134645Y12114D03*
X1101181Y17157D03*
X1104227Y12114D03*
X1101181Y-9901D03*
X1104141Y-4100D03*
X1144685Y54957D03*
X1147331Y49914D03*
X1137992Y54957D03*
X1141038Y49914D03*
X1151151Y52100D03*
X1156251Y49714D03*
X1151151Y49500D03*
X1156251Y52314D03*
X1144535Y112357D03*
X1147331Y106964D03*
X1138242Y112357D03*
X1141038Y106964D03*
X1151152Y110514D03*
X1156252Y107655D03*
X1151178Y107865D03*
X1156278Y110264D03*
X1114340Y280560D03*
X1151060Y262996D03*
X1109381Y264947D03*
X1129660Y249347D03*
X1109381D03*
X1126280Y247396D03*
X1102621Y249347D03*
X1116141D03*
X1129660Y257147D03*
X1122900Y253247D03*
X1133040Y247396D03*
Y255196D03*
X1136420Y253247D03*
X1109381Y257147D03*
X1112761Y255196D03*
X1102621Y253247D03*
X1106001Y255196D03*
X1101491Y265400D03*
X1104871Y267300D03*
X1098111Y263400D03*
X1154440Y261047D03*
X1157820Y247396D03*
X1154440Y249347D03*
X1144300Y266896D03*
X1157820Y251296D03*
X1154440Y257147D03*
X1147680Y264947D03*
X1129660Y245447D03*
X1109381D03*
X1122900Y249347D03*
X1112761Y247396D03*
X1106001D03*
X1129660Y253247D03*
X1109381D03*
X1126280Y255196D03*
X1116141Y253247D03*
X1136420Y249347D03*
X1157820Y309797D03*
X1134160Y303947D03*
X1115230Y289252D03*
X1137540Y286396D03*
Y301996D03*
X1113132Y291702D03*
X1113500Y323400D03*
X1109200Y325100D03*
X1147680Y307847D03*
X1151060Y309797D03*
Y305896D03*
X1144300Y301996D03*
Y298096D03*
X1137540D03*
X1140920Y303947D03*
X1137540Y305896D03*
X1140920Y296147D03*
X1137540Y294196D03*
X1144300Y317596D03*
X1137540Y321496D03*
X1134160Y327347D03*
X1137540Y325396D03*
X1140920Y323446D03*
X1116999Y286826D03*
X1134160Y284447D03*
X1103741Y360496D03*
X1100361Y354647D03*
Y362447D03*
X1113881Y354647D03*
X1110501Y356596D03*
Y360496D03*
X1096981Y356596D03*
X1117261D03*
X1096981Y364396D03*
X1117261D03*
X1124021Y360496D03*
X1120641Y354647D03*
Y362447D03*
Y346847D03*
X1103741Y356596D03*
X1113881Y362447D03*
X1096981Y352696D03*
X1117261D03*
X1096981Y360496D03*
X1117261D03*
X1124021Y356596D03*
X1156252Y496167D03*
X1147331Y490894D03*
X1141038Y491144D03*
X1156252Y493567D03*
X1151168Y493467D03*
Y496167D03*
X1137992Y498487D03*
X1144385D03*
X1104227Y588714D03*
X1114340Y588300D03*
X1097343Y588394D03*
X1147331Y550914D03*
X1141038D03*
X1156252Y550714D03*
Y553314D03*
X1134645Y588714D03*
X1127952D03*
X1147331D03*
X1141038D03*
X1156252Y588514D03*
X1151152Y588300D03*
X1110520Y588714D03*
X1119440Y588514D03*
X1151152Y550500D03*
Y553100D03*
X1137992Y555957D03*
X1144685D03*
X1097374Y612659D03*
X1101181Y593757D03*
X1104141Y610300D03*
X1101181Y604499D03*
X1114340Y590900D03*
Y609999D03*
X1134645Y610700D03*
X1131299Y593757D03*
Y604499D03*
X1124606Y593757D03*
X1127952Y610700D03*
X1124606Y604499D03*
X1147700Y611200D03*
X1144685Y593757D03*
Y604499D03*
X1137992Y593757D03*
X1141332Y611668D03*
X1137992Y604499D03*
X1151178Y607350D03*
X1151152Y590900D03*
Y609999D03*
X1156252Y607140D03*
Y591114D03*
X1107874Y604499D03*
X1119440Y609749D03*
Y591114D03*
Y607140D03*
X1107874Y593757D03*
X1110520Y610300D03*
X1114366Y607350D03*
X1156252Y609749D03*
X1171456Y-3700D03*
X1168110Y-9901D03*
X1164763Y-3700D03*
X1161417Y-9901D03*
X1168110Y27899D03*
X1161417D03*
X1168110Y17157D03*
X1171456Y12114D03*
X1161417Y17157D03*
X1164763Y12114D03*
X1184142D03*
X1204921Y17157D03*
X1198228D03*
X1201574Y12114D03*
X1187963Y14300D03*
X1193063Y14514D03*
X1187963Y11700D03*
X1193063Y11914D03*
X1184142Y-4100D03*
X1204921Y-9901D03*
X1201574Y-3700D03*
X1198228Y-9901D03*
X1187989Y-7050D03*
X1193063Y-7260D03*
X1187963Y-4401D03*
X1193063Y-4651D03*
X1208267Y-3700D03*
X1218307Y-9901D03*
X1214574Y-4100D03*
X1211614Y-9901D03*
X1208267Y12114D03*
X1218307Y17157D03*
X1211614D03*
X1214660Y12114D03*
X1174803Y-9901D03*
X1177763Y-4100D03*
X1181496Y-9901D03*
X1177849Y12114D03*
X1174803Y17157D03*
X1181496D03*
X1171456Y34100D03*
X1168110Y54957D03*
X1171456Y49914D03*
X1161417Y54957D03*
X1164763Y34100D03*
Y49914D03*
X1167925Y112357D03*
X1170721Y106964D03*
X1161632Y112357D03*
X1164428Y106964D03*
X1178099Y204496D03*
X1174719Y202547D03*
X1188239Y202247D03*
X1181479Y202547D03*
X1218868Y214869D03*
X1218000Y218100D03*
X1174719Y245447D03*
X1164580Y243496D03*
X1208519Y229847D03*
X1171339Y251296D03*
X1167960Y249347D03*
Y241547D03*
Y245447D03*
Y237647D03*
X1171339Y239596D03*
X1161200Y272747D03*
X1178099Y255196D03*
X1161200Y253247D03*
X1174719Y268847D03*
X1167960Y264947D03*
X1201759Y245447D03*
X1181479Y257147D03*
X1174719Y272747D03*
X1164580Y251296D03*
X1159390Y262460D03*
X1174719Y257147D03*
X1178099Y259096D03*
X1161200Y245447D03*
X1174719Y261047D03*
X1167960Y272747D03*
X1171339Y255196D03*
X1161200Y311747D03*
X1181479Y339047D03*
X1178099Y340996D03*
X1205139D03*
X1201759Y339047D03*
X1198379Y333196D03*
X1201759Y335147D03*
Y331247D03*
X1184859Y337096D03*
X1178099Y368296D03*
Y352696D03*
X1198379Y383896D03*
X1191619Y379996D03*
X1198379Y376096D03*
X1174719Y346847D03*
X1178099Y348796D03*
Y344896D03*
X1198379Y356596D03*
Y360496D03*
X1181479Y370247D03*
X1174719D03*
X1178099Y360496D03*
X1181479Y342947D03*
X1201759Y346847D03*
X1198379Y344896D03*
X1201759Y342947D03*
X1194999Y370247D03*
X1198379Y352696D03*
X1201759Y358547D03*
X1194999Y362447D03*
X1198379Y372197D03*
Y364396D03*
X1194999Y374146D03*
X1171339Y364396D03*
X1201759Y374146D03*
X1194999Y378047D03*
X1178099Y372197D03*
X1171339Y376096D03*
X1181479Y350747D03*
Y354647D03*
X1174719Y358547D03*
Y362447D03*
Y366347D03*
X1178099Y356596D03*
X1174719Y374146D03*
Y378047D03*
X1184859Y352696D03*
X1198379Y379996D03*
X1194999Y381947D03*
X1170656Y493844D03*
X1164363Y493744D03*
X1161417Y498487D03*
X1167510D03*
X1171456Y550914D03*
X1164763D03*
X1171456Y588714D03*
X1164763D03*
X1177849D03*
X1201574D03*
X1214660D03*
X1193063Y588514D03*
X1187963Y588300D03*
X1184142Y588714D03*
X1208267D03*
X1161417Y555957D03*
X1168110D03*
Y593757D03*
X1171456Y610700D03*
X1168110Y604499D03*
X1161417Y593757D03*
Y604499D03*
X1174803Y593757D03*
X1177763Y610300D03*
X1174803Y604499D03*
X1204921D03*
X1198228Y593757D03*
X1201574Y610700D03*
X1198228Y604499D03*
X1218307Y593757D03*
Y604499D03*
X1211614Y593757D03*
X1214574Y610300D03*
X1211614Y604499D03*
X1187963Y590900D03*
X1187989Y607350D03*
X1193063Y609749D03*
X1187963Y609999D03*
X1193063Y591114D03*
Y607140D03*
X1181496Y593757D03*
X1184142Y610300D03*
X1181496Y604499D03*
X1208267Y610700D03*
X1204921Y593757D03*
X1164763Y610700D03*
X1276346Y-10250D03*
X1220953Y-4100D03*
X1245078Y-3700D03*
X1241732Y-9901D03*
X1238385Y-3700D03*
X1235039Y-9901D03*
X1224800Y-7050D03*
X1229874Y-7260D03*
X1224774Y-4401D03*
X1229874Y-4651D03*
X1255118Y-9901D03*
Y-1743D03*
X1220953Y12114D03*
X1241732Y17157D03*
X1245078Y12114D03*
X1235039Y17157D03*
X1238385Y12114D03*
X1224774Y14300D03*
X1229874Y14514D03*
X1224774Y11700D03*
X1229874Y11914D03*
X1255118Y16999D03*
Y9157D03*
X1261811Y92599D03*
X1258464D03*
X1243948Y154916D03*
X1264550Y114670D03*
X1261030Y105350D03*
X1270350Y98300D03*
X1277600Y106200D03*
X1268576Y117788D03*
X1275470Y99390D03*
X1278030Y148510D03*
X1269810Y154398D03*
X1272100Y141603D03*
X1265828Y140568D03*
X1266646Y150540D03*
X1259950Y144650D03*
X1264700Y154800D03*
X1240022Y141773D03*
X1261546Y150584D03*
X1264146D03*
X1262569Y147201D03*
X1252000Y145300D03*
X1252437Y140192D03*
X1240010Y144754D03*
X1240309Y161900D03*
X1267050Y169800D03*
X1241381Y172040D03*
X1263300Y169450D03*
X1267800Y161800D03*
X1271400Y161900D03*
X1226867Y207904D03*
X1227200Y215543D03*
X1220702Y216708D03*
X1277504Y250346D03*
X1275154Y236296D03*
X1279950Y229338D03*
X1276628Y234270D03*
X1272761Y240220D03*
X1275577Y253123D03*
X1270478Y243490D03*
X1279393Y247602D03*
X1243399Y398339D03*
X1249230Y402022D03*
X1246010Y400110D03*
X1265157Y510157D03*
X1261811Y517999D03*
X1258464Y510157D03*
Y517999D03*
X1261811Y510157D03*
X1248425Y518057D03*
X1251771Y510157D03*
X1277800Y497108D03*
X1280595Y496439D03*
X1266162Y496404D03*
X1269006Y496016D03*
X1255120Y574834D03*
X1265157Y547957D03*
X1261811D03*
X1258464D03*
X1251771D03*
X1265157Y537057D03*
X1261811D03*
X1258464Y528899D03*
X1251771Y537057D03*
X1258464D03*
X1261811Y528899D03*
X1245078Y588714D03*
X1238385D03*
X1265157Y585757D03*
X1261811D03*
X1258464D03*
X1251771D03*
X1261811Y555799D03*
X1258464D03*
X1251771D03*
X1248425Y555857D03*
X1251771Y566699D03*
Y574857D03*
X1265157D03*
X1261811D03*
X1258464D03*
X1261811Y566699D03*
X1258464D03*
X1220953Y588714D03*
X1229874Y588514D03*
X1224774Y588300D03*
X1241732Y593757D03*
X1245078Y610700D03*
X1241732Y604499D03*
X1238385Y610700D03*
X1258464Y593599D03*
X1261811D03*
X1248425Y593657D03*
X1251771Y612657D03*
X1258464Y604499D03*
X1261811D03*
X1265157Y612657D03*
X1261811D03*
X1258464D03*
X1220953Y610300D03*
X1235039Y593757D03*
Y604499D03*
X1224774Y590900D03*
X1224800Y607350D03*
X1229874Y609749D03*
X1224774Y609999D03*
X1229874Y591114D03*
Y607140D03*
X1255120Y612634D03*
X1287700Y-16700D03*
X1292692Y1008D03*
X1299369Y-15680D03*
X1336500Y81100D03*
X1327168Y61483D03*
X1296935Y51335D03*
X1298754Y83233D03*
X1301219Y89141D03*
X1308983Y93814D03*
X1324127Y50827D03*
X1309700Y83300D03*
X1311559Y91431D03*
X1311551Y93952D03*
X1317300Y89600D03*
X1330300Y83500D03*
X1308400Y79600D03*
X1327900Y142918D03*
X1287790Y156575D03*
X1308972Y96742D03*
X1325125Y100001D03*
X1301770Y101300D03*
X1323026Y133323D03*
X1326026D03*
X1306900Y131744D03*
X1301900Y124400D03*
X1310061Y165235D03*
X1305171Y164767D03*
X1329324Y208951D03*
X1333074Y216500D03*
X1336074D03*
X1330074D03*
X1281799Y193190D03*
X1309462Y240229D03*
X1308200Y255800D03*
X1310950Y255650D03*
X1306585Y258250D03*
X1319310Y300795D03*
X1299700Y298557D03*
X1299735Y301298D03*
X1323688Y290205D03*
X1303866Y292345D03*
X1305558Y294313D03*
X1306290Y298255D03*
X1303380Y309441D03*
X1319297Y296878D03*
X1321600Y294700D03*
X1302203Y314439D03*
X1319888Y290205D03*
X1308887Y285015D03*
X1316600Y305500D03*
X1342570Y368220D03*
X1341954Y360368D03*
X1323815Y463543D03*
X1318054Y460507D03*
X1285769Y440062D03*
X1341528Y463528D03*
X1321172Y464474D03*
X1288671Y445338D03*
X1319320Y418900D03*
X1316820Y421400D03*
Y418900D03*
X1286831Y443058D03*
X1295960Y519450D03*
Y516450D03*
Y513450D03*
X1295880Y510810D03*
X1298460Y513450D03*
Y516450D03*
Y519450D03*
X1298380Y510810D03*
X1295660Y527700D03*
X1298460Y536700D03*
Y530700D03*
Y533700D03*
Y527700D03*
X1295660Y536700D03*
Y530700D03*
Y533700D03*
X1285400Y561000D03*
X1295090Y579360D03*
X1293290Y581160D03*
X1288100Y562000D03*
X1343100Y566300D03*
X1340700D03*
X1338000D03*
X1340526Y563337D03*
X1343026D03*
X1338026D03*
X1333026D03*
X1335526D03*
Y566237D03*
X1318500Y539900D03*
X1316100Y543400D03*
X1333026Y566237D03*
X1402600Y10000D03*
X1400100D03*
X1374100Y-16900D03*
X1376719Y-16802D03*
X1376842Y15185D03*
X1374431Y15170D03*
X1371598Y-11633D03*
X1371632Y-9191D03*
X1371653Y-16654D03*
X1371605Y-14069D03*
X1371941Y22617D03*
X1371950Y20200D03*
X1371900Y17800D03*
Y15400D03*
X1351500Y83000D03*
X1397550Y68059D03*
X1395050D03*
X1397050Y58559D03*
X1392050D03*
X1394550D03*
X1397050Y55559D03*
X1394550D03*
X1392050D03*
X1397539Y65098D03*
X1394939D03*
X1392339D03*
X1395000Y78800D03*
X1397400D03*
X1392584Y78798D03*
X1395000Y76200D03*
X1392584D03*
X1397400D03*
X1359500Y83000D03*
X1355500D03*
X1351488Y74000D03*
X1347500Y83000D03*
X1392149Y68006D03*
X1404200Y119200D03*
X1398600Y116500D03*
X1396780Y119080D03*
X1401200Y124300D03*
X1399400Y126400D03*
X1401300Y149600D03*
X1402500Y116300D03*
X1344462Y209272D03*
X1402020Y165561D03*
X1384671Y214832D03*
X1367789Y209216D03*
X1396933Y215763D03*
X1397211Y226041D03*
X1402400Y223600D03*
X1399852Y252353D03*
X1399978Y233775D03*
X1400066Y236274D03*
X1398600Y228700D03*
X1401565Y229435D03*
X1399600Y223600D03*
X1388518Y230789D03*
X1394881Y226997D03*
X1368200Y284000D03*
X1404286Y281729D03*
X1402092Y284022D03*
X1398347Y284023D03*
X1398926Y281582D03*
X1394260Y351170D03*
X1384300Y398900D03*
X1386800D03*
X1384252Y401343D03*
X1386752D03*
X1359600Y360800D03*
X1356466Y360680D03*
X1344731Y359567D03*
X1378200Y346900D03*
X1374344Y371431D03*
X1380200Y370400D03*
X1376979Y370536D03*
X1380800Y392300D03*
X1380200Y373100D03*
X1377103Y373428D03*
X1374300Y402053D03*
X1376800D03*
X1381752Y401343D03*
X1379252D03*
X1381800Y398900D03*
X1374300Y377885D03*
Y381485D03*
X1374268Y374285D03*
X1391845Y348325D03*
X1383700Y392300D03*
X1377028Y458125D03*
X1372028D03*
X1395375Y453561D03*
X1344090Y463630D03*
X1346739Y463615D03*
X1362560Y463478D03*
X1402775Y453561D03*
X1395375Y457561D03*
X1401398Y429775D03*
Y434775D03*
X1402775Y457561D03*
X1347546Y476897D03*
X1350500Y475100D03*
X1354462Y474141D03*
X1347196Y472941D03*
X1400980Y587086D03*
X1397980D03*
X1387907Y544286D03*
X1361600Y559400D03*
X1355548Y559959D03*
X1361926Y584037D03*
Y586537D03*
X1359100Y586200D03*
X1357400Y588400D03*
X1360100D03*
X1344613Y556376D03*
Y561376D03*
Y558876D03*
X1347700Y554100D03*
X1344613Y553876D03*
X1358439Y559959D03*
X1382331Y543818D03*
X1382032Y560143D03*
X1376070Y559760D03*
X1382200Y562700D03*
X1379000Y561500D03*
X1379053Y581864D03*
X1364426Y586637D03*
Y584137D03*
X1382500Y575400D03*
X1365028Y547954D03*
X1362528D03*
X1360500Y570900D03*
Y574700D03*
X1360261Y578873D03*
X1360247Y567390D03*
X1360261Y562373D03*
Y581373D03*
X1362000Y576700D03*
Y572800D03*
X1362100Y569100D03*
X1362000Y565600D03*
X1375961Y569473D03*
X1376000Y565700D03*
X1375961Y562273D03*
X1363761Y581373D03*
X1400216Y560128D03*
X1400980Y589586D03*
X1380890Y615820D03*
X1357726Y591037D03*
X1360226D03*
X1382586Y609602D03*
X1382605Y612102D03*
X1382200Y606300D03*
X1363761Y612573D03*
X1360261D03*
X1360200Y597800D03*
X1361600Y599900D03*
X1361500Y595700D03*
X1360100Y610100D03*
X1360200Y606300D03*
Y602000D03*
X1361900Y608200D03*
X1361500Y604200D03*
X1360261Y593573D03*
X1363761Y610073D03*
X1398010Y590040D03*
X1405100Y10000D03*
X1410600Y9100D03*
X1420337Y45477D03*
X1416837D03*
X1425081Y48412D03*
X1455889Y73700D03*
X1453221Y73750D03*
X1451590Y138750D03*
X1452232Y109500D03*
X1422196Y218052D03*
X1446331Y197285D03*
X1408247Y206270D03*
X1451365Y176014D03*
X1450532Y178372D03*
X1447999Y205645D03*
X1458908Y187699D03*
X1444850Y242730D03*
X1412579Y268273D03*
X1433362Y278244D03*
X1455600Y254826D03*
X1439700Y253100D03*
X1441750Y236800D03*
X1434300Y251600D03*
X1437400Y244150D03*
X1407274Y245652D03*
X1410979Y270473D03*
X1451850Y262200D03*
X1461348Y244350D03*
X1465063Y253544D03*
X1464700Y256100D03*
X1447154Y251710D03*
X1422281Y221479D03*
X1454056Y266169D03*
X1466404Y245350D03*
X1437800Y258300D03*
X1433700Y254200D03*
X1458318Y243000D03*
X1426905Y267045D03*
X1448500Y257700D03*
X1430365Y262624D03*
X1433057Y257388D03*
X1438500Y255400D03*
X1459548Y221731D03*
X1444311Y324366D03*
X1405392Y284022D03*
X1463942Y359742D03*
X1464400Y390800D03*
X1450400Y354300D03*
X1447685Y352025D03*
X1446700Y387900D03*
X1445100Y374900D03*
X1452699Y404060D03*
X1444400Y371600D03*
X1420515Y373585D03*
Y368585D03*
X1457300Y373600D03*
X1420075Y378375D03*
Y393402D03*
Y383375D03*
Y388402D03*
X1413735Y396302D03*
Y391302D03*
X1448800Y427800D03*
X1459478Y432851D03*
X1462131D03*
X1458300Y442675D03*
X1439000Y423000D03*
X1405423Y413281D03*
X1407158Y421575D03*
X1405423Y408281D03*
X1407158Y416575D03*
X1414982Y417040D03*
X1409300Y429775D03*
X1410475Y457561D03*
X1415146Y421946D03*
X1409300Y434775D03*
X1414107Y447267D03*
X1410475Y453561D03*
X1448000Y431500D03*
X1431900Y453500D03*
X1447500Y448000D03*
X1431900Y442600D03*
X1448000Y437000D03*
X1431900Y448000D03*
X1447700Y442500D03*
X1431900Y437100D03*
X1417800Y521500D03*
X1414800Y521400D03*
X1458935Y512470D03*
X1451150Y569900D03*
Y573200D03*
X1433100Y581770D03*
X1430570Y580890D03*
X1432590Y584550D03*
X1427500Y581100D03*
X1425243Y562260D03*
X1415173Y586332D03*
X1412673D03*
X1422920Y586250D03*
X1417920D03*
X1420420D03*
X1421560Y563455D03*
X1445145Y605727D03*
X1442525Y597279D03*
X1443654Y594749D03*
X1456277Y603454D03*
X1453628Y603368D03*
X1450720Y606067D03*
X1448071Y605981D03*
X1443473Y599944D03*
X1453451Y606114D03*
X1456100Y606200D03*
X1460200D03*
X1513700Y7082D03*
X1520700Y7100D03*
X1496660Y-10252D03*
X1509500Y31900D03*
X1470862Y38209D03*
X1499875Y86681D03*
X1526744Y93265D03*
X1499875Y90481D03*
X1482455Y124222D03*
X1473096Y120999D03*
X1468755Y128478D03*
X1475200Y142600D03*
X1511800Y127050D03*
X1526513Y120769D03*
Y103958D03*
X1500455Y110933D03*
X1496658Y115088D03*
X1472500Y123700D03*
X1473100Y131900D03*
X1473200Y118300D03*
X1484113Y128513D03*
X1500700Y127250D03*
X1498705Y99522D03*
X1483366Y120746D03*
X1473354Y153246D03*
X1526813Y108958D03*
X1526513Y115769D03*
X1500455Y114388D03*
X1496726Y120588D03*
X1473100Y128950D03*
X1485755Y131671D03*
X1500806Y133339D03*
X1526744Y98265D03*
X1483366Y115902D03*
X1498660Y102746D03*
X1507524Y218600D03*
X1512500Y199837D03*
X1492136Y199125D03*
X1497237Y217281D03*
X1478089Y182650D03*
X1511100Y186275D03*
X1470382Y188372D03*
X1472758Y216495D03*
X1476761Y157400D03*
X1471388Y173700D03*
X1493200Y162700D03*
X1474883Y182275D03*
X1492597Y172636D03*
X1474439Y207621D03*
X1470950Y252846D03*
X1469004Y246287D03*
X1467040Y260357D03*
X1470556Y256900D03*
X1468450Y252900D03*
X1499559Y231173D03*
X1478500Y252000D03*
X1479000Y254500D03*
X1496812Y273718D03*
X1491265Y226492D03*
X1519300Y245196D03*
X1491438Y221137D03*
X1503842Y245678D03*
X1499070Y255934D03*
X1504772Y259229D03*
X1507003Y272249D03*
X1521962Y278650D03*
X1479700Y224801D03*
X1482004Y222483D03*
X1474096Y256706D03*
X1483457Y244568D03*
X1487500Y244500D03*
X1486926Y247834D03*
X1470950Y229669D03*
X1471604Y246287D03*
X1482400Y248000D03*
X1502165Y251200D03*
X1500840Y319870D03*
X1517115Y330005D03*
X1470257Y321929D03*
X1473231Y320250D03*
X1504370Y330970D03*
X1492540Y328250D03*
X1516301Y313244D03*
X1487904Y337500D03*
X1514100Y321792D03*
X1514067Y315626D03*
X1496600Y281400D03*
X1487000Y333300D03*
X1497179Y306372D03*
X1508455Y313041D03*
X1503538Y318068D03*
X1495810Y341200D03*
X1524575Y387654D03*
X1487525Y384274D03*
X1483868Y390233D03*
X1499225Y377514D03*
X1502970Y350610D03*
X1470100Y392350D03*
X1467597Y363000D03*
X1470800Y395200D03*
X1473083Y393770D03*
X1489475Y387654D03*
X1493375D03*
X1520313Y357069D03*
X1478607Y359082D03*
X1526659Y397500D03*
X1524575Y380894D03*
X1522625Y377514D03*
X1507200Y358700D03*
X1498246Y357505D03*
X1489838Y350011D03*
X1483740Y359550D03*
X1483664Y362914D03*
X1483867Y356753D03*
X1501175Y394414D03*
X1499225Y384274D03*
X1470262Y420711D03*
X1491425Y411314D03*
X1487525D03*
X1515500Y413600D03*
X1528100Y413700D03*
X1512350Y410450D03*
X1521800Y419900D03*
X1501200Y450600D03*
X1505714Y448145D03*
X1501175Y443546D03*
X1503125Y446926D03*
X1505075Y457066D03*
X1524575D03*
X1524950Y445100D03*
Y448250D03*
X1521800Y445100D03*
X1528147Y454546D03*
X1509200Y410450D03*
X1467262Y420711D03*
X1487525Y480726D03*
X1470643Y495299D03*
X1482200Y477800D03*
X1482958Y486118D03*
X1472250Y485100D03*
X1526500Y503800D03*
Y501300D03*
X1503400Y524663D03*
X1492750Y615903D03*
X1494100Y613280D03*
X1497800Y610000D03*
X1497097Y613043D03*
X1527050Y613000D03*
X1523450Y612900D03*
X1519850Y613000D03*
X1487912Y611632D03*
X1491512Y611732D03*
X1484312D03*
X1569000Y3400D03*
X1589623Y24528D03*
X1545111Y24172D03*
X1551834Y23856D03*
X1554434D03*
X1571500Y-1406D03*
X1543500Y3400D03*
X1588962Y75926D03*
X1579807Y75841D03*
X1582407D03*
X1570511Y75396D03*
X1573076Y75328D03*
X1579100Y69000D03*
X1535300Y78490D03*
X1545572Y38188D03*
X1579310Y128604D03*
X1579290Y131104D03*
X1589880Y134851D03*
X1582500Y109900D03*
X1587620Y135921D03*
X1549187Y104713D03*
X1558136Y100877D03*
X1554627D03*
X1558100Y138025D03*
Y133526D03*
Y124427D03*
Y128926D03*
X1567000Y259560D03*
X1568120Y251710D03*
X1582699Y252646D03*
X1532237Y247801D03*
X1563157Y258164D03*
X1561104Y234255D03*
X1584568Y281339D03*
X1589476Y322953D03*
X1565235Y303734D03*
X1578577Y284799D03*
X1580365Y341293D03*
X1583794Y338767D03*
X1532850Y303950D03*
X1533838Y288706D03*
X1548334Y325497D03*
X1548273Y313227D03*
X1543864Y311399D03*
X1554775Y295328D03*
X1550619Y303087D03*
X1559997Y310317D03*
X1534400Y296029D03*
X1538450Y314300D03*
X1543700Y322600D03*
X1542200Y324600D03*
X1548024Y322145D03*
X1548000Y331361D03*
X1546612Y287812D03*
X1559800Y285300D03*
X1547882Y318942D03*
X1565244Y300934D03*
X1528475Y401174D03*
Y394414D03*
X1551875D03*
X1536275Y401174D03*
X1585150Y397400D03*
X1587683Y397414D03*
X1581822Y365770D03*
X1587968Y403368D03*
X1533589Y366361D03*
X1532367Y356530D03*
X1553825Y391034D03*
X1546025D03*
X1538200Y364700D03*
X1558950Y363050D03*
X1542932Y355740D03*
X1558980Y360130D03*
X1557534Y353400D03*
X1553825Y377514D03*
X1543300Y360900D03*
X1565525Y453686D03*
X1542125Y460446D03*
X1569425Y440166D03*
X1567475Y436786D03*
X1571375D03*
X1589500Y412035D03*
X1583208Y404941D03*
X1569425Y446926D03*
X1583773Y436137D03*
X1587238Y432593D03*
X1583208Y416752D03*
X1531250Y445100D03*
Y448250D03*
X1538225Y460446D03*
X1540700Y445100D03*
X1537550Y448250D03*
X1534400D03*
X1540700D03*
X1537550Y445100D03*
X1534400D03*
X1540700Y435650D03*
X1547754Y430351D03*
X1547755Y423570D03*
X1553825Y453686D03*
X1547000Y435650D03*
X1549925Y431594D03*
X1547755Y421138D03*
X1559595Y450631D03*
X1537550Y438800D03*
X1540700D03*
X1536300Y455200D03*
X1571545Y482842D03*
X1571375Y477346D03*
X1549925Y480726D03*
X1559675Y477346D03*
X1563575Y484106D03*
X1589025Y495975D03*
X1567475Y484106D03*
X1565525Y487486D03*
X1569425Y480726D03*
X1531685Y499540D03*
Y502040D03*
X1540175Y470586D03*
X1551875Y477346D03*
X1548300Y504000D03*
X1563575Y477346D03*
X1542475Y507000D03*
Y499400D03*
X1548300Y509200D03*
Y501500D03*
X1542475Y501900D03*
Y509600D03*
X1548300Y511800D03*
X1545200Y585724D03*
X1542600D03*
X1586700Y620100D03*
X1573260Y601600D03*
X1570660Y601563D03*
X1529067Y615784D03*
X1529697Y613384D03*
X1532270Y610764D03*
X1532160Y613408D03*
X1534968Y597268D03*
X1535565Y591658D03*
X1540477Y620308D03*
X1579680Y610279D03*
X1605500Y-3600D03*
X1592829Y24460D03*
X1597800Y24300D03*
X1637482Y21623D03*
X1617500Y-14500D03*
X1593000Y78140D03*
X1650876Y65237D03*
X1648276Y65221D03*
X1612000Y70984D03*
X1635337Y73500D03*
X1620900Y81300D03*
X1623200Y75800D03*
X1606797Y64949D03*
X1608452Y62890D03*
X1614997Y84403D03*
X1596050Y75400D03*
X1625075Y80182D03*
X1593241Y134295D03*
X1598449Y120760D03*
X1628950Y195344D03*
X1632590D03*
X1635351Y185444D03*
X1619500Y184944D03*
X1622248Y185060D03*
X1639258Y185620D03*
X1591865Y237407D03*
X1624798Y241937D03*
X1631300Y280400D03*
X1606849Y241210D03*
X1603307Y393224D03*
X1595800Y405900D03*
X1591430Y409440D03*
X1623749Y464213D03*
X1590581Y404170D03*
X1592025Y495975D03*
X1639391Y513065D03*
X1642670Y514939D03*
X1649545Y515215D03*
X1645969Y514870D03*
X1617700Y475957D03*
X1614000Y475970D03*
X1623705Y467855D03*
X1619607Y469945D03*
X1616607D03*
X1629778Y507294D03*
X1627407Y520318D03*
X1590881Y618788D03*
X1593519Y618736D03*
X1644856Y604930D03*
X1640921Y605334D03*
X1617600Y619800D03*
X1619700Y617300D03*
X1622330Y592325D03*
X1603550Y618250D03*
X1600950D03*
X1653100Y11500D03*
X1673500Y-16850D03*
X1680034Y2863D03*
X1690500Y73950D03*
X1669000Y92000D03*
X1659000Y88000D03*
X1661900Y92400D03*
X1709184Y88811D03*
X1658600Y44700D03*
X1675500Y81600D03*
X1673000D03*
X1678627Y54616D03*
X1664350Y72462D03*
Y69962D03*
X1669500Y51500D03*
X1659100Y73614D03*
X1668000Y81600D03*
X1665500D03*
X1697800Y94612D03*
X1692285D03*
X1660944Y36761D03*
X1680139Y99073D03*
X1660400Y98500D03*
X1674800Y103100D03*
X1678400Y103000D03*
X1680370Y185900D03*
X1663400Y179475D03*
X1681352Y196092D03*
X1682950Y184140D03*
X1680450Y183401D03*
X1660440Y200789D03*
X1702400Y193450D03*
X1660800Y181900D03*
X1687550Y213751D03*
X1709900Y187300D03*
X1705666Y198055D03*
X1674912Y183000D03*
X1664390Y201163D03*
X1671688Y182925D03*
X1683729Y242346D03*
X1681760Y245500D03*
X1683615Y250493D03*
X1681116Y238614D03*
X1679100Y271300D03*
X1680769Y242605D03*
X1651867Y484741D03*
X1651926Y482197D03*
X1671050Y490850D03*
X1687500Y505200D03*
X1705767Y482434D03*
X1687443Y487203D03*
X1681500Y482000D03*
X1678001Y473205D03*
X1680500Y473325D03*
X1687500Y484000D03*
X1690091Y503995D03*
X1671050Y487000D03*
X1684650Y505200D03*
X1701617Y482706D03*
X1775000Y53500D03*
X1720100Y46100D03*
X1746328Y59011D03*
X1746552Y38900D03*
X1766333Y59116D03*
X1758100Y119100D03*
X1761300D03*
X1730400Y195850D03*
X1733880Y232810D03*
X1715837Y246178D03*
X1724181Y246159D03*
X1739847Y233334D03*
X1736847D03*
X1719080Y232852D03*
X1733900Y237300D03*
X1736400D03*
X1719080Y236152D03*
X1722251Y250532D03*
X1751900Y249700D03*
X1746900Y249804D03*
X1716037Y444550D03*
X1724590Y444521D03*
X1721990D03*
X1718587Y444550D03*
X1716490Y506970D03*
X1754300Y487855D03*
X1741900Y487755D03*
X1766700Y475655D03*
X1749300Y487855D03*
X1736900Y487755D03*
X1774300Y475055D03*
X1761700Y475655D03*
X1719560Y501770D03*
X1736003Y588244D03*
X1743500Y564500D03*
X1738216Y548239D03*
X1753807Y548183D03*
X1757478Y548192D03*
X1738498Y554255D03*
X1743000Y574500D03*
X1739179Y592070D03*
X1739211Y596711D03*
X1718008Y592002D03*
X1716950Y603450D03*
X1739714Y604967D03*
X1835600Y3900D03*
X1804800Y-1500D03*
X1825324Y1000D03*
X1832900Y10300D03*
X1785366Y8100D03*
X1836700Y-18900D03*
X1819800Y2100D03*
X1813913Y2287D03*
X1823600Y8800D03*
X1809822Y26585D03*
X1807127Y26918D03*
X1808100Y21800D03*
X1797700Y21018D03*
X1791500Y26918D03*
X1786865Y22375D03*
X1829888Y10735D03*
X1815637Y54775D03*
X1818396Y54752D03*
X1779750Y36530D03*
X1784341Y64841D03*
X1789356Y38286D03*
X1796100Y68800D03*
X1826900Y40400D03*
X1802119Y56581D03*
X1794100Y70898D03*
X1776828Y155211D03*
X1815883Y133277D03*
X1813118Y127976D03*
X1803509Y128500D03*
X1800420Y148240D03*
X1833629Y170807D03*
X1824200Y176900D03*
X1816125Y169492D03*
X1807440Y165530D03*
Y169030D03*
Y162030D03*
X1793600Y235100D03*
X1793700Y232500D03*
X1806083Y232584D03*
X1803280Y232611D03*
X1790250Y522350D03*
X1834100Y523900D03*
X1820400Y501100D03*
X1804500Y526200D03*
X1816800Y525700D03*
X1829967Y476927D03*
X1817375Y478320D03*
X1794975Y479300D03*
X1779300Y475055D03*
X1825297Y476927D03*
X1812375Y478320D03*
X1789975Y479300D03*
X1801525Y473955D03*
X1806525D03*
X1818509Y527893D03*
X1829000Y536315D03*
X1792170Y583900D03*
X1785050Y584550D03*
X1792100Y566900D03*
X1811704Y554341D03*
X1780394Y561076D03*
X1781300Y537800D03*
X1829300Y572900D03*
X1816458Y587480D03*
X1787500Y597791D03*
X1837900Y9700D03*
X1883041Y15814D03*
X1882999Y7383D03*
X1848322Y12723D03*
X1841289Y21631D03*
X1843426Y9528D03*
X1893081Y-20735D03*
X1893094Y-12642D03*
X1853467Y35000D03*
X1841060Y35540D03*
X1846527Y34435D03*
X1849027Y34426D03*
X1850600Y41348D03*
X1858198Y41108D03*
X1860786Y41200D03*
X1855400Y40800D03*
X1889218Y56030D03*
Y61030D03*
Y46030D03*
Y51030D03*
X1878000Y73950D03*
X1867619Y39779D03*
X1854115Y131121D03*
X1839667Y151994D03*
X1848100Y134750D03*
X1839941Y156858D03*
X1871521Y153593D03*
X1875600Y156300D03*
X1886050Y151431D03*
X1860969Y136369D03*
Y133769D03*
X1857849Y148079D03*
X1854962Y133613D03*
X1894855Y142122D03*
X1893640Y147042D03*
X1888639D03*
X1868843Y207920D03*
X1839873Y159358D03*
X1854942Y181655D03*
X1836932Y170486D03*
X1858470Y206335D03*
X1855670Y206430D03*
X1863650Y189750D03*
X1893238Y208042D03*
X1863750Y163750D03*
X1886400Y170000D03*
X1886200Y161000D03*
X1857400Y175900D03*
X1862000Y177500D03*
X1876832Y173919D03*
X1875066Y175782D03*
X1886952Y213125D03*
X1883800Y213436D03*
X1884340Y217866D03*
X1874236Y213800D03*
X1886093Y202184D03*
X1878789Y213663D03*
X1883800Y210575D03*
X1889400Y191200D03*
X1854374Y248790D03*
X1843600Y239000D03*
X1840300Y239300D03*
X1861605Y253925D03*
X1881900Y224100D03*
X1864305Y253825D03*
X1870815Y453022D03*
X1858633Y452803D03*
X1844630Y454321D03*
X1859059Y448076D03*
X1872860Y450550D03*
Y447950D03*
X1866050Y451100D03*
X1841630Y454321D03*
X1863137Y452710D03*
X1842450Y507520D03*
X1896700Y472600D03*
X1896800Y470200D03*
X1894100Y472600D03*
X1894200Y470200D03*
X1837857Y468630D03*
X1842857D03*
X1876945Y471316D03*
X1837534Y579322D03*
X1857108Y550108D03*
X1852400Y554900D03*
X1840700Y563800D03*
X1856573Y576534D03*
X1857812Y557245D03*
X1895523Y586365D03*
X1856040Y588704D03*
X1839126Y583354D03*
X1896358Y595255D03*
X1946500Y104974D03*
X1904215Y142812D03*
X1911961Y153000D03*
X1905092Y150170D03*
X1944609Y149184D03*
X1944600Y151700D03*
X1932998Y119438D03*
X1911440Y128840D03*
X1933914Y96040D03*
X1899855Y142122D03*
X1909216Y142812D03*
X1908327Y149353D03*
X1934256Y99459D03*
X1913392Y149381D03*
X1938400Y178200D03*
X1932837Y186700D03*
X1939200Y194300D03*
X1910123Y217349D03*
X1957334Y201269D03*
X1939300Y204300D03*
X1928249Y178179D03*
X1903150Y217250D03*
X1935600Y176300D03*
X1944463Y228458D03*
X1903032Y228368D03*
X1944925Y226001D03*
X1903020Y225776D03*
X1920472Y447930D03*
X1942000Y440500D03*
X1904724Y447930D03*
X1901574Y454422D03*
X1899100Y472600D03*
X1899200Y470200D03*
X1904200Y472700D03*
X1901700Y472600D03*
X1904300Y470300D03*
X1901800Y470200D03*
X1942328Y508712D03*
X1899800Y548100D03*
X1973004Y143120D03*
X1964382Y147318D03*
G54D31*
G01X680370Y427770D02*
Y428870D01*
X679870Y429370D01*
X615478D01*
X574854Y388746D01*
Y362543D01*
X572092Y359781D01*
G01X680200Y432100D02*
Y430870D01*
X679700Y430370D01*
X615063D01*
X573854Y389161D01*
Y362958D01*
X571383Y360489D01*
G01X765116Y216512D02*
X765912Y215716D01*
X767330D01*
X769200Y217586D01*
Y225990D01*
X767440Y227750D01*
X757642D01*
X755133Y230259D01*
Y243815D01*
X747000Y251948D01*
Y255800D01*
X748700Y257500D01*
G01X765144Y213508D02*
X766352Y214716D01*
X767745D01*
X770200Y217171D01*
Y226405D01*
X767855Y228750D01*
X758057D01*
X756133Y230674D01*
Y244230D01*
X748000Y252363D01*
Y253300D01*
X748700Y254000D01*
G01X754263Y254207D02*
X753667Y253611D01*
Y252453D01*
X758768Y247352D01*
X763956D01*
X765116Y248512D01*
G01X749090Y270250D02*
X750090Y269250D01*
X758500D01*
X759000Y269750D01*
Y272315D01*
X761100Y274415D01*
Y277577D01*
X763026Y279503D01*
X764107D01*
X765116Y280512D01*
G01X754846Y276340D02*
X755621Y275565D01*
X756954D01*
X757393Y276004D01*
Y278765D01*
X756044Y280114D01*
Y290082D01*
X757000Y291038D01*
Y306500D01*
X761923Y311423D01*
X764027D01*
X765116Y312512D01*
G01X751363Y254207D02*
X752667Y252903D01*
Y252038D01*
X758353Y246352D01*
X764300D01*
X765144Y245508D01*
G01X748990Y267450D02*
X749790Y268250D01*
X758915D01*
X760000Y269335D01*
Y271900D01*
X762100Y274000D01*
Y277162D01*
X763441Y278503D01*
X764149D01*
X765144Y277508D01*
G01X754758Y273356D02*
X755967Y274565D01*
X757369D01*
X758393Y275589D01*
Y279180D01*
X757044Y280529D01*
Y289667D01*
X758000Y290623D01*
Y306085D01*
X762338Y310423D01*
X764229D01*
X765144Y309508D01*
G01X749100Y279500D02*
X750100D01*
X752150Y281550D01*
Y318261D01*
X760600Y326711D01*
Y340101D01*
X762850Y342351D01*
X764301D01*
X765144Y341508D01*
G01X749800Y282300D02*
X751150Y283650D01*
Y318676D01*
X759600Y327126D01*
Y340516D01*
X762435Y343351D01*
X763955D01*
X765116Y344512D01*
G01X737750Y298894D02*
X738997Y300141D01*
Y309231D01*
X733300Y314928D01*
Y326815D01*
X737900Y331415D01*
Y350715D01*
X744085Y356900D01*
X752801D01*
X756300Y360399D01*
Y367600D01*
X760500Y371800D01*
Y374216D01*
X761593Y375309D01*
X762693D01*
X764131Y376747D01*
G01X741250Y298856D02*
X739997Y300109D01*
Y309646D01*
X734300Y315343D01*
Y326400D01*
X738900Y331000D01*
Y350300D01*
X744500Y355900D01*
X753216D01*
X757300Y359984D01*
Y367185D01*
X761500Y371385D01*
Y373801D01*
X762008Y374309D01*
X763593D01*
X764159Y373743D01*
G01X840871Y391380D02*
X839600Y390109D01*
Y376488D01*
X845290Y370798D01*
X856375D01*
X894073Y333100D01*
X907301D01*
X908521Y334320D01*
X910260D01*
G01X837272Y391420D02*
X838700Y389992D01*
Y376115D01*
X844917Y369898D01*
X856002D01*
X893700Y332200D01*
X907674D01*
X908894Y333420D01*
X910410D01*
G01X1200948Y312247D02*
X1203141D01*
X1203644Y312750D01*
X1214800D01*
X1219719Y307831D01*
X1301501D01*
X1304971Y304361D01*
X1309841D01*
X1314852Y299350D01*
X1317839D01*
X1319297Y300808D01*
Y300795D01*
X1319310D01*
G01X1319297Y296878D02*
X1317825Y298350D01*
X1314437D01*
X1309426Y303361D01*
X1304556D01*
X1301086Y306831D01*
X1219304D01*
X1214385Y311750D01*
X1204059D01*
X1203556Y311247D01*
X1200948D01*
G01X1341954Y360368D02*
X1341953D01*
X1344785Y363200D01*
X1346840D01*
X1352522Y357518D01*
X1386051D01*
X1392399Y351170D01*
X1394260D01*
G01X1344731Y359567D02*
X1344283Y360015D01*
Y361425D01*
X1345158Y362300D01*
X1346467D01*
X1352149Y356618D01*
X1385678D01*
X1391845Y350451D01*
Y348325D01*
G01X1356466Y360680D02*
X1359235Y363449D01*
X1382635D01*
X1386800Y367614D01*
Y384812D01*
X1381780Y389832D01*
Y391320D01*
X1380800Y392300D01*
G01X1359600Y360800D02*
X1361249Y362449D01*
X1383050D01*
X1387800Y367199D01*
Y385227D01*
X1382780Y390247D01*
Y391380D01*
X1383700Y392300D01*
G01X1382605Y612102D02*
X1383357Y611350D01*
X1386651D01*
X1389000Y609001D01*
Y602415D01*
X1389400Y602015D01*
Y590715D01*
X1395300Y584815D01*
Y572753D01*
X1401053Y567000D01*
X1422638D01*
X1423810Y565828D01*
Y564705D01*
X1425395Y563120D01*
Y562412D01*
X1425243Y562260D01*
G01X1382586Y609602D02*
X1383334Y610350D01*
X1386236D01*
X1388000Y608586D01*
Y602000D01*
X1388400Y601600D01*
Y590300D01*
X1394300Y584400D01*
Y572338D01*
X1400638Y566000D01*
X1422223D01*
X1422810Y565413D01*
Y564705D01*
X1421560Y563455D01*
G54D13*
X30500Y-42250D03*
Y-52250D03*
X12290Y264640D03*
X18450Y267010D03*
X22970Y244400D03*
X28720Y244450D03*
X17120Y244220D03*
X24200Y267060D03*
X50500Y-42250D03*
X70500D03*
X90500D03*
X110500D03*
X50500Y-52250D03*
X70500D03*
X90500D03*
X110500D03*
X120500Y-42250D03*
Y-52250D03*
X457246Y-52301D03*
Y-42301D03*
X477246Y-52301D03*
Y-42301D03*
X497246Y-52301D03*
Y-42301D03*
X517246Y-52301D03*
Y-42301D03*
X537246Y-52301D03*
Y-42301D03*
X547246Y-52301D03*
Y-42301D03*
X788984Y-52057D03*
Y-42057D03*
X808984Y-52057D03*
Y-42057D03*
X828984Y-52057D03*
Y-42057D03*
X848984Y-52057D03*
Y-42057D03*
X868984Y-52057D03*
Y-42057D03*
X878984Y-52057D03*
Y-42057D03*
X1125583Y-52285D03*
Y-42285D03*
X1145583Y-52285D03*
Y-42285D03*
X1155583Y-52285D03*
Y-42285D03*
X1382258Y-52257D03*
Y-42257D03*
X1402258Y-52257D03*
Y-42257D03*
X1422258Y-52257D03*
Y-42257D03*
X1432258Y-52257D03*
Y-42257D03*
G54D22*
X531871Y202547D03*
X525111D03*
X947887Y324160D03*
G54D32*
G01X1155583Y-42285D02*
X1159783Y-46485D01*
X1162125D01*
X1165440Y-49800D01*
X1363500D01*
G03Y-47298I0J1251D01*
G01X1169200D01*
G02Y-41596I0J2851D01*
G01X1365113D01*
G01X1155583Y-52285D02*
X1159783Y-48085D01*
X1161462D01*
X1164777Y-51400D01*
X1363500D01*
G03Y-45698I0J2851D01*
G01X1169200D01*
G02Y-43196I0J1251D01*
G01X1365113D01*
G01X1908327Y149353D02*
X1909610Y149362D01*
X1910138Y148838D01*
Y147238D01*
X1913824Y143552D01*
X1916011D01*
X1918509Y146050D01*
X1919074D01*
X1920280Y144844D01*
Y144277D01*
X1917568Y141565D01*
Y139319D01*
X1921756Y135131D01*
Y133488D01*
X1923095Y132149D01*
X1925759D01*
X1926161Y131747D01*
Y130049D01*
X1925759Y129647D01*
X1923095D01*
X1921756Y128308D01*
Y125080D01*
X1920436Y123760D01*
Y121536D01*
X1919288Y120388D01*
Y119182D01*
X1920436Y118034D01*
Y116828D01*
X1922216Y115048D01*
Y114481D01*
X1921129Y113394D01*
Y111500D01*
X1923268Y109361D01*
X1925162D01*
X1926249Y110448D01*
X1926816D01*
X1928969Y108295D01*
X1931923D01*
X1932370Y107848D01*
Y106195D01*
X1931968Y105793D01*
X1925501D01*
X1924162Y104454D01*
Y101475D01*
X1925546Y100091D01*
X1929697D01*
X1930099Y99689D01*
Y97991D01*
X1929697Y97589D01*
X1926693D01*
X1925354Y96250D01*
Y93226D01*
X1926693Y91887D01*
X1932121D01*
X1932523Y91485D01*
Y89787D01*
X1932121Y89385D01*
X1921747D01*
X1920408Y88046D01*
Y85225D01*
X1921950Y83683D01*
X1932121D01*
X1932523Y83281D01*
Y81583D01*
X1932121Y81181D01*
X1924853D01*
X1923259Y79587D01*
Y71701D01*
X1930419Y64541D01*
X1939500D01*
X1939902Y64139D01*
Y62328D01*
X1939500Y61926D01*
X1926287D01*
X1925885Y62328D01*
Y64203D01*
X1924546Y65542D01*
X1921522D01*
X1920183Y64203D01*
Y62328D01*
X1919196Y61341D01*
X1903771D01*
X1898838Y56408D01*
X1898270D01*
X1897164Y57514D01*
X1895270D01*
X1893129Y55373D01*
Y53479D01*
X1894235Y52373D01*
Y51805D01*
X1891783Y49353D01*
X1889620D01*
X1889218Y49755D01*
Y51030D01*
G01X1913392Y149381D02*
X1912237Y149374D01*
X1911738Y148871D01*
Y147901D01*
X1914487Y145152D01*
X1915348D01*
X1917846Y147650D01*
X1919737D01*
X1921880Y145507D01*
Y143614D01*
X1919168Y140902D01*
Y139982D01*
X1923356Y135794D01*
Y134151D01*
X1923758Y133749D01*
X1926422D01*
X1927761Y132410D01*
Y129386D01*
X1926422Y128047D01*
X1923758D01*
X1923356Y127645D01*
Y124417D01*
X1922036Y123097D01*
Y117491D01*
X1923816Y115711D01*
Y113818D01*
X1922729Y112731D01*
Y112163D01*
X1923931Y110961D01*
X1924499D01*
X1925586Y112048D01*
X1927479D01*
X1929632Y109895D01*
X1932586D01*
X1933970Y108511D01*
Y105532D01*
X1932631Y104193D01*
X1926164D01*
X1925762Y103791D01*
Y102138D01*
X1926209Y101691D01*
X1930360D01*
X1931699Y100352D01*
Y97328D01*
X1930360Y95989D01*
X1927356D01*
X1926954Y95587D01*
Y93889D01*
X1927356Y93487D01*
X1932784D01*
X1934123Y92148D01*
Y89124D01*
X1932784Y87785D01*
X1922410D01*
X1922008Y87383D01*
Y85888D01*
X1922613Y85283D01*
X1932784D01*
X1934123Y83944D01*
Y80920D01*
X1932784Y79581D01*
X1925516D01*
X1924859Y78924D01*
Y72364D01*
X1931082Y66141D01*
X1940163D01*
X1941502Y64802D01*
Y61665D01*
X1940163Y60326D01*
X1925624D01*
X1924285Y61665D01*
Y63540D01*
X1923883Y63942D01*
X1922185D01*
X1921783Y63540D01*
Y61665D01*
X1919859Y59741D01*
X1904434D01*
X1899501Y54808D01*
X1897607D01*
X1896501Y55914D01*
X1895933D01*
X1894729Y54710D01*
Y54142D01*
X1895835Y53036D01*
Y51142D01*
X1892446Y47753D01*
X1889620D01*
X1889218Y47351D01*
Y46030D01*
G01X1904215Y142812D02*
X1905928D01*
X1906428Y142312D01*
Y140270D01*
X1907787Y138911D01*
X1912146D01*
X1914994Y136063D01*
Y132919D01*
X1916072Y131841D01*
Y122995D01*
X1915160Y122083D01*
Y121043D01*
X1914680Y120563D01*
X1913408D01*
X1912693Y121278D01*
X1910441D01*
X1908660Y119497D01*
Y117245D01*
X1909375Y116530D01*
Y115962D01*
X1908364Y114951D01*
Y108566D01*
X1909801Y107129D01*
X1912344D01*
X1914955Y109740D01*
X1916030D01*
X1918641Y107129D01*
X1919573D01*
X1920007Y106695D01*
Y105061D01*
X1919573Y104627D01*
X1911732D01*
X1910393Y103288D01*
Y100264D01*
X1911732Y98925D01*
X1914145D01*
X1914587Y98483D01*
Y96825D01*
X1914185Y96423D01*
X1910628D01*
X1909289Y95084D01*
Y92060D01*
X1910628Y90721D01*
X1914464D01*
X1914916Y90269D01*
Y88621D01*
X1914084Y87789D01*
X1911369D01*
X1909698Y86118D01*
Y83758D01*
X1911369Y82087D01*
X1915955D01*
X1916493Y81549D01*
Y80981D01*
X1913624Y78112D01*
Y75652D01*
X1914963Y74313D01*
X1918513D01*
X1919157Y73669D01*
Y72455D01*
X1918513Y71811D01*
X1915527D01*
X1914188Y70472D01*
Y65813D01*
X1913818Y65443D01*
X1912056D01*
X1911653Y65846D01*
Y73607D01*
X1910118Y75142D01*
X1907486D01*
X1905951Y73607D01*
Y67088D01*
X1905164Y66301D01*
X1902661D01*
X1901808Y65448D01*
X1900185D01*
X1899332Y64595D01*
Y62972D01*
X1898120Y61760D01*
X1893265D01*
X1890516Y59011D01*
X1889719D01*
X1889218Y59512D01*
Y61030D01*
G01X1909216Y142812D02*
X1908408D01*
X1908028Y142432D01*
Y140933D01*
X1908450Y140511D01*
X1912809D01*
X1916594Y136726D01*
Y133582D01*
X1917672Y132504D01*
Y122332D01*
X1916760Y121420D01*
Y120380D01*
X1915343Y118963D01*
X1912745D01*
X1912030Y119678D01*
X1911104D01*
X1910260Y118834D01*
Y117908D01*
X1910975Y117193D01*
Y115299D01*
X1909964Y114288D01*
Y109229D01*
X1910464Y108729D01*
X1911681D01*
X1914292Y111340D01*
X1916693D01*
X1919304Y108729D01*
X1920236D01*
X1921607Y107358D01*
Y104398D01*
X1920236Y103027D01*
X1912395D01*
X1911993Y102625D01*
Y100927D01*
X1912395Y100525D01*
X1914808D01*
X1916187Y99146D01*
Y96162D01*
X1914848Y94823D01*
X1911291D01*
X1910889Y94421D01*
Y92723D01*
X1911291Y92321D01*
X1915127D01*
X1916516Y90932D01*
Y87958D01*
X1914747Y86189D01*
X1912032D01*
X1911298Y85455D01*
Y84421D01*
X1912032Y83687D01*
X1916618D01*
X1918093Y82212D01*
Y80318D01*
X1915224Y77449D01*
Y76315D01*
X1915626Y75913D01*
X1919176D01*
X1920757Y74332D01*
Y71792D01*
X1919176Y70211D01*
X1916190D01*
X1915788Y69809D01*
Y65150D01*
X1914481Y63843D01*
X1911393D01*
X1910053Y65183D01*
Y72944D01*
X1909455Y73542D01*
X1908149D01*
X1907551Y72944D01*
Y66425D01*
X1905827Y64701D01*
X1903324D01*
X1898783Y60160D01*
X1893928D01*
X1891179Y57411D01*
X1890084D01*
X1889218Y56545D01*
Y56030D01*
G54D23*
X1809504Y-15000D03*
G54D14*
X28740Y124843D03*
X12205D03*
G54D33*
G01X445875Y109217D02*
Y106583D01*
G01X1087795Y-4536D02*
Y-2404D01*
X1087797Y-2402D01*
G01X1095483Y106583D02*
Y109217D01*
G54D15*
X18228Y178386D03*
X-1969D03*
X44291D03*
G54D24*
X1934597Y495775D03*
X1924754D03*
G54D34*
G01X-19776Y333229D02*
Y264124D01*
G01Y261965D02*
Y246665D01*
G01X40512Y467244D02*
X47746Y460010D01*
Y443123D01*
X32260Y427637D01*
Y416537D01*
X36883Y411914D01*
Y356849D01*
X30984Y350950D01*
X-4249D01*
X-21327Y333872D01*
Y177898D01*
X-11679Y168250D01*
X36751D01*
X41757Y163244D01*
Y153332D01*
X53368Y141721D01*
Y89271D01*
X46011Y81914D01*
Y17874D01*
X52779Y11106D01*
Y3321D01*
X54951Y1149D01*
Y-1822D01*
X61537Y-8408D01*
X65085D01*
X68931Y-12254D01*
Y-19321D01*
X71257Y-21647D01*
X406158D01*
X408820Y-18985D01*
X462616D01*
X465023Y-21392D01*
X649970D01*
X655023Y-16339D01*
Y-1766D01*
X663309Y6520D01*
X679522D01*
X683156Y10154D01*
X703696D01*
X705250Y8600D01*
G01X260369Y261630D02*
X261123D01*
X262568Y260185D01*
X264549D01*
G02X266494Y259022I-70J-2325D01*
G03X269224I1365J787D01*
G02X271169Y260185I2015J-1162D01*
G01X271309D01*
G02X273254Y259022I-70J-2325D01*
G03X275984I1365J787D01*
G02X277929Y260185I2015J-1162D01*
G01X278058D01*
G03X279364Y260972I-59J1575D01*
G02X281294Y262134I2015J-1163D01*
G01X281423D01*
G03X282744Y262922I-44J1575D01*
G02X284689Y264085I2015J-1162D01*
G01X284818D01*
G03X286124Y264872I-59J1575D01*
G02X288054Y266034I2015J-1163D01*
G01X288183D01*
G03X289504Y266822I-44J1575D01*
G02X291449Y267985I2015J-1162D01*
G01X291589D01*
G02X293534Y266822I-70J-2325D01*
G03X294855Y266034I1365J787D01*
G01X294984D01*
G02X296914Y264872I-85J-2325D01*
G01X297163Y264445D01*
X298301Y261817D01*
X298279Y261760D01*
G01X257250Y236942D02*
X258103Y236089D01*
X266039D01*
X268886Y238936D01*
X269224Y239522D01*
G02X271169Y240685I2015J-1162D01*
G01X271309D01*
G02X273254Y239522I-70J-2325D01*
G03X275984I1365J787D01*
G02X277929Y240685I2015J-1162D01*
G01X278058D01*
G03X279364Y241472I-59J1575D01*
G02X281294Y242634I2015J-1163D01*
G01X281423D01*
G03X282744Y243422I-44J1575D01*
G02X284689Y244585I2015J-1162D01*
G01X284818D01*
G03X286124Y245372I-59J1575D01*
G02X288054Y246534I2015J-1163D01*
G01X288183D01*
G03X289504Y247322I-44J1575D01*
G02X291449Y248485I2015J-1162D01*
G01X292168D01*
X293959Y249374D01*
G02X294840Y249684I940J-1265D01*
G01X294958D01*
G02X296264Y248897I-59J-1575D01*
G03X298194Y247735I2015J1163D01*
G01X298323D01*
G02X299644Y246947I-44J-1575D01*
G01X299710Y246831D01*
X301659Y244209D01*
G01X257448Y234442D02*
X258347Y235341D01*
X266433D01*
X269376Y238284D01*
X269874Y239147D01*
G02X272604I1365J-787D01*
G03X274549Y237984I2015J1162D01*
G01X274689D01*
G03X276634Y239147I-70J2325D01*
G02X277955Y239935I1365J-787D01*
G01X278084D01*
G03X280014Y241097I-85J2325D01*
G02X281320Y241884I1365J-788D01*
G01X281449D01*
G03X283394Y243047I-70J2325D01*
G02X284715Y243835I1365J-787D01*
G01X284844D01*
G03X286774Y244997I-85J2325D01*
G02X288080Y245784I1365J-788D01*
G01X288209D01*
G03X290154Y246947I-70J2325D01*
G02X291475Y247735I1365J-787D01*
G01X292168D01*
X293923Y246872D01*
G03X294855Y246534I976J1237D01*
G01X294984D01*
G02X296914Y245372I-85J-2325D01*
G03X298220Y244585I1365J788D01*
G01X298349D01*
G02X300294Y243422I-70J-2325D01*
G03X301615Y242634I1365J787D01*
G01X301805D01*
X305039Y242260D01*
G01X260086Y259130D02*
X262018D01*
X262323Y259435D01*
X264523D01*
G02X265844Y258647I-44J-1575D01*
G03X267789Y257484I2015J1162D01*
G01X267929D01*
G03X269874Y258647I-70J2325D01*
G02X272604I1365J-787D01*
G03X274549Y257484I2015J1162D01*
G01X274689D01*
G03X276634Y258647I-70J2325D01*
G02X277955Y259435I1365J-787D01*
G01X278084D01*
G03X280014Y260597I-85J2325D01*
G02X281320Y261384I1365J-788D01*
G01X281449D01*
G03X283394Y262547I-70J2325D01*
G02X284715Y263335I1365J-787D01*
G01X284844D01*
G03X286774Y264497I-85J2325D01*
G02X288080Y265284I1365J-788D01*
G01X288209D01*
G03X290154Y266447I-70J2325D01*
G02X292884I1365J-787D01*
G03X294829Y265284I2015J1162D01*
G01X294958D01*
G02X296264Y264497I-59J-1575D01*
G01X296496Y264096D01*
X296553Y263348D01*
X296499Y262469D01*
X296754Y261362D01*
G03X298220Y260185I1525J398D01*
G01X298678D01*
X300843Y261158D01*
G02X301600Y261384I815J-1349D01*
G01X301718D01*
G02X303024Y260597I-59J-1575D01*
G01X303090Y260481D01*
X305039Y257860D01*
G01X259009Y243480D02*
X259854Y242635D01*
X260800D01*
X260803Y242632D01*
X261166D01*
X262898Y244364D01*
X262897D01*
Y244366D01*
X263116Y244585D01*
X264977D01*
G02X266351Y243411I-798J-2325D01*
G03X267204Y242634I1508J798D01*
G01X267903D01*
G03X269224Y243422I-44J1575D01*
G02X271169Y244585I2015J-1162D01*
G01X271309D01*
G02X273254Y243422I-70J-2325D01*
G03X275984I1365J787D01*
G02X277929Y244585I2015J-1162D01*
G01X278058D01*
G03X279364Y245372I-59J1575D01*
G02X281294Y246534I2015J-1163D01*
G01X281423D01*
G03X282744Y247322I-44J1575D01*
G02X284689Y248485I2015J-1162D01*
G01X284818D01*
G03X286124Y249272I-59J1575D01*
G02X288054Y250434I2015J-1163D01*
G01X288183D01*
G03X289504Y251222I-44J1575D01*
G02X291449Y252385I2015J-1162D01*
G01X292062D01*
X294858Y252060D01*
X294899Y252009D01*
G01X259087Y240980D02*
X259991Y241884D01*
X261476D01*
X263427Y243835D01*
X264834D01*
G02X265687Y243058I-655J-1575D01*
G03X267061Y241884I2172J1151D01*
G01X267929D01*
G03X269874Y243047I-70J2325D01*
G02X272604I1365J-787D01*
G03X274549Y241884I2015J1162D01*
G01X274689D01*
G03X276634Y243047I-70J2325D01*
G02X277955Y243835I1365J-787D01*
G01X278084D01*
G03X280014Y244997I-85J2325D01*
G02X281320Y245784I1365J-788D01*
G01X281449D01*
G03X283394Y246947I-70J2325D01*
G02X284715Y247735I1365J-787D01*
G01X284844D01*
G03X286774Y248897I-85J2325D01*
G02X288080Y249684I1365J-788D01*
G01X288209D01*
G03X290154Y250847I-70J2325D01*
G02X291475Y251635I1365J-787D01*
G01X292000D01*
X293960Y250744D01*
G03X294855Y250434I939J1265D01*
G01X295045D01*
X298279Y250060D01*
G01X301659Y263709D02*
X300457Y266480D01*
G03X298349Y267985I-2177J-821D01*
G01X298220D01*
G02X296914Y268772I59J1575D01*
G03X294984Y269934I-2015J-1163D01*
G01X294855D01*
G02X293534Y270722I44J1575D01*
G03X291589Y271885I-2015J-1162D01*
G01X291449D01*
G03X289504Y270722I70J-2325D01*
G02X288183Y269934I-1365J787D01*
G01X288054D01*
G03X286124Y268772I85J-2325D01*
G02X284818Y267985I-1365J788D01*
G01X284689D01*
G03X282744Y266822I70J-2325D01*
G02X281423Y266034I-1365J787D01*
G01X281294D01*
G03X279364Y264872I85J-2325D01*
G02X278058Y264085I-1365J788D01*
G01X277929D01*
G03X275984Y262922I70J-2325D01*
G02X273254I-1365J787D01*
G03X271309Y264085I-2015J-1162D01*
G01X271169D01*
G03X269224Y262922I70J-2325D01*
G02X266494I-1365J787D01*
G03X264549Y264085I-2015J-1162D01*
G01X263343D01*
X262368Y265060D01*
Y265467D01*
X261205Y266630D01*
X259321D01*
G01X260368Y264130D02*
X261406D01*
X262201Y263335D01*
X264523D01*
G02X265844Y262547I-44J-1575D01*
G03X267789Y261384I2015J1162D01*
G01X267929D01*
G03X269874Y262547I-70J2325D01*
G02X272604I1365J-787D01*
G03X274549Y261384I2015J1162D01*
G01X274689D01*
G03X276634Y262547I-70J2325D01*
G02X277955Y263335I1365J-787D01*
G01X278084D01*
G03X280014Y264497I-85J2325D01*
G02X281320Y265284I1365J-788D01*
G01X281449D01*
G03X283394Y266447I-70J2325D01*
G02X284715Y267235I1365J-787D01*
G01X284844D01*
G03X286774Y268397I-85J2325D01*
G02X288080Y269184I1365J-788D01*
G01X288209D01*
G03X290154Y270347I-70J2325D01*
G02X292884I1365J-787D01*
G03X294829Y269184I2015J1162D01*
G01X294958D01*
G02X296264Y268397I-59J-1575D01*
G03X298194Y267235I2015J1163D01*
G01X298323D01*
G02X299852Y265567I-44J-1575D01*
G01X299936Y264073D01*
X300140Y263189D01*
X300294Y262922D01*
G03X301615Y262134I1365J787D01*
G01X301805D01*
X305039Y261760D01*
G01X258506Y248485D02*
X264549D01*
G02X266494Y247322I-70J-2325D01*
G03X269224I1365J787D01*
G02X271169Y248485I2015J-1162D01*
G01X271309D01*
G02X273254Y247322I-70J-2325D01*
G03X275984I1365J787D01*
G02X277929Y248485I2015J-1162D01*
G01X278058D01*
G03X279364Y249272I-59J1575D01*
G02X281294Y250434I2015J-1163D01*
G01X281423D01*
G03X282744Y251222I-44J1575D01*
G02X284689Y252385I2015J-1162D01*
G01X284818D01*
G03X286124Y253172I-59J1575D01*
G02X288054Y254334I2015J-1163D01*
G01X288183D01*
G03X289504Y255122I-44J1575D01*
G02X291449Y256285I2015J-1162D01*
G01X291661D01*
X294899Y255909D01*
G01X257772Y245980D02*
X259527Y247735D01*
X264523D01*
G02X265844Y246947I-44J-1575D01*
G03X267789Y245784I2015J1162D01*
G01X267929D01*
G03X269874Y246947I-70J2325D01*
G02X272604I1365J-787D01*
G03X274549Y245784I2015J1162D01*
G01X274689D01*
G03X276634Y246947I-70J2325D01*
G02X277955Y247735I1365J-787D01*
G01X278084D01*
G03X280014Y248897I-85J2325D01*
G02X281320Y249684I1365J-788D01*
G01X281449D01*
G03X283394Y250847I-70J2325D01*
G02X284715Y251635I1365J-787D01*
G01X284844D01*
G03X286774Y252797I-85J2325D01*
G02X288080Y253584I1365J-788D01*
G01X288209D01*
G03X290154Y254747I-70J2325D01*
G02X292884I1365J-787D01*
G03X294829Y253584I2015J1162D01*
G01X294958D01*
G02X296264Y252797I-59J-1575D01*
G03X298194Y251635I2015J1163D01*
G01X298425D01*
X301659Y252009D01*
G01X257128Y231542D02*
X257949Y230721D01*
X266310D01*
X270423Y234834D01*
X274663D01*
G03X275984Y235622I-44J1575D01*
G02X277929Y236785I2015J-1162D01*
G01X278058D01*
G03X279364Y237572I-59J1575D01*
G02X281294Y238734I2015J-1163D01*
G01X281423D01*
G03X282744Y239522I-44J1575D01*
G02X284689Y240685I2015J-1162D01*
G01X284818D01*
G03X286124Y241472I-59J1575D01*
G02X288054Y242634I2015J-1163D01*
G01X288183D01*
G03X289504Y243422I-44J1575D01*
G02X291449Y244585I2015J-1162D01*
G01X292168D01*
X293959Y245474D01*
G02X294840Y245784I940J-1265D01*
G01X294958D01*
G02X296264Y244997I-59J-1575D01*
G01X296330Y244881D01*
X298279Y242260D01*
G01X257128Y229042D02*
X258057Y229971D01*
X266621D01*
X270734Y234084D01*
X274689D01*
G03X276634Y235247I-70J2325D01*
G02X277955Y236035I1365J-787D01*
G01X278084D01*
G03X280014Y237197I-85J2325D01*
G02X281320Y237984I1365J-788D01*
G01X281449D01*
G03X283394Y239147I-70J2325D01*
G02X284715Y239935I1365J-787D01*
G01X284844D01*
G03X286774Y241097I-85J2325D01*
G02X288080Y241884I1365J-788D01*
G01X288209D01*
G03X290154Y243047I-70J2325D01*
G02X291475Y243835I1365J-787D01*
G01X292268D01*
X293809Y243071D01*
G03X294855Y242634I1090J1138D01*
G01X294984D01*
G02X296914Y241472I-85J-2325D01*
G03X298220Y240685I1365J788D01*
G01X298618D01*
X300789Y241624D01*
G02X301600Y241884I869J-1315D01*
G01X301718D01*
G02X303024Y241097I-59J-1575D01*
G01X303090Y240981D01*
X305039Y238360D01*
G01X261014Y251480D02*
X261101D01*
X261256Y251635D01*
X264523D01*
G02X265844Y250847I-44J-1575D01*
G03X267855Y249685I2011J1160D01*
G01X267862D01*
G03X269874Y250847I1J2322D01*
G02X271236Y251634I1362J-785D01*
G01X271242D01*
G02X272604Y250847I0J-1572D01*
G03X274617Y249685I2011J1160D01*
G01X274623D01*
G03X276634Y250847I0J2322D01*
G02X277955Y251635I1365J-787D01*
G01X278084D01*
G03X280014Y252797I-85J2325D01*
G02X281320Y253584I1365J-788D01*
G01X281449D01*
G03X283394Y254747I-70J2325D01*
G02X284715Y255535I1365J-787D01*
G01X284844D01*
G03X286774Y256697I-85J2325D01*
G02X288080Y257484I1365J-788D01*
G01X288193D01*
G03X290154Y258647I-54J2325D01*
G02X291518Y259435I1364J-786D01*
G01X291520D01*
G02X292884Y258647I0J-1574D01*
G03X294845Y257484I2015J1162D01*
G01X294958D01*
G02X296264Y256697I-59J-1575D01*
G03X298194Y255535I2015J1163D01*
G01X298323D01*
G02X299644Y254747I-44J-1575D01*
G03X301589Y253584I2015J1162D01*
G01X301729D01*
G03X303533Y254530I-69J2325D01*
G01X303885Y254625D01*
X305039Y253960D01*
G01X258792Y255380D02*
X258947Y255535D01*
X264523D01*
G02X265844Y254747I-44J-1575D01*
G03X267857Y253585I2011J1160D01*
G01X267862D01*
G03X269874Y254747I1J2322D01*
G02X271236Y255534I1362J-785D01*
G01X271242D01*
G02X272604Y254747I0J-1572D01*
G03X274617Y253585I2011J1160D01*
G01X274622D01*
G03X276634Y254747I1J2322D01*
G02X277955Y255535I1365J-787D01*
G01X278071D01*
G03X280014Y256697I-72J2325D01*
G02X281310Y257484I1365J-788D01*
G01X281433D01*
G03X283394Y258647I-54J2325D01*
G02X284702Y259435I1365J-787D01*
G01X284831D01*
G03X286774Y260597I-72J2325D01*
G02X288070Y261384I1365J-788D01*
G01X288193D01*
G03X290154Y262547I-54J2325D01*
G02X291518Y263335I1364J-786D01*
G01X291520D01*
G02X292883Y262547I0J-1574D01*
G03X293240Y262077I2016J1161D01*
G03X293351Y261973I1645J1645D01*
G01X293384Y261932D01*
X294899Y259809D01*
G01X261014Y252540D02*
X261101D01*
X261256Y252385D01*
X264533D01*
G02X266494Y251222I-54J-2325D01*
G03X267856Y250435I1362J785D01*
G01X267862D01*
G03X269224Y251222I0J1572D01*
G02X271235Y252384I2011J-1160D01*
G01X271243D01*
G02X273254Y251222I0J-2322D01*
G03X274616Y250435I1362J785D01*
G01X274622D01*
G03X275984Y251222I0J1572D01*
G02X277945Y252385I2015J-1162D01*
G01X278058D01*
G03X279364Y253172I-59J1575D01*
G02X281294Y254334I2015J-1163D01*
G01X281423D01*
G03X282744Y255122I-44J1575D01*
G02X284689Y256285I2015J-1162D01*
G01X284818D01*
G03X286124Y257072I-59J1575D01*
G02X288054Y258234I2015J-1163D01*
G01X288183D01*
G03X289504Y259022I-44J1575D01*
G02X291517Y260185I2013J-1161D01*
G01X291521D01*
G02X293534Y259022I0J-2324D01*
G03X294855Y258234I1365J787D01*
G01X294984D01*
G02X296914Y257072I-85J-2325D01*
G03X298220Y256285I1365J788D01*
G01X298349D01*
G02X300294Y255122I-70J-2325D01*
G03X301615Y254334I1365J787D01*
G01X301703D01*
G03X302896Y254934I-45J1575D01*
G01X302813Y255244D01*
X302481Y255435D01*
X301659Y255909D01*
G01X258792Y256440D02*
X258947Y256285D01*
X264533D01*
G02X266494Y255122I-54J-2325D01*
G03X267856Y254335I1362J785D01*
G01X267862D01*
G03X269224Y255122I0J1572D01*
G02X271235Y256284I2011J-1160D01*
G01X271243D01*
G02X273254Y255122I0J-2322D01*
G03X274616Y254335I1362J785D01*
G01X274622D01*
G03X275984Y255122I0J1572D01*
G02X277945Y256285I2015J-1162D01*
G01X278058D01*
G03X279364Y257072I-59J1575D01*
G02X281294Y258234I2015J-1163D01*
G01X281423D01*
G03X282744Y259022I-44J1575D01*
G02X284689Y260185I2015J-1162D01*
G01X284818D01*
G03X286124Y260972I-59J1575D01*
G02X288054Y262134I2015J-1163D01*
G01X288183D01*
G03X289504Y262922I-44J1575D01*
G02X291517Y264085I2013J-1161D01*
G01X291521D01*
G02X293534Y262922I0J-2324D01*
G03X293775Y262604I1366J785D01*
G03X293892Y262497I1121J1108D01*
G01X294484Y261764D01*
G03X294958Y261384I764J467D01*
G02X296264Y260597I-59J-1575D01*
G01X296330Y260481D01*
X298279Y257860D01*
G01X305039Y339760D02*
X303742Y336764D01*
X303674Y336647D01*
G02X301729Y335484I-2015J1162D01*
G01X301600D01*
G03X300294Y334697I59J-1575D01*
G02X298364Y333535I-2015J1163D01*
G01X298235D01*
G03X296914Y332747I44J-1575D01*
G02X294969Y331584I-2015J1162D01*
G01X294840D01*
G03X293534Y330797I59J-1575D01*
G02X291604Y329635I-2015J1163D01*
G01X291434D01*
G02X289504Y330797I85J2325D01*
G03X288198Y331584I-1365J-788D01*
G01X288069D01*
G02X286124Y332747I70J2325D01*
G03X284803Y333535I-1365J-787D01*
G01X284674D01*
G02X282744Y334697I85J2325D01*
G03X281438Y335484I-1365J-788D01*
G01X281309D01*
G02X279364Y336647I70J2325D01*
G03X278043Y337435I-1365J-787D01*
G01X277914D01*
G02X275984Y338597I85J2325D01*
G03X274678Y339384I-1365J-788D01*
G01X274549D01*
G02X272604Y340547I70J2325D01*
G03X271283Y341335I-1365J-787D01*
G01X271154D01*
G02X269224Y342497I85J2325D01*
G03X267918Y343284I-1365J-788D01*
G01X267789D01*
G02X265844Y344447I70J2325D01*
G03X264523Y345235I-1365J-787D01*
G01X262692D01*
X260798Y343341D01*
X253801D01*
X252888Y342428D01*
G01X305039Y335860D02*
X303742Y332864D01*
X303674Y332747D01*
G02X301729Y331584I-2015J1162D01*
G01X301600D01*
G03X300294Y330797I59J-1575D01*
G02X298364Y329635I-2015J1163D01*
G01X298235D01*
G03X296914Y328847I44J-1575D01*
G02X294969Y327684I-2015J1162D01*
G01X294828D01*
G03X293534Y326897I71J-1574D01*
G02X291604Y325735I-2015J1163D01*
G01X291434D01*
G02X289504Y326897I85J2325D01*
G03X288210Y327684I-1365J-787D01*
G01X288069D01*
G02X286124Y328847I70J2325D01*
G03X284803Y329635I-1365J-787D01*
G01X284674D01*
G02X282744Y330797I85J2325D01*
G03X281438Y331584I-1365J-788D01*
G01X281309D01*
G02X279364Y332747I70J2325D01*
G03X278043Y333535I-1365J-787D01*
G01X277914D01*
G02X275984Y334697I85J2325D01*
G03X274678Y335484I-1365J-788D01*
G01X274549D01*
G02X272604Y336647I70J2325D01*
G03X271283Y337435I-1365J-787D01*
G01X271154D01*
G02X269224Y338597I85J2325D01*
G03X267918Y339384I-1365J-788D01*
G01X267789D01*
G02X265844Y340547I70J2325D01*
G03X264523Y341335I-1365J-787D01*
G01X263442D01*
X262604Y340497D01*
Y339297D01*
X261346Y338039D01*
X256959D01*
X256398Y338600D01*
G01X256756Y340500D02*
X258467Y338789D01*
X261001D01*
X261854Y339642D01*
Y340808D01*
X263131Y342085D01*
X264549D01*
G02X266494Y340922I-70J-2325D01*
G03X267815Y340134I1365J787D01*
G01X267944D01*
G02X269874Y338972I-85J-2325D01*
G03X271180Y338185I1365J788D01*
G01X271309D01*
G02X273254Y337022I-70J-2325D01*
G03X274575Y336234I1365J787D01*
G01X274704D01*
G02X276634Y335072I-85J-2325D01*
G03X277940Y334285I1365J788D01*
G01X278069D01*
G02X280014Y333122I-70J-2325D01*
G03X281335Y332334I1365J787D01*
G01X281464D01*
G02X283394Y331172I-85J-2325D01*
G03X284700Y330385I1365J788D01*
G01X284829D01*
G02X286774Y329222I-70J-2325D01*
G03X288068Y328435I1365J787D01*
G01X288224D01*
G02X290154Y327273I-85J-2325D01*
G03X292884I1365J787D01*
G02X294814Y328435I2015J-1163D01*
G01X294970D01*
G03X296264Y329222I-71J1574D01*
G02X298209Y330385I2015J-1162D01*
G01X298338D01*
G03X299644Y331172I-59J1575D01*
G01X299710Y331288D01*
X301659Y333909D01*
G01X264900Y317200D02*
X266200Y315900D01*
X268300D01*
X270241Y317841D01*
X270981D01*
X271570Y317798D01*
G02X272455Y317045I-631J-1638D01*
G03X273683Y315984I2164J1264D01*
G01X274678D01*
G02X275984Y315197I-59J-1575D01*
G03X277914Y314035I2015J1163D01*
G01X278043D01*
G02X279364Y313247I-44J-1575D01*
G03X281309Y312084I2015J1162D01*
G01X281438D01*
G02X282744Y311297I-59J-1575D01*
G03X284674Y310135I2015J1163D01*
G01X284803D01*
G02X286124Y309347I-44J-1575D01*
G03X288069Y308184I2015J1162D01*
G01X288198D01*
G02X289504Y307397I-59J-1575D01*
G03X291434Y306235I2015J1163D01*
G01X291604D01*
G03X293534Y307397I-85J2325D01*
G02X294840Y308184I1365J-788D01*
G01X294958D01*
G02X296264Y307397I-59J-1575D01*
G03X298194Y306235I2015J1163D01*
G01X298364D01*
G03X300294Y307397I-85J2325D01*
G02X301600Y308184I1365J-788D01*
G01X301729D01*
G03X303674Y309347I-70J2325D01*
G02X304995Y310135I1365J-787D01*
G01X305137D01*
G03X307054Y311296I-98J2325D01*
G01X307067Y311319D01*
G02X308418Y312084I1351J-810D01*
G01X308488D01*
G03X310433Y313247I-70J2325D01*
G02X311754Y314035I1365J-787D01*
G01X311883D01*
G03X313813Y315197I-85J2325D01*
G02X315119Y315984I1365J-788D01*
G01X315248D01*
G03X317193Y317147I-70J2325D01*
G02X318514Y317935I1365J-787D01*
G01X318643D01*
G03X320573Y319097I-85J2325D01*
G02X321879Y319884I1365J-788D01*
G01X322008D01*
G03X323953Y321047I-70J2325D01*
G02X325274Y321835I1365J-787D01*
G01X325403D01*
G03X327333Y322997I-85J2325D01*
G02X328639Y323784I1365J-788D01*
G01X328749D01*
G03X330713Y324947I-51J2326D01*
G02X332034Y325735I1365J-787D01*
G01X332163D01*
G03X334093Y326897I-85J2325D01*
G02X335387Y327684I1365J-787D01*
G01X335528D01*
G03X337473Y328847I-70J2325D01*
G02X338794Y329635I1365J-787D01*
G01X338923D01*
G03X340853Y330797I-85J2325D01*
G02X342159Y331584I1365J-788D01*
G01X342288D01*
G03X344233Y332747I-70J2325D01*
G02X345554Y333535I1365J-787D01*
G01X345683D01*
G03X347613Y334697I-85J2325D01*
G02X348919Y335484I1365J-788D01*
G01X349048D01*
G03X350993Y336647I-70J2325D01*
G01X351006Y336670D01*
G02X352357Y337435I1351J-810D01*
G01X352442D01*
G03X354372Y338597I-85J2325D01*
G02X355678Y339384I1365J-788D01*
G01X355807D01*
G03X357752Y340547I-70J2325D01*
G02X359073Y341335I1365J-787D01*
G01X359202D01*
G03X359187Y345985I-85J2325D01*
G01X359047D01*
G03X357243Y345039I69J-2325D01*
G01X356891Y344944D01*
X355737Y345609D01*
G01X267061Y331584D02*
X267918D01*
G02X269224Y330797I-59J-1575D01*
G03X271154Y329635I2015J1163D01*
G01X271283D01*
G02X272604Y328847I-44J-1575D01*
G03X274549Y327684I2015J1162D01*
G01X274690D01*
G02X275984Y326897I-71J-1574D01*
G03X277914Y325735I2015J1163D01*
G01X278043D01*
G02X279364Y324947I-44J-1575D01*
G03X281328Y323784I2015J1163D01*
G01X281438D01*
G02X282744Y322997I-59J-1575D01*
G03X284674Y321835I2015J1163D01*
G01X284803D01*
G02X286124Y321047I-44J-1575D01*
G03X288069Y319884I2015J1162D01*
G01X288198D01*
G02X289504Y319097I-59J-1575D01*
G03X291434Y317935I2015J1163D01*
G01X291604D01*
G03X293534Y319097I-85J2325D01*
G02X294840Y319884I1365J-788D01*
G01X294969D01*
G03X296914Y321047I-70J2325D01*
G02X298235Y321835I1365J-787D01*
G01X298364D01*
G03X300294Y322997I-85J2325D01*
G02X301600Y323784I1365J-788D01*
G01X301710D01*
G03X303674Y324947I-51J2326D01*
G02X304995Y325735I1365J-787D01*
G01X305124D01*
G03X307054Y326897I-85J2325D01*
G02X308370Y327684I1364J-787D01*
G01X308488D01*
G03X310433Y331172I-70J2325D01*
G02X310414Y332713I1365J787D01*
G01X310800Y333383D01*
Y336700D01*
G01X263568Y337520D02*
X265505D01*
G02X266351Y337011I0J-957D01*
G03X267204Y336234I1508J798D01*
G01X267944D01*
G02X269874Y335072I-85J-2325D01*
G03X271180Y334285I1365J788D01*
G01X271309D01*
G02X273254Y333122I-70J-2325D01*
G03X274575Y332334I1365J787D01*
G01X274704D01*
G02X276634Y331172I-85J-2325D01*
G03X277940Y330385I1365J788D01*
G01X278069D01*
G02X280014Y329222I-70J-2325D01*
G03X281308Y328435I1365J787D01*
G01X281464D01*
G02X283394Y327273I-85J-2325D01*
G03X284715Y326485I1365J787D01*
G01X284844D01*
G02X286774Y325323I-85J-2325D01*
G03X288095Y324535I1365J787D01*
G01X288190D01*
G02X290154Y323372I-51J-2326D01*
G03X291460Y322585I1365J788D01*
G01X291578D01*
G03X292884Y323372I-59J1575D01*
G02X294848Y324535I2015J-1163D01*
G01X294943D01*
G03X296264Y325323I-44J1575D01*
G02X298194Y326485I2015J-1163D01*
G01X298323D01*
G03X299644Y327273I-44J1575D01*
G02X301574Y328435I2015J-1163D01*
G01X301730D01*
G03X303024Y329222I-71J1574D01*
G02X304969Y330385I2015J-1162D01*
G01X305039D01*
G03X306403Y332747I0J1575D01*
G01X306368Y332807D01*
G02X306403Y335073I2050J1102D01*
G03Y336647I-1364J787D01*
G01X306368Y336707D01*
G02X306403Y338973I2050J1102D01*
G03Y340547I-1364J787D01*
G01X306368Y340607D01*
G02X306403Y342873I2050J1102D01*
G03Y344447I-1364J787D01*
G01X306368Y344507D01*
G02X306403Y346773I2050J1102D01*
G03Y348347I-1364J787D01*
G01X306368Y348407D01*
G02X306403Y350673I2050J1102D01*
G02X308320Y351834I2015J-1164D01*
G01X308462D01*
G03X309783Y352622I-44J1575D01*
G02X311541Y353772I2015J-1162D01*
G01X311798Y354029D01*
Y355360D01*
G01X263936Y333535D02*
X265646D01*
G02X266351Y333111I0J-797D01*
G03X267204Y332334I1508J798D01*
G01X267944D01*
G02X269874Y331172I-85J-2325D01*
G03X271180Y330385I1365J788D01*
G01X271309D01*
G02X273254Y329222I-70J-2325D01*
G03X274548Y328435I1365J787D01*
G01X274704D01*
G02X276634Y327273I-85J-2325D01*
G03X277955Y326485I1365J787D01*
G01X278084D01*
G02X280014Y325323I-85J-2325D01*
G03X281335Y324535I1365J787D01*
G01X281430D01*
G02X283394Y323372I-51J-2326D01*
G03X284700Y322585I1365J788D01*
G01X284829D01*
G02X286774Y321422I-70J-2325D01*
G03X288095Y320634I1365J787D01*
G01X288224D01*
G02X290154Y319472I-85J-2325D01*
G03X291460Y318685I1365J788D01*
G01X291578D01*
G03X292884Y319472I-59J1575D01*
G02X294814Y320634I2015J-1163D01*
G01X294943D01*
G03X296264Y321422I-44J1575D01*
G02X298209Y322585I2015J-1162D01*
G01X298338D01*
G03X299644Y323372I-59J1575D01*
G02X301608Y324535I2015J-1163D01*
G01X301703D01*
G03X303024Y325323I-44J1575D01*
G02X304954Y326485I2015J-1163D01*
G01X305039D01*
G03X306390Y327250I0J1575D01*
G01X306403Y327273D01*
G02X308333Y328435I2015J-1163D01*
G01X308489D01*
G03X309783Y330797I-71J1574D01*
G02X309758Y333080I2015J1164D01*
G01X310000Y333499D01*
Y337600D01*
G01X311798Y351460D02*
Y352791D01*
X311570Y353019D01*
G03X310433Y352247I228J-1559D01*
G02X308488Y351084I-2015J1162D01*
G01X308418D01*
G03X307067Y350319I0J-1575D01*
G01X307054Y350296D01*
G03Y348722I1364J-787D01*
G01X307089Y348662D01*
G02X307054Y346396I-2050J-1102D01*
G03Y344822I1364J-787D01*
G01X307089Y344762D01*
G02X307054Y342496I-2050J-1102D01*
G03Y340922I1364J-787D01*
G01X307089Y340862D01*
G02X307054Y338596I-2050J-1102D01*
G03Y337022I1364J-787D01*
G01X307089Y336962D01*
G02X307054Y334696I-2050J-1102D01*
G03Y333122I1364J-787D01*
G01X307089Y333062D01*
G02X305137Y329635I-2050J-1102D01*
G01X304995D01*
G03X303674Y328847I44J-1575D01*
G02X301729Y327684I-2015J1162D01*
G01X301588D01*
G03X300294Y326897I71J-1574D01*
G02X298364Y325735I-2015J1163D01*
G01X298235D01*
G03X296914Y324947I44J-1575D01*
G02X294950Y323784I-2015J1163D01*
G01X294840D01*
G03X293534Y322997I59J-1575D01*
G02X291604Y321835I-2015J1163D01*
G01X291434D01*
G02X289504Y322997I85J2325D01*
G03X288198Y323784I-1365J-788D01*
G01X288088D01*
G02X286124Y324947I51J2326D01*
G03X284803Y325735I-1365J-787D01*
G01X284674D01*
G02X282744Y326897I85J2325D01*
G03X281450Y327684I-1365J-787D01*
G01X281309D01*
G02X279364Y328847I70J2325D01*
G03X278043Y329635I-1365J-787D01*
G01X277914D01*
G02X275984Y330797I85J2325D01*
G03X274678Y331584I-1365J-788D01*
G01X274549D01*
G02X272604Y332747I70J2325D01*
G03X271283Y333535I-1365J-787D01*
G01X271154D01*
G02X269224Y334697I85J2325D01*
G03X267918Y335484I-1365J-788D01*
G01X266773D01*
X265576Y334287D01*
X264051D01*
X263808Y334324D01*
G01X362497Y345609D02*
X363651Y346275D01*
X363734Y346585D01*
G03X362556Y347184I-1238J-976D01*
G01X362427D01*
G02X360482Y348347I70J2325D01*
G03X357752I-1365J-787D01*
G02X355807Y347184I-2015J1162D01*
G01X355678D01*
G03X354372Y346397I59J-1575D01*
G02X352442Y345235I-2015J1163D01*
G01X352357D01*
G03X350993Y342873I0J-1575D01*
G02X349048Y339384I-2015J-1163D01*
G01X348919D01*
G03X347613Y338597I59J-1575D01*
G02X345683Y337435I-2015J1163D01*
G01X345554D01*
G03X344233Y336647I44J-1575D01*
G02X342288Y335484I-2015J1162D01*
G01X342159D01*
G03X340853Y334697I59J-1575D01*
G02X338923Y333535I-2015J1163D01*
G01X338794D01*
G03X337473Y332747I44J-1575D01*
G02X335528Y331584I-2015J1162D01*
G01X335399D01*
G03X334093Y330797I59J-1575D01*
G02X332163Y329635I-2015J1163D01*
G01X332034D01*
G03X330713Y328847I44J-1575D01*
G02X328768Y327684I-2015J1162D01*
G01X328627D01*
G03X327333Y326897I71J-1574D01*
G02X325403Y325735I-2015J1163D01*
G01X325274D01*
G03X323953Y324947I44J-1575D01*
G02X321989Y323784I-2015J1163D01*
G01X321879D01*
G03X320573Y322997I59J-1575D01*
G02X318643Y321835I-2015J1163D01*
G01X318514D01*
G03X317193Y321047I44J-1575D01*
G02X315248Y319884I-2015J1162D01*
G01X315119D01*
G03X313813Y319097I59J-1575D01*
G02X311883Y317935I-2015J1163D01*
G01X311754D01*
G03X310433Y317147I44J-1575D01*
G02X308488Y315984I-2015J1162D01*
G01X308418D01*
G03X307067Y315219I0J-1575D01*
G01X307054Y315196D01*
G02X305137Y314035I-2015J1164D01*
G01X304995D01*
G03X303674Y313247I44J-1575D01*
G02X301729Y312084I-2015J1162D01*
G01X301600D01*
G03X300294Y311297I59J-1575D01*
G02X298364Y310135I-2015J1163D01*
G01X298194D01*
G02X296264Y311297I85J2325D01*
G03X293534I-1365J-788D01*
G02X291604Y310135I-2015J1163D01*
G01X291434D01*
G02X289504Y311297I85J2325D01*
G03X288198Y312084I-1365J-788D01*
G01X288069D01*
G02X286124Y313247I70J2325D01*
G03X284803Y314035I-1365J-787D01*
G01X284674D01*
G02X282744Y315197I85J2325D01*
G03X281438Y315984I-1365J-788D01*
G01X281309D01*
G02X279364Y317147I70J2325D01*
G03X278043Y317935I-1365J-787D01*
G01X277914D01*
G02X275984Y319097I85J2325D01*
G03X274678Y319884I-1365J-788D01*
G01X274549D01*
G02X272604Y321047I70J2325D01*
G03X271283Y321835I-1365J-787D01*
G01X270265D01*
X268400Y323700D01*
X265700D01*
G01X365877Y347560D02*
X364723Y346894D01*
X364371Y346989D01*
G03X362582Y347934I-1873J-1380D01*
G01X362453D01*
G02X361132Y348722I44J1575D01*
G03X359187Y349885I-2015J-1162D01*
G01X359047D01*
G03X357102Y348722I70J-2325D01*
G02X355781Y347934I-1365J787D01*
G01X355652D01*
G03X353722Y346772I85J-2325D01*
G02X352416Y345985I-1365J788D01*
G01X352287D01*
G03X350342Y342496I69J-2325D01*
G02X348978Y340134I-1364J-787D01*
G01X348893D01*
G03X346963Y338972I85J-2325D01*
G02X345657Y338185I-1365J788D01*
G01X345528D01*
G03X343583Y337022I70J-2325D01*
G02X342262Y336234I-1365J787D01*
G01X342133D01*
G03X340203Y335072I85J-2325D01*
G02X338897Y334285I-1365J788D01*
G01X338768D01*
G03X336823Y333122I70J-2325D01*
G02X335502Y332334I-1365J787D01*
G01X335373D01*
G03X333443Y331172I85J-2325D01*
G02X332137Y330385I-1365J788D01*
G01X332008D01*
G03X330063Y329222I70J-2325D01*
G02X328769Y328435I-1365J787D01*
G01X328613D01*
G03X326683Y327273I85J-2325D01*
G02X325362Y326485I-1365J787D01*
G01X325233D01*
G03X323303Y325323I85J-2325D01*
G02X321982Y324535I-1365J787D01*
G01X321887D01*
G03X319923Y323372I51J-2326D01*
G02X318617Y322585I-1365J788D01*
G01X318488D01*
G03X316543Y321422I70J-2325D01*
G02X315222Y320634I-1365J787D01*
G01X315093D01*
G03X313163Y319472I85J-2325D01*
G02X311857Y318685I-1365J788D01*
G01X311728D01*
G03X309783Y317522I70J-2325D01*
G02X308462Y316734I-1365J787D01*
G01X308320D01*
G03X306403Y315573I98J-2325D01*
G01X306390Y315550D01*
G02X305039Y314785I-1351J810D01*
G01X304969D01*
G03X303024Y313622I70J-2325D01*
G02X301703Y312834I-1365J787D01*
G01X301574D01*
G03X299644Y311672I85J-2325D01*
G02X298338Y310885I-1365J788D01*
G01X298220D01*
G02X296914Y311672I59J1575D01*
G03X292884I-2015J-1163D01*
G02X291578Y310885I-1365J788D01*
G01X291460D01*
G02X290154Y311672I59J1575D01*
G03X288224Y312834I-2015J-1163D01*
G01X288095D01*
G02X286774Y313622I44J1575D01*
G03X284829Y314785I-2015J-1162D01*
G01X284700D01*
G02X283394Y315572I59J1575D01*
G03X281464Y316734I-2015J-1163D01*
G01X281335D01*
G02X280014Y317522I44J1575D01*
G03X278069Y318685I-2015J-1162D01*
G01X277940D01*
G02X276634Y319472I59J1575D01*
G03X274704Y320634I-2015J-1163D01*
G01X274575D01*
G02X273254Y321422I44J1575D01*
G03X271309Y322585I-2015J-1162D01*
G01X270576D01*
X268712Y324449D01*
X266014D01*
X266012Y324451D01*
X265700D01*
X263751Y326400D01*
G01X265438Y317738D02*
Y317736D01*
X266515Y316659D01*
X267985D01*
X269926Y318600D01*
X271037D01*
X271045Y318591D01*
X271723Y318540D01*
G02X273103Y317424I-784J-2380D01*
G03X273844Y316734I1516J885D01*
G01X274704D01*
G02X276634Y315572I-85J-2325D01*
G03X277940Y314785I1365J788D01*
G01X278069D01*
G02X280014Y313622I-70J-2325D01*
G03X281335Y312834I1365J787D01*
G01X281464D01*
G02X283394Y311672I-85J-2325D01*
G03X284700Y310885I1365J788D01*
G01X284829D01*
G02X286774Y309722I-70J-2325D01*
G03X288095Y308934I1365J787D01*
G01X288224D01*
G02X290154Y307772I-85J-2325D01*
G03X291460Y306985I1365J788D01*
G01X291578D01*
G03X292884Y307772I-59J1575D01*
G02X294814Y308934I2015J-1163D01*
G01X294984D01*
G02X296914Y307772I-85J-2325D01*
G03X298220Y306985I1365J788D01*
G01X298338D01*
G03X299644Y307772I-59J1575D01*
G02X301574Y308934I2015J-1163D01*
G01X301703D01*
G03X303024Y309722I-44J1575D01*
G02X304969Y310885I2015J-1162D01*
G01X305039D01*
G03X306390Y311650I0J1575D01*
G01X306403Y311673D01*
G02X308320Y312834I2015J-1164D01*
G01X308462D01*
G03X309783Y313622I-44J1575D01*
G02X311728Y314785I2015J-1162D01*
G01X311857D01*
G03X313163Y315572I-59J1575D01*
G02X315093Y316734I2015J-1163D01*
G01X315222D01*
G03X316543Y317522I-44J1575D01*
G02X318488Y318685I2015J-1162D01*
G01X318617D01*
G03X319923Y319472I-59J1575D01*
G02X321853Y320634I2015J-1163D01*
G01X321982D01*
G03X323303Y321422I-44J1575D01*
G02X325248Y322585I2015J-1162D01*
G01X325377D01*
G03X326683Y323372I-59J1575D01*
G02X328647Y324535I2015J-1163D01*
G01X328742D01*
G03X330063Y325323I-44J1575D01*
G02X331993Y326485I2015J-1163D01*
G01X332122D01*
G03X333443Y327273I-44J1575D01*
G02X335373Y328435I2015J-1163D01*
G01X335529D01*
G03X336823Y329222I-71J1574D01*
G02X338768Y330385I2015J-1162D01*
G01X338897D01*
G03X340203Y331172I-59J1575D01*
G02X342133Y332334I2015J-1163D01*
G01X342262D01*
G03X343583Y333122I-44J1575D01*
G02X345528Y334285I2015J-1162D01*
G01X345657D01*
G03X346963Y335072I-59J1575D01*
G02X348893Y336234I2015J-1163D01*
G01X348978D01*
G03X350329Y336999I0J1575D01*
G01X350342Y337022D01*
G02X352287Y338185I2015J-1162D01*
G01X352416D01*
G03X353722Y338972I-59J1575D01*
G02X355652Y340134I2015J-1163D01*
G01X355781D01*
G03X357102Y340922I-44J1575D01*
G02X359047Y342085I2015J-1162D01*
G01X359176D01*
G03X357880Y344635I-58J1575D01*
G01X357963Y344325D01*
X359117Y343660D01*
G01X305039Y355360D02*
X303742Y352364D01*
X303674Y352247D01*
G02X301729Y351084I-2015J1162D01*
G01X301600D01*
G03X300294Y350297I59J-1575D01*
G02X298364Y349135I-2015J1163D01*
G01X298235D01*
G03X296914Y348347I44J-1575D01*
G02X294969Y347184I-2015J1162D01*
G01X294829D01*
G02X292884Y348347I70J2325D01*
G03X291563Y349135I-1365J-787D01*
G01X291434D01*
G02X289504Y350297I85J2325D01*
G03X288198Y351084I-1365J-788D01*
G01X288069D01*
G02X286124Y352247I70J2325D01*
G03X284803Y353035I-1365J-787D01*
G01X284674D01*
G02X282744Y354197I85J2325D01*
G03X281438Y354984I-1365J-788D01*
G01X281309D01*
G02X279364Y356147I70J2325D01*
G03X278043Y356935I-1365J-787D01*
G01X277914D01*
G02X275984Y358097I85J2325D01*
G03X274678Y358884I-1365J-788D01*
G01X273583D01*
X272756Y359711D01*
X271678D01*
X268248Y363141D01*
X263848D01*
X259148Y367841D01*
X254862D01*
X254448Y367427D01*
G01X301659Y353409D02*
X299710Y350788D01*
X299644Y350672D01*
G02X298338Y349885I-1365J788D01*
G01X298209D01*
G03X296264Y348722I70J-2325D01*
G02X293534I-1365J787D01*
G03X291589Y349885I-2015J-1162D01*
G01X291460D01*
G02X290154Y350672I59J1575D01*
G03X288224Y351834I-2015J-1163D01*
G01X288095D01*
G02X286774Y352622I44J1575D01*
G03X284829Y353785I-2015J-1162D01*
G01X284700D01*
G02X283394Y354572I59J1575D01*
G03X281464Y355734I-2015J-1163D01*
G01X281335D01*
G02X280014Y356522I44J1575D01*
G03X278069Y357685I-2015J-1162D01*
G01X277940D01*
G02X276634Y358472I59J1575D01*
G03X274704Y359634I-2015J-1163D01*
G01X273896D01*
X273069Y360461D01*
X271989D01*
X268561Y363889D01*
X264158D01*
X259458Y368589D01*
X254900D01*
X253558Y369931D01*
G01X298279Y335860D02*
X296330Y333238D01*
X296264Y333122D01*
G02X294943Y332334I-1365J787D01*
G01X294814D01*
G03X292884Y331172I85J-2325D01*
G02X291578Y330385I-1365J788D01*
G01X291460D01*
G02X290154Y331172I59J1575D01*
G03X288224Y332334I-2015J-1163D01*
G01X288095D01*
G02X286774Y333122I44J1575D01*
G03X284829Y334285I-2015J-1162D01*
G01X284700D01*
G02X283394Y335072I59J1575D01*
G03X281464Y336234I-2015J-1163D01*
G01X281335D01*
G02X280014Y337022I44J1575D01*
G03X278069Y338185I-2015J-1162D01*
G01X277940D01*
G02X276634Y338972I59J1575D01*
G03X274704Y340134I-2015J-1163D01*
G01X274575D01*
G02X273254Y340922I44J1575D01*
G03X271309Y342085I-2015J-1162D01*
G01X271180D01*
G02X269874Y342872I59J1575D01*
G03X267944Y344034I-2015J-1163D01*
G01X267815D01*
G02X266494Y344822I44J1575D01*
G03X264533Y345985I-2015J-1162D01*
G01X262384D01*
X260488Y344089D01*
X253828D01*
X252989Y344928D01*
G01X298279Y347560D02*
X296982Y344564D01*
X296914Y344447D01*
G02X294969Y343284I-2015J1162D01*
G01X294829D01*
G02X292884Y344447I70J2325D01*
G03X291563Y345235I-1365J-787D01*
G01X291434D01*
G02X289504Y346397I85J2325D01*
G03X288198Y347184I-1365J-788D01*
G01X288069D01*
G02X286124Y348347I70J2325D01*
G03X284803Y349135I-1365J-787D01*
G01X284674D01*
G02X282744Y350297I85J2325D01*
G03X281438Y351084I-1365J-788D01*
G01X281309D01*
G02X279364Y352247I70J2325D01*
G03X278043Y353035I-1365J-787D01*
G01X277914D01*
G02X275984Y354197I85J2325D01*
G03X274678Y354984I-1365J-788D01*
G01X274549D01*
G02X272604Y356147I70J2325D01*
G03X271412Y356926I-1365J-787D01*
G03X271063Y356940I-274J-2484D01*
G02X269224Y358097I178J2323D01*
G03X267918Y358884I-1365J-788D01*
G01X266531D01*
X265454Y359961D01*
X262470D01*
X260748Y361683D01*
X250448D01*
X249621Y360856D01*
G01X294899Y345609D02*
X291661Y345985D01*
X291460D01*
G02X290154Y346772I59J1575D01*
G03X288224Y347934I-2015J-1163D01*
G01X288095D01*
G02X286774Y348722I44J1575D01*
G03X284829Y349885I-2015J-1162D01*
G01X284700D01*
G02X283394Y350672I59J1575D01*
G03X281464Y351834I-2015J-1163D01*
G01X281335D01*
G02X280014Y352622I44J1575D01*
G03X278069Y353785I-2015J-1162D01*
G01X277940D01*
G02X276634Y354572I59J1575D01*
G03X274704Y355734I-2015J-1163D01*
G01X274575D01*
G02X273254Y356522I44J1575D01*
G03X271520Y357669I-2016J-1163D01*
G03X271019Y357699I-493J-4042D01*
G02X269874Y358472I215J1554D01*
G03X267944Y359634I-2015J-1163D01*
G01X266839D01*
X265764Y360709D01*
X262780D01*
X261058Y362431D01*
X250147D01*
X249205Y363373D01*
G01X249457Y355736D02*
X250362Y356641D01*
X262666D01*
X262960Y356935D01*
X264179D01*
G02X265687Y356158I0J-1852D01*
G03X267061Y354984I2172J1151D01*
G01X294899Y341709D02*
X292797Y342016D01*
X292202Y342085D01*
X291460D01*
G02X290154Y342872I59J1575D01*
G03X288224Y344034I-2015J-1163D01*
G01X288095D01*
G02X286774Y344822I44J1575D01*
G03X284829Y345985I-2015J-1162D01*
G01X284700D01*
G02X283394Y346772I59J1575D01*
G03X281464Y347934I-2015J-1163D01*
G01X281335D01*
G02X280014Y348722I44J1575D01*
G03X278069Y349885I-2015J-1162D01*
G01X277940D01*
G02X276634Y350672I59J1575D01*
G03X274704Y351834I-2015J-1163D01*
G01X274575D01*
G02X273254Y352622I44J1575D01*
G03X271309Y353785I-2015J-1162D01*
G01X271180D01*
G02X269874Y354572I59J1575D01*
G03X267944Y355734I-2015J-1163D01*
G01X267204D01*
G02X266472Y356316I655J1575D01*
G03X264179Y357685I-2293J-1236D01*
G01X262652D01*
X262356Y357389D01*
X250283D01*
X249436Y358236D01*
G01X305039Y359260D02*
X303742Y356264D01*
X303674Y356147D01*
G02X301729Y354984I-2015J1162D01*
G01X301600D01*
G03X300294Y354197I59J-1575D01*
G02X298364Y353035I-2015J1163D01*
G01X298235D01*
G03X296914Y352247I44J-1575D01*
G02X294969Y351084I-2015J1162D01*
G01X294829D01*
G02X292884Y352247I70J2325D01*
G03X291563Y353035I-1365J-787D01*
G01X291434D01*
G02X289504Y354197I85J2325D01*
G03X288198Y354984I-1365J-788D01*
G01X288069D01*
G02X286124Y356147I70J2325D01*
G03X284803Y356935I-1365J-787D01*
G01X284674D01*
G02X282744Y358097I85J2325D01*
G03X281438Y358884I-1365J-788D01*
G01X281309D01*
G02X279364Y360047I70J2325D01*
G03X278043Y360835I-1365J-787D01*
G01X277914D01*
G02X275984Y361997I85J2325D01*
G03X274678Y362784I-1365J-788D01*
G01X272544D01*
X272325Y363003D01*
Y363005D01*
X272326D01*
X269338Y365993D01*
X265338D01*
X257938Y373393D01*
X254040D01*
X253248Y372601D01*
G01X294899Y337809D02*
X291930Y337470D01*
G02X291604Y337435I-411J2290D01*
G01X291434D01*
G02X289504Y338597I85J2325D01*
G03X288198Y339384I-1365J-788D01*
G01X288069D01*
G02X286124Y340547I70J2325D01*
G03X284803Y341335I-1365J-787D01*
G01X284674D01*
G02X282744Y342497I85J2325D01*
G03X281438Y343284I-1365J-788D01*
G01X281309D01*
G02X279364Y344447I70J2325D01*
G03X278043Y345235I-1365J-787D01*
G01X277914D01*
G02X275984Y346397I85J2325D01*
G03X274678Y347184I-1365J-788D01*
G01X274549D01*
G02X272604Y348347I70J2325D01*
G03X271283Y349135I-1365J-787D01*
G01X271154D01*
G02X269224Y350297I85J2325D01*
G03X267918Y351084I-1365J-788D01*
G01X267789D01*
G02X265844Y352247I70J2325D01*
G03X264523Y353035I-1365J-787D01*
G01X262787D01*
X261583Y351831D01*
X249960D01*
X249805Y351676D01*
X249718D01*
G01X258105Y348839D02*
X258192D01*
X258347Y348684D01*
X261941D01*
X263142Y349885D01*
X264533D01*
G02X266494Y348722I-54J-2325D01*
G03X267815Y347934I1365J787D01*
G01X267944D01*
G02X269874Y346772I-85J-2325D01*
G03X271180Y345985I1365J788D01*
G01X271309D01*
G02X273254Y344822I-70J-2325D01*
G03X274575Y344034I1365J787D01*
G01X274704D01*
G02X276634Y342872I-85J-2325D01*
G03X277940Y342085I1365J788D01*
G01X278069D01*
G02X280014Y340922I-70J-2325D01*
G03X281335Y340134I1365J787D01*
G01X281464D01*
G02X283394Y338972I-85J-2325D01*
G03X284700Y338185I1365J788D01*
G01X284829D01*
G02X286774Y337022I-70J-2325D01*
G03X288095Y336234I1365J787D01*
G01X288224D01*
G02X290154Y335072I-85J-2325D01*
G03X291460Y334285I1365J788D01*
G01X291578D01*
G03X292884Y335072I-59J1575D01*
G02X294814Y336234I2015J-1163D01*
G01X294943D01*
G03X296264Y337022I-44J1575D01*
G02X298209Y338185I2015J-1162D01*
G01X298338D01*
G03X299644Y338972I-59J1575D01*
G02X301574Y340134I2015J-1163D01*
G01X301703D01*
G03X303123Y342291I-45J1575D01*
G01X302813Y342375D01*
X302481Y342183D01*
X301659Y341709D01*
G01X298279Y339760D02*
X296253Y339383D01*
X293995D01*
X292904Y338714D01*
G02X292168Y338324I-3459J5638D01*
G02X291797Y338209I-649J1436D01*
G02X291578Y338185I-281J1551D01*
G01X291460D01*
G02X290154Y338972I59J1575D01*
G03X288224Y340134I-2015J-1163D01*
G01X288095D01*
G02X286774Y340922I44J1575D01*
G03X284829Y342085I-2015J-1162D01*
G01X284700D01*
G02X283394Y342872I59J1575D01*
G03X281464Y344034I-2015J-1163D01*
G01X281335D01*
G02X280014Y344822I44J1575D01*
G03X278069Y345985I-2015J-1162D01*
G01X277940D01*
G02X276634Y346772I59J1575D01*
G03X274704Y347934I-2015J-1163D01*
G01X274575D01*
G02X273254Y348722I44J1575D01*
G03X271309Y349885I-2015J-1162D01*
G01X271180D01*
G02X269874Y350672I59J1575D01*
G03X267944Y351834I-2015J-1163D01*
G01X267815D01*
G02X266494Y352622I44J1575D01*
G03X264533Y353785I-2015J-1162D01*
G01X262476D01*
X261272Y352581D01*
X249960D01*
X249805Y352736D01*
X249718D01*
G01X258105Y347779D02*
X258192D01*
X258347Y347934D01*
X262252D01*
X263453Y349135D01*
X264523D01*
G02X265844Y348347I-44J-1575D01*
G03X267789Y347184I2015J1162D01*
G01X267918D01*
G02X269224Y346397I-59J-1575D01*
G03X271154Y345235I2015J1163D01*
G01X271283D01*
G02X272604Y344447I-44J-1575D01*
G03X274549Y343284I2015J1162D01*
G01X274678D01*
G02X275984Y342497I-59J-1575D01*
G03X277914Y341335I2015J1163D01*
G01X278043D01*
G02X279364Y340547I-44J-1575D01*
G03X281309Y339384I2015J1162D01*
G01X281438D01*
G02X282744Y338597I-59J-1575D01*
G03X284674Y337435I2015J1163D01*
G01X284803D01*
G02X286124Y336647I-44J-1575D01*
G03X288069Y335484I2015J1162D01*
G01X288198D01*
G02X289504Y334697I-59J-1575D01*
G03X291434Y333535I2015J1163D01*
G01X291604D01*
G03X293534Y334697I-85J2325D01*
G02X294840Y335484I1365J-788D01*
G01X294969D01*
G03X296914Y336647I-70J2325D01*
G02X298235Y337435I1365J-787D01*
G01X298364D01*
G03X300294Y338597I-85J2325D01*
G02X301600Y339384I1365J-788D01*
G01X301729D01*
G03X303791Y342642I-69J2325D01*
G01X303885Y342994D01*
X305039Y343660D01*
G01X262828Y212333D02*
X263650Y211511D01*
X264478D01*
X272201Y219234D01*
X274663D01*
G03X275984Y220022I-44J1575D01*
G02X277929Y221185I2015J-1162D01*
G01X278058D01*
G03X279364Y221972I-59J1575D01*
G02X281294Y223134I2015J-1163D01*
G01X281423D01*
G03X282744Y223922I-44J1575D01*
G02X284689Y225085I2015J-1162D01*
G01X284818D01*
G03X286124Y225872I-59J1575D01*
G02X288088Y227035I2015J-1163D01*
G01X288183D01*
G03X289504Y227823I-44J1575D01*
G02X291434Y228985I2015J-1163D01*
G01X291590D01*
G03X292884Y229772I-71J1574D01*
G01X292950Y229888D01*
X294899Y232509D01*
G01X298279Y230559D02*
X295043Y230184D01*
X294828D01*
G03X293534Y229397I71J-1574D01*
G02X291589Y228234I-2015J1162D01*
G01X291448D01*
G03X290154Y227447I71J-1574D01*
G02X288190Y226284I-2015J1163D01*
G01X288080D01*
G03X286774Y225497I59J-1575D01*
G02X284844Y224335I-2015J1163D01*
G01X284715D01*
G03X283394Y223547I44J-1575D01*
G02X281449Y222384I-2015J1162D01*
G01X281320D01*
G03X280014Y221597I59J-1575D01*
G02X278084Y220435I-2015J1163D01*
G01X277955D01*
G03X276634Y219647I44J-1575D01*
G02X274689Y218484I-2015J1162D01*
G01X272509D01*
X264786Y210761D01*
X263756D01*
X262828Y209833D01*
G01X294899Y236409D02*
X292950Y233788D01*
X292884Y233672D01*
G02X291578Y232885I-1365J788D01*
G01X291468D01*
G03X289504Y231722I51J-2326D01*
G02X288210Y230935I-1365J787D01*
G01X288069D01*
G03X286124Y229772I70J-2325D01*
G02X284830Y228985I-1365J787D01*
G01X284674D01*
G03X282744Y227823I85J-2325D01*
G02X281423Y227035I-1365J787D01*
G01X281328D01*
G03X279364Y225872I51J-2326D01*
G02X278058Y225085I-1365J788D01*
G01X277929D01*
G03X275984Y223922I70J-2325D01*
G02X274663Y223134I-1365J787D01*
G01X271829D01*
X265306Y216611D01*
X263550D01*
X262828Y217333D01*
G01X272140Y222384D02*
X265617Y215861D01*
X263856D01*
X262828Y214833D01*
G01X268688Y199831D02*
X270543Y201686D01*
X271320D01*
G03X272623Y204013I-81J1574D01*
G01X272604Y204047D01*
G02X274549Y207535I2015J1163D01*
G01X274690D01*
G03X275984Y209897I-71J1574D01*
G02X277929Y213385I2015J1163D01*
G01X278058D01*
G03X279364Y214172I-59J1575D01*
G02X281294Y215334I2015J-1163D01*
G01X281423D01*
G03X282744Y216122I-44J1575D01*
G02X284689Y217285I2015J-1162D01*
G01X284818D01*
G03X286124Y218072I-59J1575D01*
G02X288054Y219234I2015J-1163D01*
G01X288183D01*
G03X289504Y220022I-44J1575D01*
G02X291449Y221185I2015J-1162D01*
G01X291578D01*
G03X292884Y221972I-59J1575D01*
G02X294814Y223134I2015J-1163D01*
G01X294943D01*
G03X296264Y223922I-44J1575D01*
G02X298209Y225085I2015J-1162D01*
G01X298338D01*
G03X299644Y225872I-59J1575D01*
G02X301608Y227035I2015J-1163D01*
G01X301703D01*
G03X303024Y227823I-44J1575D01*
G02X304954Y228985I2015J-1163D01*
G01X305087D01*
G03X306403Y229772I-48J1574D01*
G02X308348Y230935I2015J-1162D01*
G01X309799D01*
X311672Y230717D01*
X311798Y230559D01*
G01X318558Y234460D02*
X315320Y234084D01*
X315119D01*
G03X313624Y232248I59J-1575D01*
G01X313372Y230134D01*
X313073Y229467D01*
X312648Y229203D01*
X312298Y228985D01*
X311218D01*
X309594Y229659D01*
G03X309213Y229971I-1177J-1048D01*
G03X308489Y230184I-794J-1361D01*
G01X308418D01*
G03X307067Y229419I0J-1575D01*
G01X307054Y229396D01*
G02X305124Y228234I-2015J1163D01*
G01X304968D01*
G03X303674Y227447I71J-1574D01*
G02X301710Y226284I-2015J1163D01*
G01X301600D01*
G03X300294Y225497I59J-1575D01*
G02X298364Y224335I-2015J1163D01*
G01X298235D01*
G03X296914Y223547I44J-1575D01*
G02X294969Y222384I-2015J1162D01*
G01X294840D01*
G03X293534Y221597I59J-1575D01*
G02X291604Y220435I-2015J1163D01*
G01X291475D01*
G03X290154Y219647I44J-1575D01*
G02X288209Y218484I-2015J1162D01*
G01X288080D01*
G03X286774Y217697I59J-1575D01*
G02X284844Y216535I-2015J1163D01*
G01X284715D01*
G03X283394Y215747I44J-1575D01*
G02X281449Y214584I-2015J1162D01*
G01X281320D01*
G03X280014Y213797I59J-1575D01*
G02X278084Y212635I-2015J1163D01*
G01X277955D01*
G03X276634Y210272I44J-1575D01*
G02X274704Y206784I-2015J-1163D01*
G01X274548D01*
G03X273254Y204423I71J-1574D01*
G02Y202097I-2015J-1163D01*
G01X272498Y200787D01*
Y199492D01*
X270337Y197331D01*
G01X318558Y222760D02*
X316979Y220568D01*
G03X316543Y220022I1579J-1708D01*
G02X315222Y219234I-1365J787D01*
G01X315093D01*
G03X313163Y218072I85J-2325D01*
G02X311857Y217285I-1365J788D01*
G01X311728D01*
G03X309783Y216122I70J-2325D01*
G02X308462Y215334I-1365J787D01*
G01X308320D01*
G03X306403Y214173I98J-2325D01*
G02X305087Y213386I-1364J787D01*
G01X304969D01*
G03X303024Y212223I70J-2325D01*
G02X301678Y211434I-1365J786D01*
G01X301574D01*
G03X299644Y210272I85J-2325D01*
G02X298338Y209485I-1365J788D01*
G01X298228D01*
G03X296264Y208322I51J-2326D01*
G02X294970Y207535I-1365J787D01*
G01X294829D01*
G03X292884Y206372I70J-2325D01*
G02X291590Y205585I-1365J787D01*
G01X291434D01*
G03X289504Y202097I85J-2325D01*
G02X289523Y200556I-1365J-787D01*
G01X289504Y200522D01*
X289469Y200462D01*
G03X289504Y198196I2050J-1102D01*
G01X290575Y196345D01*
Y190368D01*
X289677Y189470D01*
X288531D01*
G01X321938Y224709D02*
X320687Y221822D01*
G02X318643Y220435I-2129J938D01*
G01X318514D01*
G03X317193Y219647I44J-1575D01*
G02X315248Y218484I-2015J1162D01*
G01X315119D01*
G03X313813Y217697I59J-1575D01*
G02X311883Y216535I-2015J1163D01*
G01X311754D01*
G03X310433Y215747I44J-1575D01*
G02X308488Y214584I-2015J1162D01*
G01X308418D01*
G03X307067Y213819I0J-1575D01*
G01X307054Y213796D01*
G02X305137Y212635I-2015J1164D01*
G01X304980D01*
G03X303674Y211847I59J-1574D01*
G02X301729Y210684I-2015J1162D01*
G01X301600D01*
G03X300294Y209897I59J-1575D01*
G02X298330Y208734I-2015J1163D01*
G01X298235D01*
G03X296914Y207946I44J-1575D01*
G02X294984Y206784I-2015J1163D01*
G01X294828D01*
G03X293534Y205997I71J-1574D01*
G02X291589Y204834I-2015J1162D01*
G01X291448D01*
G03X290154Y202472I71J-1574D01*
G02X290179Y200189I-2015J-1164D01*
G01X290154Y200147D01*
X290135Y200113D01*
G03X290154Y198572I1384J-754D01*
G01X291325Y196547D01*
Y190050D01*
X290312Y189037D01*
Y186920D01*
G01X267080Y206810D02*
X268079D01*
X268724Y207455D01*
X269092Y208093D01*
X269224Y208322D01*
G02X271154Y209484I2015J-1163D01*
G01X271283D01*
G03X272604Y211846I-44J1575D01*
G02X274534Y215334I2015J1163D01*
G01X274663D01*
G03X275984Y216122I-44J1575D01*
G02X277929Y217285I2015J-1162D01*
G01X278058D01*
G03X279364Y218072I-59J1575D01*
G02X281294Y219234I2015J-1163D01*
G01X281423D01*
G03X282744Y220022I-44J1575D01*
G02X284689Y221185I2015J-1162D01*
G01X284818D01*
G03X286124Y221972I-59J1575D01*
G02X288054Y223134I2015J-1163D01*
G01X288183D01*
G03X289504Y223922I-44J1575D01*
G02X291449Y225085I2015J-1162D01*
G01X291578D01*
G03X292884Y225872I-59J1575D01*
G02X294848Y227035I2015J-1163D01*
G01X294943D01*
G03X296264Y227823I-44J1575D01*
G02X298194Y228985I2015J-1163D01*
G01X298350D01*
G03X299644Y229772I-71J1574D01*
G02X301589Y230935I2015J-1162D01*
G01X301730D01*
G03X303024Y231722I-71J1574D01*
G02X304988Y232885I2015J-1163D01*
G01X305039D01*
G03X306390Y233650I0J1575D01*
G01X306403Y233673D01*
G02X308320Y234834I2015J-1164D01*
G01X308503D01*
G02X308777Y234808I-82J-2325D01*
G01X311798Y234460D01*
G01X315178Y236409D02*
X313229Y233788D01*
X313163Y233672D01*
G02X311857Y232885I-1365J788D01*
G01X311568D01*
X310645Y233142D01*
X309499Y233656D01*
G03X307067Y233319I-1080J-1147D01*
G01X307054Y233296D01*
G02X305109Y232134I-2015J1164D01*
G01X304995D01*
G03X303674Y231346I44J-1575D01*
G02X301744Y230184I-2015J1163D01*
G01X301588D01*
G03X300294Y229397I71J-1574D01*
G02X298349Y228234I-2015J1162D01*
G01X298208D01*
G03X296914Y227447I71J-1574D01*
G02X294950Y226284I-2015J1163D01*
G01X294840D01*
G03X293534Y225497I59J-1575D01*
G02X291604Y224335I-2015J1163D01*
G01X291475D01*
G03X290154Y223547I44J-1575D01*
G02X288209Y222384I-2015J1162D01*
G01X288080D01*
G03X286774Y221597I59J-1575D01*
G02X284844Y220435I-2015J1163D01*
G01X284715D01*
G03X283394Y219647I44J-1575D01*
G02X281449Y218484I-2015J1162D01*
G01X281320D01*
G03X280014Y217697I59J-1575D01*
G02X278084Y216535I-2015J1163D01*
G01X277955D01*
G03X276634Y215747I44J-1575D01*
G02X274689Y214584I-2015J1162D01*
G01X274575D01*
G03X273254Y212222I44J-1575D01*
G02X271324Y208734I-2015J-1163D01*
G01X271195D01*
G03X269874Y207946I44J-1575D01*
G01X269692Y207623D01*
X269658Y207563D01*
Y206751D01*
X269148Y206241D01*
Y205141D01*
X268948Y204941D01*
G01X315178Y224709D02*
X313229Y222088D01*
X313163Y221972D01*
G02X311857Y221185I-1365J788D01*
G01X311728D01*
G03X309783Y220022I70J-2325D01*
G02X308462Y219234I-1365J787D01*
G01X308320D01*
G03X306403Y218073I98J-2325D01*
G01X306390Y218050D01*
G02X305039Y217285I-1351J810D01*
G01X304969D01*
G03X303024Y216122I70J-2325D01*
G02X301703Y215334I-1365J787D01*
G01X301574D01*
G03X299644Y214172I85J-2325D01*
G02X298338Y213385I-1365J788D01*
G01X298209D01*
G03X296264Y212222I70J-2325D01*
G02X294943Y211434I-1365J787D01*
G01X294814D01*
G03X292884Y210272I85J-2325D01*
G02X291578Y209485I-1365J788D01*
G01X291468D01*
G03X289504Y208322I51J-2326D01*
G02X288210Y207535I-1365J787D01*
G01X288069D01*
G03X286124Y204047I70J-2325D01*
G01X286143Y204013D01*
G02X286124Y202472I-1384J-754D01*
G03X286099Y200189I2015J-1164D01*
G01X286124Y200147D01*
G02X286334Y199360I-1365J-786D01*
G01X286336Y199358D01*
Y193129D01*
X284647Y191440D01*
X283489D01*
G01X321938Y228610D02*
X320639Y225611D01*
X320573Y225497D01*
G02X318643Y224335I-2015J1163D01*
G01X318514D01*
G03X317193Y223547I44J-1575D01*
G02X315248Y222384I-2015J1162D01*
G01X315119D01*
G03X313813Y221597I59J-1575D01*
G02X311883Y220435I-2015J1163D01*
G01X311754D01*
G03X310433Y219647I44J-1575D01*
G02X308488Y218484I-2015J1162D01*
G01X308418D01*
G03X307067Y217719I0J-1575D01*
G01X307054Y217696D01*
G02X305137Y216535I-2015J1164D01*
G01X304995D01*
G03X303674Y215747I44J-1575D01*
G02X301729Y214584I-2015J1162D01*
G01X301600D01*
G03X300294Y213797I59J-1575D01*
G02X298364Y212635I-2015J1163D01*
G01X298235D01*
G03X296914Y211847I44J-1575D01*
G02X294969Y210684I-2015J1162D01*
G01X294840D01*
G03X293534Y209897I59J-1575D01*
G02X291570Y208734I-2015J1163D01*
G01X291475D01*
G03X290154Y207946I44J-1575D01*
G02X288224Y206784I-2015J1163D01*
G01X288068D01*
G03X286774Y204423I71J-1574D01*
G02Y202097I-2015J-1163D01*
G03X286755Y200556I1365J-787D01*
G01X286774Y200522D01*
G02X287085Y199360I-2015J-1162D01*
G01Y192674D01*
X284962Y190551D01*
Y189437D01*
G01X257892Y224180D02*
X257936D01*
X257980Y224224D01*
Y224268D01*
X258047Y224335D01*
X265547D01*
X271396Y230184D01*
X274704D01*
G03X276634Y231346I-85J2325D01*
G02X277955Y232134I1365J-787D01*
G01X278050D01*
G03X280014Y233297I-51J2326D01*
G02X281320Y234084I1365J-788D01*
G01X281449D01*
G03X283394Y235247I-70J2325D01*
G02X284715Y236035I1365J-787D01*
G01X284844D01*
G03X286774Y237197I-85J2325D01*
G02X288080Y237984I1365J-788D01*
G01X288209D01*
G03X290154Y239147I-70J2325D01*
G02X291475Y239935I1365J-787D01*
G01X291604D01*
G03X292371Y240095I-85J2325D01*
G01X294899Y240309D01*
G01X311798Y226660D02*
X308916Y226337D01*
G02X308469Y226284I-496J2273D01*
G01X308418D01*
G03X307067Y225519I0J-1575D01*
G01X307054Y225496D01*
G02X305137Y224335I-2015J1164D01*
G01X304995D01*
G03X303674Y223547I44J-1575D01*
G02X301729Y222384I-2015J1162D01*
G01X301600D01*
G03X300294Y221597I59J-1575D01*
G02X298364Y220435I-2015J1163D01*
G01X298235D01*
G03X296914Y219647I44J-1575D01*
G02X294969Y218484I-2015J1162D01*
G01X294840D01*
G03X293534Y217697I59J-1575D01*
G02X291604Y216535I-2015J1163D01*
G01X291475D01*
G03X290154Y215747I44J-1575D01*
G02X288209Y214584I-2015J1162D01*
G01X288080D01*
G03X286774Y213797I59J-1575D01*
G02X284844Y212635I-2015J1163D01*
G01X284715D01*
G03X283394Y211847I44J-1575D01*
G02X281449Y210684I-2015J1162D01*
G01X281320D01*
G03X279995Y208356I59J-1575D01*
G01X280014Y208322D01*
G02X278069Y204834I-2015J-1163D01*
G01X277928D01*
G03X276634Y202472I71J-1574D01*
G02X276659Y200192I-2015J-1162D01*
G01X275125Y197469D01*
X275184Y197257D01*
X275141Y197181D01*
G01X257710Y220168D02*
X257754D01*
X257798Y220212D01*
Y220292D01*
X257847Y220341D01*
X265825D01*
X271769Y226285D01*
X274672D01*
X274670Y226284D01*
G03X276634Y227447I-51J2326D01*
G02X277928Y228234I1365J-787D01*
G01X278069D01*
G03X280014Y229397I-70J2325D01*
G02X281308Y230184I1365J-787D01*
G01X281464D01*
G03X283394Y231346I-85J2325D01*
G02X284715Y232134I1365J-787D01*
G01X284810D01*
G03X286774Y233297I-51J2326D01*
G02X288080Y234084I1365J-788D01*
G01X288209D01*
G03X290154Y235247I-70J2325D01*
G02X291475Y236035I1365J-787D01*
G01X291604D01*
G03X293534Y237197I-85J2325D01*
G02X294840Y237984I1365J-788D01*
G01X294958D01*
G02X296264Y237197I-59J-1575D01*
G03X298194Y236035I2015J1163D01*
G01X298323D01*
G02X299644Y235247I-44J-1575D01*
G03X303533Y235030I2015J1162D01*
G01X303885Y235125D01*
X305039Y234460D01*
G01X281133Y197119D02*
X281195Y197181D01*
Y197399D01*
X282700Y198904D01*
X283419Y200189D01*
G03X283394Y202472I-2040J1119D01*
G02X283375Y204013I1365J787D01*
G01X283394Y204047D01*
G03X283419Y206330I-2015J1164D01*
G01X283394Y206372D01*
G02X284715Y208734I1365J787D01*
G01X284810D01*
G03X286774Y209897I-51J2326D01*
G02X288080Y210684I1365J-788D01*
G01X288209D01*
G03X290154Y211847I-70J2325D01*
G02X291475Y212635I1365J-787D01*
G01X291604D01*
G03X293534Y213797I-85J2325D01*
G02X294840Y214584I1365J-788D01*
G01X294969D01*
G03X296914Y215747I-70J2325D01*
G02X298235Y216535I1365J-787D01*
G01X298364D01*
G03X300294Y217697I-85J2325D01*
G02X301600Y218484I1365J-788D01*
G01X301729D01*
G03X303674Y219647I-70J2325D01*
G02X304995Y220435I1365J-787D01*
G01X305137D01*
G03X307054Y221596I-98J2325D01*
G01X307067Y221619D01*
G02X308418Y222384I1351J-810D01*
G01X308488D01*
G03X310433Y223547I-70J2325D01*
G02X311754Y224335I1365J-787D01*
G01X311883D01*
G03X313813Y225497I-85J2325D01*
G02X315119Y226284I1365J-788D01*
G01X315229D01*
G03X317193Y227447I-51J2326D01*
G02X318487Y228234I1365J-787D01*
G01X318628D01*
G03X320690Y231492I-69J2325D01*
G01X320784Y231844D01*
X321938Y232509D01*
G01X257892Y225240D02*
X258047Y225085D01*
X265236D01*
X271085Y230934D01*
X274677D01*
G03X275984Y231721I-58J1575D01*
G01Y231722D01*
G02X277948Y232885I2015J-1163D01*
G01X278058D01*
G03X279364Y233672I-59J1575D01*
G02X281294Y234834I2015J-1163D01*
G01X281423D01*
G03X282744Y235622I-44J1575D01*
G02X284689Y236785I2015J-1162D01*
G01X284818D01*
G03X286124Y237572I-59J1575D01*
G02X288054Y238734I2015J-1163D01*
G01X288183D01*
G03X289504Y239522I-44J1575D01*
G02X291449Y240685I2015J-1162D01*
G01X291578D01*
G03X292096Y240793I-58J1575D01*
G03X292272Y240875I-576J1467D01*
G01X293644Y241301D01*
G02X294642Y241886I998J-559D01*
G01X294958Y241884D01*
G02X296264Y241097I-59J-1575D01*
G01X296463Y240747D01*
X298233Y238367D01*
X298279Y238360D01*
G01X315178Y228610D02*
X312360Y228236D01*
X311478D01*
X310801Y228130D01*
X310298Y227991D01*
G03X309627Y227600I406J-1468D01*
G02X308460Y227034I-1210J1009D01*
G01X308418D01*
G03X306418Y225896I0J-2326D01*
G01X306402Y225869D01*
G02X305119Y225085I-1364J791D01*
G01X304985D01*
G03X303024Y223922I54J-2325D01*
G02X301716Y223134I-1365J787D01*
G01X301587D01*
G03X299644Y221972I72J-2325D01*
G02X298348Y221185I-1365J788D01*
G01X298225D01*
G03X296264Y220022I54J-2325D01*
G02X294956Y219234I-1365J787D01*
G01X294827D01*
G03X292884Y218072I72J-2325D01*
G02X291588Y217285I-1365J788D01*
G01X291465D01*
G03X289504Y216122I54J-2325D01*
G02X288196Y215334I-1365J787D01*
G01X288067D01*
G03X286124Y214172I72J-2325D01*
G02X284828Y213385I-1365J788D01*
G01X284705D01*
G03X282744Y212222I54J-2325D01*
G02X281436Y211434I-1365J787D01*
G01X281307D01*
G03X279338Y207993I72J-2325D01*
G01X279361Y207951D01*
X279364Y207947D01*
G02X278056Y205584I-1365J-788D01*
G01X277912D01*
G03X275984Y202097I86J-2324D01*
G02X276003Y200556I-1365J-787D01*
G01X274471Y197837D01*
X274261Y197779D01*
X274218Y197703D01*
G01X257710Y221228D02*
X257847Y221091D01*
X265514D01*
X271458Y227035D01*
X274663D01*
G03X275984Y227823I-44J1575D01*
G02X277914Y228985I2015J-1163D01*
G01X278070D01*
G03X279364Y229772I-71J1574D01*
G02X281309Y230935I2015J-1162D01*
G01X281450D01*
G03X282744Y231722I-71J1574D01*
G02X284708Y232885I2015J-1163D01*
G01X284818D01*
G03X286124Y233672I-59J1575D01*
G02X288054Y234834I2015J-1163D01*
G01X288183D01*
G03X289504Y235622I-44J1575D01*
G02X291449Y236785I2015J-1162D01*
G01X291578D01*
G03X292884Y237572I-59J1575D01*
G02X294814Y238734I2015J-1163D01*
G01X294984D01*
G02X296914Y237572I-85J-2325D01*
G03X298220Y236785I1365J788D01*
G01X298349D01*
G02X300294Y235622I-70J-2325D01*
G03X302896Y235434I1365J787D01*
G01X302897Y235433D01*
X302813Y235744D01*
X302481Y235935D01*
X301659Y236409D01*
G01X280384Y197869D02*
X280446Y197931D01*
X280666D01*
X282096Y199361D01*
X282762Y200553D01*
G03X282744Y202097I-1383J756D01*
G02Y204423I2015J1163D01*
G03Y205997I-1365J787D01*
G01X282719Y206039D01*
G02X284708Y209485I2040J1120D01*
G01X284818D01*
G03X286124Y210272I-59J1575D01*
G02X288054Y211434I2015J-1163D01*
G01X288183D01*
G03X289504Y212222I-44J1575D01*
G02X291449Y213385I2015J-1162D01*
G01X291578D01*
G03X292884Y214172I-59J1575D01*
G02X294814Y215334I2015J-1163D01*
G01X294943D01*
G03X296264Y216122I-44J1575D01*
G02X298209Y217285I2015J-1162D01*
G01X298338D01*
G03X299644Y218072I-59J1575D01*
G02X301574Y219234I2015J-1163D01*
G01X301703D01*
G03X303024Y220022I-44J1575D01*
G02X304969Y221185I2015J-1162D01*
G01X305039D01*
G03X306390Y221950I0J1575D01*
G01X306403Y221973D01*
G02X308320Y223134I2015J-1164D01*
G01X308462D01*
G03X309783Y223922I-44J1575D01*
G02X311728Y225085I2015J-1162D01*
G01X311857D01*
G03X313163Y225872I-59J1575D01*
G02X315127Y227035I2015J-1163D01*
G01X315222D01*
G03X316543Y227823I-44J1575D01*
G02X318473Y228985I2015J-1163D01*
G01X318629D01*
G03X320022Y231140I-71J1574D01*
G01X319712Y231224D01*
X318558Y230559D01*
G01X268826Y383132D02*
X269243Y383856D01*
G03X269224Y385397I-1384J754D01*
G02X269199Y387680I2015J1164D01*
G01X269224Y387722D01*
X269243Y387756D01*
G03X269224Y389297I-1384J754D01*
G02Y391623I2015J1163D01*
G03Y393197I-1365J787D01*
G01X269004Y393578D01*
X268147Y394140D01*
X260347D01*
X259499Y393292D01*
G01X298279Y367060D02*
X295036Y367435D01*
X294855D01*
G02X293534Y368223I44J1575D01*
G03X291604Y369385I-2015J-1163D01*
G01X291448D01*
G02X290154Y370172I71J1574D01*
G03X288209Y371335I-2015J-1162D01*
G01X288068D01*
G02X286774Y372122I71J1574D01*
G03X284810Y373285I-2015J-1163D01*
G01X284700D01*
G02X283394Y374072I59J1575D01*
G03X281464Y375234I-2015J-1163D01*
G01X281335D01*
G02X280014Y376022I44J1575D01*
G03X278069Y377185I-2015J-1162D01*
G01X277940D01*
G02X276634Y377972I59J1575D01*
G03X274704Y379134I-2015J-1163D01*
G01X274575D01*
G02X273254Y379922I44J1575D01*
G03X271309Y381085I-2015J-1162D01*
G01X270582D01*
G02X269547Y382879I657J1575D01*
G01X269899Y383489D01*
G03X269874Y385772I-2040J1119D01*
G02X269855Y387313I1365J787D01*
G01X269874Y387347D01*
X269899Y387389D01*
G03X269874Y389672I-2040J1119D01*
G02X269855Y391213I1365J787D01*
G01X269874Y391247D01*
G03X269899Y393530I-2015J1164D01*
G01X269802Y393692D01*
X269565Y394106D01*
X268371Y394888D01*
X260434D01*
X259499Y395823D01*
G01X294899Y361209D02*
X292950Y363831D01*
X292884Y363947D01*
G03X291563Y364735I-1365J-787D01*
G01X291434D01*
G02X289504Y365897I85J2325D01*
G03X288198Y366684I-1365J-788D01*
G01X288088D01*
G02X286124Y367847I51J2326D01*
G03X284830Y368634I-1365J-787D01*
G01X284689D01*
G02X282744Y369797I70J2325D01*
G03X281450Y370584I-1365J-787D01*
G01X281294D01*
G02X279364Y371746I85J2325D01*
G03X278043Y372534I-1365J-787D01*
G01X277948D01*
G02X275984Y373697I51J2326D01*
G03X274690Y374484I-1365J-787D01*
G01X274534D01*
G02X272604Y375646I85J2325D01*
G01X270809Y377441D01*
X267048D01*
X264948Y379541D01*
Y387941D01*
X264148Y388741D01*
X256949D01*
X255997Y387789D01*
G01X294899Y365109D02*
X291661Y365485D01*
X291460D01*
G02X290154Y366272I59J1575D01*
G03X288190Y367435I-2015J-1163D01*
G01X288095D01*
G02X286774Y368223I44J1575D01*
G03X284844Y369385I-2015J-1163D01*
G01X284688D01*
G02X283394Y370172I71J1574D01*
G03X281449Y371335I-2015J-1162D01*
G01X281308D01*
G02X280014Y372122I71J1574D01*
G03X278050Y373285I-2015J-1163D01*
G01X277940D01*
G02X276634Y374072I59J1575D01*
G03X274689Y375235I-2015J-1162D01*
G01X274548D01*
G02X273254Y376022I71J1574D01*
G03X273133Y376175I-580J-335D01*
G01X271119Y378189D01*
X267358D01*
X265696Y379851D01*
Y388251D01*
X264458Y389489D01*
X256477D01*
X255677Y390289D01*
G01X310951Y365720D02*
X309352Y366683D01*
X308418D01*
G02X306416Y367822I-1J2328D01*
G01X306402Y367847D01*
X306403D01*
G03X305087Y368634I-1364J-787D01*
G01X304969D01*
G02X303024Y369797I70J2325D01*
G03X301730Y370584I-1365J-787D01*
G01X301574D01*
G02X299644Y371746I85J2325D01*
G03X298323Y372534I-1365J-787D01*
G01X298228D01*
G02X296264Y373697I51J2326D01*
G03X294958Y374484I-1365J-788D01*
G01X294829D01*
G02X292884Y375647I70J2325D01*
G03X291563Y376435I-1365J-787D01*
G01X291434D01*
G02X289504Y377597I85J2325D01*
G03X288198Y378384I-1365J-788D01*
G01X288069D01*
G02X286124Y379547I70J2325D01*
G03X284803Y380335I-1365J-787D01*
G01X284674D01*
G02X282744Y381497I85J2325D01*
G03X281438Y382284I-1365J-788D01*
G01X281309D01*
G02X279364Y383447I70J2325D01*
G03X278043Y384235I-1365J-787D01*
G01X277914D01*
G02X275984Y387723I85J2325D01*
G03Y389297I-1365J787D01*
G02Y391623I2015J1163D01*
G03Y393197I-1365J787D01*
G01X275959Y393239D01*
G02X275984Y395522I2040J1119D01*
G01X276003Y395556D01*
G03X274678Y397884I-1384J753D01*
G01X274549D01*
G02X272604Y399047I70J2325D01*
G01X271992Y400109D01*
Y402897D01*
X270292Y404597D01*
X269104D01*
G01X311798Y367060D02*
X309611Y367427D01*
X309524Y367435D01*
X308418D01*
G02X307067Y368200I0J1575D01*
G01X307054Y368223D01*
G03X305124Y369385I-2015J-1163D01*
G01X304968D01*
G02X303674Y370172I71J1574D01*
G03X301729Y371335I-2015J-1162D01*
G01X301588D01*
G02X300294Y372122I71J1574D01*
G03X298330Y373285I-2015J-1163D01*
G01X298220D01*
G02X296914Y374072I59J1575D01*
G03X294984Y375234I-2015J-1163D01*
G01X294855D01*
G02X293534Y376022I44J1575D01*
G03X291589Y377185I-2015J-1162D01*
G01X291460D01*
G02X290154Y377972I59J1575D01*
G03X288224Y379134I-2015J-1163D01*
G01X288095D01*
G02X286774Y379922I44J1575D01*
G03X284829Y381085I-2015J-1162D01*
G01X284700D01*
G02X283394Y381872I59J1575D01*
G03X281464Y383034I-2015J-1163D01*
G01X281335D01*
G02X280014Y383822I44J1575D01*
G03X278069Y384985I-2015J-1162D01*
G01X277955D01*
G02X276634Y387347I44J1575D01*
G03Y389673I-2015J1163D01*
G02Y391247I1365J787D01*
G03X276659Y393530I-2015J1164D01*
G01X276634Y393572D01*
G02Y395146I1365J787D01*
G03X274704Y398634I-2015J1163D01*
G01X274575D01*
G02X273254Y399422I44J1575D01*
G01X272740Y400314D01*
Y403207D01*
X270872Y405075D01*
Y406365D01*
G01X315178Y361209D02*
X311940Y361585D01*
X310497D01*
G02X309783Y361997I0J825D01*
G03X308477Y362784I-1365J-788D01*
G01X308348D01*
G02X306403Y363947I70J2325D01*
G01X306390Y363970D01*
G03X305039Y364735I-1351J-810D01*
G01X304954D01*
G02X303024Y365897I85J2325D01*
G03X301718Y366684I-1365J-788D01*
G01X301608D01*
G02X299644Y367847I51J2326D01*
G03X298350Y368634I-1365J-787D01*
G01X298209D01*
G02X296264Y369797I70J2325D01*
G03X294970Y370584I-1365J-787D01*
G01X294814D01*
G02X292884Y371746I85J2325D01*
G03X291563Y372534I-1365J-787D01*
G01X291468D01*
G02X289504Y373697I51J2326D01*
G03X288198Y374484I-1365J-788D01*
G01X288069D01*
G02X286124Y375647I70J2325D01*
G03X284803Y376435I-1365J-787D01*
G01X284674D01*
G02X282744Y377597I85J2325D01*
G03X281438Y378384I-1365J-788D01*
G01X281309D01*
G02X279364Y379547I70J2325D01*
G03X278043Y380335I-1365J-787D01*
G01X277914D01*
G02X275984Y381497I85J2325D01*
G03X274678Y382284I-1365J-788D01*
G01X274568D01*
G02X272604Y385773I51J2326D01*
G03Y387347I-1365J787D01*
G02Y389673I2015J1163D01*
G03Y391247I-1365J787D01*
G02X272579Y393530I2015J1164D01*
G01X272604Y393572D01*
G03X271283Y395934I-1365J787D01*
G01X271188D01*
G02X269224Y397097I51J2326D01*
G01X268185Y398677D01*
X266769Y400093D01*
X265699D01*
G01X311798Y363160D02*
X308564Y363534D01*
X308418D01*
G02X307067Y364299I0J1575D01*
G01X307054Y364322D01*
G03X305109Y365485I-2015J-1162D01*
G01X304980D01*
G02X303674Y366272I59J1575D01*
G03X301710Y367435I-2015J-1163D01*
G01X301615D01*
G02X300294Y368223I44J1575D01*
G03X298364Y369385I-2015J-1163D01*
G01X298208D01*
G02X296914Y370172I71J1574D01*
G03X294969Y371335I-2015J-1162D01*
G01X294828D01*
G02X293534Y372122I71J1574D01*
G03X291570Y373285I-2015J-1163D01*
G01X291460D01*
G02X290154Y374072I59J1575D01*
G03X288224Y375234I-2015J-1163D01*
G01X288095D01*
G02X286774Y376022I44J1575D01*
G03X284829Y377185I-2015J-1162D01*
G01X284700D01*
G02X283394Y377972I59J1575D01*
G03X281464Y379134I-2015J-1163D01*
G01X281335D01*
G02X280014Y379922I44J1575D01*
G03X278069Y381085I-2015J-1162D01*
G01X277940D01*
G02X276634Y381872I59J1575D01*
G03X274670Y383035I-2015J-1163D01*
G01X274575D01*
G02X273254Y385397I44J1575D01*
G03Y387723I-2015J1163D01*
G02Y389297I1365J787D01*
G03Y391623I-2015J1163D01*
G02Y393197I1365J787D01*
G01X273279Y393239D01*
G03X271290Y396685I-2040J1120D01*
G01X271180D01*
G02X269874Y397472I59J1575D01*
G01X269849Y397508D01*
X268768Y399152D01*
X267476Y400444D01*
Y401870D01*
G01X253248Y375168D02*
X254275Y374141D01*
X258248D01*
X265648Y366741D01*
X269648D01*
X272855Y363534D01*
X274704D01*
G02X276634Y362372I-85J-2325D01*
G03X277940Y361585I1365J788D01*
G01X278069D01*
G02X280014Y360422I-70J-2325D01*
G03X281335Y359634I1365J787D01*
G01X281464D01*
G02X283394Y358472I-85J-2325D01*
G03X284700Y357685I1365J788D01*
G01X284829D01*
G02X286774Y356522I-70J-2325D01*
G03X288095Y355734I1365J787D01*
G01X288224D01*
G02X290154Y354572I-85J-2325D01*
G03X291460Y353785I1365J788D01*
G01X291589D01*
G02X293534Y352622I-70J-2325D01*
G03X296264I1365J787D01*
G01X296330Y352738D01*
X298279Y355360D01*
G01X301659Y361209D02*
X302481Y361683D01*
X302813Y361875D01*
X303123Y361791D01*
G02X301703Y359634I-1465J-582D01*
G01X301574D01*
G03X299644Y358472I85J-2325D01*
G02X298338Y357685I-1365J788D01*
G01X298225D01*
G03X296264Y356522I54J-2325D01*
G02X294902Y355735I-1362J785D01*
G01X294896D01*
G02X293534Y356522I0J1572D01*
G03X291573Y357685I-2015J-1162D01*
G01X291460D01*
G02X290154Y358472I59J1575D01*
G03X288224Y359634I-2015J-1163D01*
G01X288095D01*
G02X286774Y360422I44J1575D01*
G03X284829Y361585I-2015J-1162D01*
G01X284700D01*
G02X283394Y362372I59J1575D01*
G03X281464Y363534I-2015J-1163D01*
G01X281335D01*
G02X280014Y364322I44J1575D01*
G03X278069Y365485I-2015J-1162D01*
G01X277940D01*
G02X276634Y366272I59J1575D01*
G03X274670Y367435I-2015J-1163D01*
G01X274669Y367434D01*
X272916D01*
X268459Y371891D01*
X264659D01*
X257230Y379320D01*
X254314D01*
X254159Y379475D01*
X254072D01*
G01X318558Y367060D02*
X319712Y366394D01*
X319795Y366084D01*
G02X318617Y365485I-1238J976D01*
G01X318499D01*
G02X317193Y366272I59J1575D01*
G03X315229Y367435I-2015J-1163D01*
G01X315134D01*
G02X313813Y368223I44J1575D01*
G03X311883Y369385I-2015J-1163D01*
G01X311727D01*
G02X310433Y370172I71J1574D01*
G03X308488Y371335I-2015J-1162D01*
G01X308370D01*
G02X307054Y372122I48J1574D01*
G03X305090Y373285I-2015J-1163D01*
G01X304980D01*
G02X303674Y374072I59J1575D01*
G03X301744Y375234I-2015J-1163D01*
G01X301615D01*
G02X300294Y376022I44J1575D01*
G03X298349Y377185I-2015J-1162D01*
G01X298220D01*
G02X296914Y377972I59J1575D01*
G03X294984Y379134I-2015J-1163D01*
G01X294855D01*
G02X293534Y379922I44J1575D01*
G03X291589Y381085I-2015J-1162D01*
G01X291460D01*
G02X290154Y381872I59J1575D01*
G03X288224Y383034I-2015J-1163D01*
G01X288095D01*
G02X286774Y383822I44J1575D01*
G03X284829Y384985I-2015J-1162D01*
G01X284700D01*
G02X283394Y385772I59J1575D01*
G03X281464Y386934I-2015J-1163D01*
G01X281335D01*
G02X280014Y389297I44J1575D01*
G03Y391623I-2015J1163D01*
G02Y393197I1365J787D01*
G01X280039Y393239D01*
G03X280014Y395522I-2040J1119D01*
G01X279995Y395556D01*
G02X280014Y397097I1384J754D01*
G03X280039Y399380I-2015J1164D01*
G01X279768Y399848D01*
Y403165D01*
X273678Y409255D01*
Y409474D01*
X273616Y409536D01*
G01X252577Y382660D02*
X252664Y382659D01*
X252821Y382811D01*
X253367Y382800D01*
X260911D01*
X261518Y382193D01*
Y378466D01*
X265824Y374141D01*
X269187D01*
X272744Y370584D01*
X274700D01*
G02X275984Y369797I-81J-1574D01*
G03X277929Y368634I2015J1162D01*
G01X278070D01*
G02X279364Y367847I-71J-1574D01*
G03X281328Y366684I2015J1163D01*
G01X281438D01*
G02X282744Y365897I-59J-1575D01*
G03X284674Y364735I2015J1163D01*
G01X284803D01*
G02X286124Y363947I-44J-1575D01*
G03X288069Y362784I2015J1162D01*
G01X288198D01*
G02X289504Y361997I-59J-1575D01*
G03X291434Y360835I2015J1163D01*
G01X291563D01*
G02X292884Y360047I-44J-1575D01*
G03X294829Y358884I2015J1162D01*
G01X294958D01*
G02X296136Y358285I-60J-1575D01*
G01X296053Y357975D01*
X294899Y357309D01*
G01X305039Y363160D02*
X303885Y362494D01*
X303791Y362142D01*
G02X301729Y358884I-2131J-933D01*
G01X301600D01*
G03X300294Y358097I59J-1575D01*
G02X298364Y356935I-2015J1163D01*
G01X298235D01*
G03X296914Y356147I44J-1575D01*
G02X294903Y354985I-2011J1160D01*
G01X294895D01*
G02X292884Y356147I0J2322D01*
G03X291563Y356935I-1365J-787D01*
G01X291434D01*
G02X289504Y358097I85J2325D01*
G03X288198Y358884I-1365J-788D01*
G01X288069D01*
G02X286124Y360047I70J2325D01*
G03X284803Y360835I-1365J-787D01*
G01X284674D01*
G02X282744Y361997I85J2325D01*
G03X281438Y362784I-1365J-788D01*
G01X281309D01*
G02X279364Y363947I70J2325D01*
G03X278043Y364735I-1365J-787D01*
G01X277914D01*
G02X275984Y365897I85J2325D01*
G03X274678Y366684I-1365J-788D01*
G01X272605D01*
X268148Y371141D01*
X264348D01*
X256919Y378570D01*
X254314D01*
X254159Y378415D01*
X254072D01*
G01X321938Y365109D02*
X320784Y365775D01*
X320432Y365680D01*
G02X318643Y364735I-1873J1380D01*
G01X318473D01*
G02X316543Y365897I85J2325D01*
G03X315237Y366684I-1365J-788D01*
G01X315127D01*
G02X313163Y367847I51J2326D01*
G03X311869Y368634I-1365J-787D01*
G01X311728D01*
G02X309783Y369797I70J2325D01*
G03X308489Y370584I-1365J-787D01*
G01X308333D01*
G02X306403Y371746I85J2325D01*
G01X306390Y371769D01*
G03X305039Y372534I-1351J-810D01*
G01X304988D01*
G02X303024Y373697I51J2326D01*
G03X301718Y374484I-1365J-788D01*
G01X301589D01*
G02X299644Y375647I70J2325D01*
G03X298323Y376435I-1365J-787D01*
G01X298194D01*
G02X296264Y377597I85J2325D01*
G03X294958Y378384I-1365J-788D01*
G01X294829D01*
G02X292884Y379547I70J2325D01*
G03X291563Y380335I-1365J-787D01*
G01X291434D01*
G02X289504Y381497I85J2325D01*
G03X288198Y382284I-1365J-788D01*
G01X288069D01*
G02X286124Y383447I70J2325D01*
G03X284803Y384235I-1365J-787D01*
G01X284674D01*
G02X282744Y385397I85J2325D01*
G03X281438Y386184I-1365J-788D01*
G01X281309D01*
G02X279364Y389672I70J2325D01*
G03X279383Y391213I-1365J787D01*
G01X279364Y391247D01*
G02X279339Y393530I2015J1164D01*
G01X279364Y393572D01*
G03Y395146I-1365J787D01*
G02Y397472I2015J1163D01*
G01X279365Y397473D01*
G03X279384Y399012I-1366J786D01*
G01X279018Y399647D01*
Y402854D01*
X273148Y408724D01*
X272928D01*
X272866Y408786D01*
G01X252597Y383720D02*
X252684Y383719D01*
X252835Y383561D01*
X253381Y383550D01*
X261222D01*
X262268Y382504D01*
Y378795D01*
X266138Y374891D01*
X269498D01*
X273055Y371334D01*
X274689D01*
X274690Y371335D01*
G02X276634Y370172I-71J-2325D01*
G03X277928Y369385I1365J787D01*
G01X278084D01*
G02X280014Y368223I-85J-2325D01*
G03X281335Y367435I1365J787D01*
G01X281430D01*
G02X283394Y366272I-51J-2326D01*
G03X284700Y365485I1365J788D01*
G01X284829D01*
G02X286774Y364322I-70J-2325D01*
G03X288095Y363534I1365J787D01*
G01X288224D01*
G02X290154Y362372I-85J-2325D01*
G03X291460Y361585I1365J788D01*
G01X291589D01*
G02X293534Y360422I-70J-2325D01*
G03X294855Y359634I1365J787D01*
G01X295461D01*
X298279Y359260D01*
G01X321938Y372909D02*
X318694Y373285D01*
X318499D01*
G02X317193Y374072I59J1575D01*
G01X316543Y375198D01*
G02Y376022I714J412D01*
G01X316562Y376056D01*
G03X315237Y378384I-1384J753D01*
G01X315108D01*
G02X313163Y379547I70J2325D01*
G03X311842Y380335I-1365J-787D01*
G01X311713D01*
G02X309783Y381497I85J2325D01*
G03X308477Y382284I-1365J-788D01*
G01X308348D01*
G02X306403Y383447I70J2325D01*
G01X306390Y383470D01*
G03X305039Y384235I-1351J-810D01*
G01X304954D01*
G02X303024Y385397I85J2325D01*
G03X301718Y386184I-1365J-788D01*
G01X301589D01*
G02X299644Y387347I70J2325D01*
G03X298323Y388135I-1365J-787D01*
G01X298194D01*
G02X296264Y391623I85J2325D01*
G03Y393197I-1365J787D01*
G01X296239Y393239D01*
G02X296264Y395522I2040J1119D01*
G01X296283Y395556D01*
G03X296264Y397097I-1384J754D01*
G02X296239Y399380I2015J1164D01*
G01X296653Y400118D01*
Y407036D01*
X288793Y414896D01*
X286903D01*
G01X321938Y369010D02*
X318702Y369385D01*
X318487D01*
G02X317193Y370172I71J1574D01*
G03X315248Y371335I-2015J-1162D01*
G01X315107D01*
G02X313813Y372122I71J1574D01*
G01X313163Y373249D01*
G02Y374072I713J412D01*
G03X311842Y376435I-1365J788D01*
G01X311713D01*
G02X309783Y377597I85J2325D01*
G03X308477Y378384I-1365J-788D01*
G01X308348D01*
G02X306403Y379547I70J2325D01*
G01X306390Y379570D01*
G03X305039Y380335I-1351J-810D01*
G01X304954D01*
G02X303024Y381497I85J2325D01*
G03X301718Y382284I-1365J-788D01*
G01X301589D01*
G02X299644Y383447I70J2325D01*
G03X298323Y384235I-1365J-787D01*
G01X298194D01*
G02X296264Y385397I85J2325D01*
G03X294958Y386184I-1365J-788D01*
G01X294829D01*
G02X292884Y387347I70J2325D01*
G03X291563Y388135I-1365J-787D01*
G01X291434D01*
G02X289504Y391623I85J2325D01*
G03Y393197I-1365J787D01*
G01X289479Y393239D01*
G02X289504Y395522I2040J1119D01*
G01X289523Y395556D01*
G03X289504Y397097I-1384J754D01*
G02X289479Y399380I2015J1164D01*
G01X289504Y399422D01*
X289752Y399799D01*
Y405584D01*
X284545Y410791D01*
X283098D01*
G01X315178Y372909D02*
X313881Y375905D01*
X313813Y376022D01*
G03X311868Y377185I-2015J-1162D01*
G01X311739D01*
G02X310433Y377972I59J1575D01*
G03X308503Y379134I-2015J-1163D01*
G01X308418D01*
G02X307067Y379899I0J1575D01*
G01X307054Y379922D01*
G03X305109Y381085I-2015J-1162D01*
G01X304980D01*
G02X303674Y381872I59J1575D01*
G03X301744Y383034I-2015J-1163D01*
G01X301615D01*
G02X300294Y383822I44J1575D01*
G03X298349Y384985I-2015J-1162D01*
G01X298220D01*
G02X296914Y385772I59J1575D01*
G03X294984Y386934I-2015J-1163D01*
G01X294855D01*
G02X293534Y387722I44J1575D01*
G03X291589Y388885I-2015J-1162D01*
G01X291460D01*
G02X290135Y391213I59J1575D01*
G01X290154Y391247D01*
G03X290179Y393530I-2015J1164D01*
G01X290154Y393572D01*
G02Y395146I1365J787D01*
G03Y397472I-2015J1163D01*
G02X290135Y399013I1365J787D01*
G01X290158Y399054D01*
X290500Y399574D01*
Y405894D01*
X285116Y411278D01*
Y412309D01*
G01X311798Y370959D02*
X310635Y372218D01*
X309783Y373697D01*
G03X308487Y374484I-1365J-788D01*
G01X308348D01*
G02X306403Y375647I70J2325D01*
G01X306390Y375670D01*
G03X305039Y376435I-1351J-810D01*
G01X304954D01*
G02X303024Y377597I85J2325D01*
G03X301718Y378384I-1365J-788D01*
G01X301589D01*
G02X299644Y379547I70J2325D01*
G03X298323Y380335I-1365J-787D01*
G01X298194D01*
G02X296264Y381497I85J2325D01*
G03X294958Y382284I-1365J-788D01*
G01X294829D01*
G02X292884Y383447I70J2325D01*
G03X291563Y384235I-1365J-787D01*
G01X291434D01*
G02X289504Y385397I85J2325D01*
G03X288198Y386184I-1365J-788D01*
G01X288069D01*
G02X286124Y387347I70J2325D01*
G03X284803Y388135I-1365J-787D01*
G01X284674D01*
G02X282744Y391623I85J2325D01*
G03Y393197I-1365J787D01*
G01X282719Y393239D01*
G02X282744Y395522I2040J1119D01*
G01X282763Y395556D01*
G03X282744Y397097I-1384J754D01*
G01X282743Y397098D01*
G02X282719Y399380I2016J1162D01*
G01X282968Y399834D01*
Y404492D01*
X275036Y412424D01*
X274815D01*
X274753Y412486D01*
G01X315178Y369010D02*
G02X313163Y371749I11250J10387D01*
G03X312370Y372430I-1365J-787D01*
G01X312018Y372580D01*
X311191Y372758D01*
X310433Y374072D01*
G03X308503Y375234I-2015J-1163D01*
G01X308418D01*
G02X307067Y375999I0J1575D01*
G01X307054Y376022D01*
G03X305109Y377185I-2015J-1162D01*
G01X304980D01*
G02X303674Y377972I59J1575D01*
G03X301744Y379134I-2015J-1163D01*
G01X301615D01*
G02X300294Y379922I44J1575D01*
G03X298349Y381085I-2015J-1162D01*
G01X298220D01*
G02X296914Y381872I59J1575D01*
G03X294984Y383034I-2015J-1163D01*
G01X294855D01*
G02X293534Y383822I44J1575D01*
G03X291589Y384985I-2015J-1162D01*
G01X291460D01*
G02X290154Y385772I59J1575D01*
G03X288224Y386934I-2015J-1163D01*
G01X288095D01*
G02X286774Y387722I44J1575D01*
G03X284829Y388885I-2015J-1162D01*
G01X284700D01*
G02X283375Y391213I59J1575D01*
G01X283394Y391247D01*
G03X283419Y393530I-2015J1164D01*
G01X283394Y393572D01*
G02Y395146I1365J787D01*
G03Y397472I-2015J1163D01*
G01X283393Y397473D01*
G02X283374Y399012I1366J786D01*
G01X283718Y399607D01*
Y404803D01*
X275565Y412956D01*
Y413175D01*
X275503Y413237D01*
G01X318558Y374860D02*
X317259Y377859D01*
X317193Y377972D01*
G03X315263Y379134I-2015J-1163D01*
G01X315134D01*
G02X313813Y379922I44J1575D01*
G03X311868Y381085I-2015J-1162D01*
G01X311739D01*
G02X310433Y381872I59J1575D01*
G03X308503Y383034I-2015J-1163D01*
G01X308418D01*
G02X307067Y383799I0J1575D01*
G01X307054Y383822D01*
G03X305109Y384985I-2015J-1162D01*
G01X304980D01*
G02X303674Y385772I59J1575D01*
G03X301744Y386934I-2015J-1163D01*
G01X301615D01*
G02X300294Y387722I44J1575D01*
G03X298349Y388885I-2015J-1162D01*
G01X298220D01*
G02X296895Y391213I59J1575D01*
G01X296914Y391247D01*
G03X296939Y393530I-2015J1164D01*
G01X296914Y393572D01*
G02Y395146I1365J787D01*
G03Y397472I-2015J1163D01*
G02X296895Y399013I1365J787D01*
G01X297401Y399922D01*
Y407346D01*
X288671Y416076D01*
Y416664D01*
G01X313889Y203400D02*
X315407D01*
X322708Y210701D01*
Y212325D01*
X323866Y213483D01*
Y216439D01*
X326353Y218926D01*
Y221399D01*
X326683Y221972D01*
G03X326702Y223513I-1365J787D01*
G01X326683Y223547D01*
X326658Y223589D01*
G02X326683Y225872I2040J1119D01*
G03X326702Y227413I-1365J787D01*
G01X326683Y227447D01*
G02X326658Y229730I2015J1164D01*
G01X326683Y229772D01*
G03Y231346I-1365J787D01*
G02Y233672I2015J1163D01*
G03X326702Y235213I-1365J787D01*
G01X326683Y235247D01*
X326658Y235289D01*
G02X326683Y237572I2040J1119D01*
G03X326702Y239113I-1365J787D01*
G01X326683Y239147D01*
X326658Y239189D01*
G02X326683Y241472I2040J1119D01*
G03X326702Y243013I-1365J787D01*
G01X326683Y243047D01*
X326658Y243089D01*
G02X326683Y245372I2040J1119D01*
G03X326702Y246913I-1365J787D01*
G01X326683Y246947D01*
X326658Y246989D01*
G02X326683Y249272I2040J1119D01*
G03Y250847I-1364J787D01*
G02Y253173I2015J1163D01*
G01X326699Y253201D01*
G02X328532Y255733I13166J-7602D01*
G01X328698Y255909D01*
G01Y263709D02*
X328685Y263704D01*
X327356Y260643D01*
G02X327333Y260597I-418J180D01*
G03X328094Y258355I1365J-787D01*
G02X329948Y256869I-1636J-3940D01*
G02X329272Y254443I-1250J-959D01*
G03X327333Y252797I1328J-3530D01*
G03Y251223I1365J-787D01*
G02Y248897I-2017J-1163D01*
G03X327314Y247356I1365J-787D01*
G01X327333Y247322D01*
X327358Y247280D01*
G02X327333Y244997I-2040J-1119D01*
G03X327314Y243456I1365J-787D01*
G01X327333Y243422D01*
X327358Y243380D01*
G02X327333Y241097I-2040J-1119D01*
G03X327314Y239556I1365J-787D01*
G01X327333Y239522D01*
X327358Y239480D01*
G02X327333Y237197I-2040J-1119D01*
G03X327314Y235656I1365J-787D01*
G01X327333Y235622D01*
X327358Y235580D01*
G02X327333Y233297I-2040J-1119D01*
G03X327314Y231756I1365J-787D01*
G01X327333Y231722D01*
G02X327358Y229439I-2015J-1164D01*
G01X327333Y229397D01*
G03Y227823I1365J-787D01*
G02Y225497I-2015J-1163D01*
G03X327314Y223956I1365J-787D01*
G01X327333Y223922D01*
X327358Y223880D01*
G02X327333Y221597I-2040J-1119D01*
G01X327103Y221199D01*
Y218615D01*
X324616Y216128D01*
Y213171D01*
X323458Y212013D01*
Y210393D01*
X316124Y203059D01*
Y201765D01*
G01X333218Y194591D02*
X334048Y195421D01*
Y196041D01*
X331938Y198151D01*
Y200011D01*
X336478Y204551D01*
Y212006D01*
X337857Y213385D01*
X338897D01*
G03X340222Y215713I-59J1575D01*
G01X340203Y215747D01*
X340178Y215789D01*
G02X340203Y218072I2040J1119D01*
G03X340222Y219613I-1365J787D01*
G01X340203Y219647D01*
X340178Y219689D01*
G02X340203Y221972I2040J1119D01*
G03X340222Y223513I-1365J787D01*
G01X340203Y223547D01*
X340178Y223589D01*
G02X340203Y225872I2040J1119D01*
G03X340222Y227413I-1365J787D01*
G01X340203Y227447D01*
G02X340178Y229730I2015J1164D01*
G01X340203Y229772D01*
G03Y231346I-1365J787D01*
G02Y233672I2015J1163D01*
G03X340222Y235213I-1365J787D01*
G01X340203Y235247D01*
X340178Y235289D01*
G02X340203Y237572I2040J1119D01*
G03X340222Y239113I-1365J787D01*
G01X340203Y239147D01*
X340178Y239189D01*
G02X340203Y241472I2040J1119D01*
G03X340222Y243013I-1365J787D01*
G01X340203Y243047D01*
X340178Y243089D01*
G02X340203Y245372I2040J1119D01*
G03X340222Y246913I-1365J787D01*
G01X340203Y246947D01*
X340178Y246989D01*
G02X340203Y249272I2040J1119D01*
G03X340222Y250813I-1365J787D01*
G01X340203Y250847D01*
X340178Y250889D01*
G02X340203Y253172I2040J1119D01*
G03X340222Y254713I-1365J787D01*
G01X340135Y254864D01*
X338838Y257860D01*
G01Y261760D02*
X340787Y259138D01*
X340853Y259022D01*
X340878Y258980D01*
G02X340853Y256697I-2040J-1119D01*
G03X340834Y255156I1365J-787D01*
G01X340853Y255122D01*
X340878Y255080D01*
G02X340853Y252797I-2040J-1119D01*
G03X340834Y251256I1365J-787D01*
G01X340853Y251222D01*
X340878Y251180D01*
G02X340853Y248897I-2040J-1119D01*
G03X340834Y247356I1365J-787D01*
G01X340853Y247322D01*
X340878Y247280D01*
G02X340853Y244997I-2040J-1119D01*
G03X340834Y243456I1365J-787D01*
G01X340853Y243422D01*
X340878Y243380D01*
G02X340853Y241097I-2040J-1119D01*
G03X340834Y239556I1365J-787D01*
G01X340853Y239522D01*
X340878Y239480D01*
G02X340853Y237197I-2040J-1119D01*
G03X340834Y235656I1365J-787D01*
G01X340853Y235622D01*
X340878Y235580D01*
G02X340853Y233297I-2040J-1119D01*
G03X340834Y231756I1365J-787D01*
G01X340853Y231722D01*
G02X340878Y229439I-2015J-1164D01*
G01X340853Y229397D01*
G03Y227823I1365J-787D01*
G02Y225497I-2015J-1163D01*
G03X340834Y223956I1365J-787D01*
G01X340853Y223922D01*
X340878Y223880D01*
G02X340853Y221597I-2040J-1119D01*
G03X340834Y220056I1365J-787D01*
G01X340853Y220022D01*
X340878Y219980D01*
G02X340853Y217697I-2040J-1119D01*
G03X340834Y216156I1365J-787D01*
G01X340853Y216122D01*
X340878Y216080D01*
G02X338923Y212635I-2040J-1120D01*
G01X338179D01*
X337228Y211684D01*
Y204241D01*
X332688Y199701D01*
Y198461D01*
X334798Y196351D01*
Y195511D01*
X335718Y194591D01*
G01X325318Y257860D02*
X323369Y255238D01*
X323303Y255122D01*
X323278Y255080D01*
G03X323303Y252797I2040J-1119D01*
G02X323322Y251256I-1365J-787D01*
G01X323303Y251222D01*
X323278Y251180D01*
G03X323303Y248897I2040J-1119D01*
G02X323322Y247356I-1365J-787D01*
G01X323303Y247322D01*
X323278Y247280D01*
G03X323303Y244997I2040J-1119D01*
G02X323322Y243456I-1365J-787D01*
G01X323303Y243422D01*
X323278Y243380D01*
G03X323303Y241097I2040J-1119D01*
G02X323322Y239556I-1365J-787D01*
G01X323303Y239522D01*
X323278Y239480D01*
G03X323303Y237197I2040J-1119D01*
G02X323322Y235656I-1365J-787D01*
G01X323303Y235622D01*
X323278Y235580D01*
G03X323303Y233297I2040J-1119D01*
G02X323322Y231756I-1365J-787D01*
G01X323303Y231722D01*
G03X323278Y229439I2015J-1164D01*
G01X323303Y229397D01*
G02Y227823I-1365J-787D01*
G03Y225497I2015J-1163D01*
G02X323322Y223956I-1365J-787D01*
G01X323303Y223922D01*
X323278Y223880D01*
G03X323303Y221597I2040J-1119D01*
G02Y220021I-1365J-788D01*
G01X322942Y219396D01*
X317839Y214293D01*
Y212916D01*
X316357Y211434D01*
X315093D01*
G03X313163Y210272I85J-2325D01*
G02X311798Y209485I-1363J787D01*
G01X310788D01*
X305903Y204600D01*
X304512D01*
G01X325318Y261760D02*
X326615Y258764D01*
X326702Y258613D01*
G02X326683Y257072I-1384J-754D01*
G01X326426Y256626D01*
X324752Y255431D01*
G03X323953Y253172I566J-1471D01*
G02X323978Y250889I-2015J-1164D01*
G01X323953Y250847D01*
X323934Y250813D01*
G03X323953Y249272I1384J-754D01*
G02X323978Y246989I-2015J-1164D01*
G01X323953Y246947D01*
X323934Y246913D01*
G03X323953Y245372I1384J-754D01*
G02X323978Y243089I-2015J-1164D01*
G01X323953Y243047D01*
X323934Y243013D01*
G03X323953Y241472I1384J-754D01*
G02X323978Y239189I-2015J-1164D01*
G01X323953Y239147D01*
X323934Y239113D01*
G03X323953Y237572I1384J-754D01*
G02X323978Y235289I-2015J-1164D01*
G01X323953Y235247D01*
X323934Y235213D01*
G03X323953Y233672I1384J-754D01*
G02Y231346I-2015J-1163D01*
G03Y229772I1365J-787D01*
G01X323978Y229730D01*
G02X323953Y227447I-2040J-1119D01*
G01X323934Y227413D01*
G03X323953Y225872I1384J-754D01*
G02X323978Y223589I-2015J-1164D01*
G01X323953Y223547D01*
X323934Y223513D01*
G03X323953Y221972I1384J-754D01*
G02Y219646I-2015J-1163D01*
G01X323539Y218929D01*
X318589Y213979D01*
Y212602D01*
X316671Y210684D01*
X315119D01*
G03X313813Y209897I59J-1575D01*
G02X311798Y208735I-2013J1162D01*
G01X311112D01*
X306392Y204015D01*
Y202936D01*
G01X328368Y195431D02*
X329238Y196301D01*
Y196821D01*
X328623Y197436D01*
Y202346D01*
X333452Y207175D01*
Y212663D01*
X336703Y215914D01*
X336823Y216122D01*
G03X336842Y217663I-1365J787D01*
G01X336823Y217697D01*
X336798Y217739D01*
G02X336823Y220022I2040J1119D01*
G01X336842Y220056D01*
G03X336823Y221597I-1384J754D01*
G02X336798Y223880I2015J1164D01*
G01X336823Y223922D01*
X336842Y223956D01*
G03X336823Y225497I-1384J754D01*
G02Y227823I2015J1163D01*
G03Y229397I-1365J787D01*
G01X336798Y229439D01*
G02X336823Y231722I2040J1119D01*
G01X336842Y231756D01*
G03X336823Y233297I-1384J754D01*
G02X336798Y235580I2015J1164D01*
G01X336823Y235622D01*
X336842Y235656D01*
G03X336823Y237197I-1384J754D01*
G02X336798Y239480I2015J1164D01*
G01X336823Y239522D01*
X336842Y239556D01*
G03X336823Y241097I-1384J754D01*
G02X336798Y243380I2015J1164D01*
G01X336823Y243422D01*
X336842Y243456D01*
G03X336823Y244997I-1384J754D01*
G02X336798Y247280I2015J1164D01*
G01X336823Y247322D01*
X336842Y247356D01*
G03X336823Y248897I-1384J754D01*
G02Y251223I2017J1163D01*
G03Y252797I-1365J787D01*
G02X336692Y253061I2014J1164D01*
G01X335458Y255909D01*
G01Y263709D02*
X336823Y260597D01*
G02X337010Y259540I-1365J-787D01*
G03X337473Y257073I3741J-575D01*
G02Y254747I-2015J-1163D01*
G03Y253173I1365J-787D01*
G02Y250847I-2015J-1163D01*
G03Y249272I1364J-788D01*
G02X337498Y246989I-2015J-1164D01*
G01X337473Y246947D01*
X337454Y246913D01*
G03X337473Y245372I1384J-754D01*
G02X337498Y243089I-2015J-1164D01*
G01X337473Y243047D01*
X337454Y243013D01*
G03X337473Y241472I1384J-754D01*
G02X337498Y239189I-2015J-1164D01*
G01X337473Y239147D01*
X337454Y239113D01*
G03X337473Y237572I1384J-754D01*
G02X337498Y235289I-2015J-1164D01*
G01X337473Y235247D01*
X337454Y235213D01*
G03X337473Y233672I1384J-754D01*
G02Y231346I-2015J-1163D01*
G03Y229772I1365J-787D01*
G01X337498Y229730D01*
G02X337473Y227447I-2040J-1119D01*
G01X337454Y227413D01*
G03X337473Y225872I1384J-754D01*
G02X337498Y223589I-2015J-1164D01*
G01X337473Y223547D01*
X337454Y223513D01*
G03X337473Y221972I1384J-754D01*
G02X337498Y219689I-2015J-1164D01*
G01X337473Y219647D01*
G03X337454Y218106I1365J-787D01*
G01X337473Y218072D01*
X337498Y218030D01*
G02X337473Y215747I-2040J-1119D01*
G01X337303Y215452D01*
X334202Y212351D01*
Y206863D01*
X329373Y202034D01*
Y197747D01*
X329986Y197134D01*
Y196153D01*
X330718Y195421D01*
G01X319692Y198488D02*
X319754Y198550D01*
Y198770D01*
X322471Y201487D01*
X323168Y202696D01*
Y204770D01*
X327998Y209600D01*
Y215491D01*
X328885Y216378D01*
X330738Y219689D01*
G03X330713Y221972I-2040J1119D01*
G02X330694Y223513I1365J787D01*
G01X330713Y223547D01*
X330738Y223589D01*
G03X330713Y225872I-2040J1119D01*
G02X330694Y227413I1365J787D01*
G01X330713Y227447D01*
G03X330738Y229730I-2015J1164D01*
G01X330713Y229772D01*
G02Y231346I1365J787D01*
G03Y233672I-2015J1163D01*
G02X330694Y235213I1365J787D01*
G01X330713Y235247D01*
X330738Y235289D01*
G03X330713Y237572I-2040J1119D01*
G02X330694Y239113I1365J787D01*
G01X330713Y239147D01*
X330738Y239189D01*
G03X330713Y241472I-2040J1119D01*
G02X330694Y243013I1365J787D01*
G01X330713Y243047D01*
X330738Y243089D01*
G03X330713Y245372I-2040J1119D01*
G02X330694Y246913I1365J787D01*
G01X330713Y246947D01*
X330738Y246989D01*
G03X330713Y249272I-2040J1119D01*
G02X330694Y250813I1365J787D01*
G01X330697Y250818D01*
X330699Y250822D01*
X330701Y250825D01*
X330704Y250830D01*
X330710Y250842D01*
X330738Y250889D01*
G03X331227Y251887I-10368J5699D01*
G01X332117Y253943D01*
X332078Y253960D01*
G01X325860Y196281D02*
X325922Y196343D01*
Y196563D01*
X326525Y197166D01*
Y203447D01*
X331176Y208098D01*
Y213028D01*
X332218Y214070D01*
Y215710D01*
X333939Y217431D01*
X334093Y217697D01*
G03X334118Y219980I-2015J1164D01*
G01X334093Y220022D01*
X334074Y220056D01*
G02X334093Y221597I1384J754D01*
G03X334118Y223880I-2015J1164D01*
G01X334093Y223922D01*
X334074Y223956D01*
G02X334093Y225497I1384J754D01*
G03Y227823I-2015J1163D01*
G02Y229397I1365J787D01*
G01X334118Y229439D01*
G03X334093Y231722I-2040J1119D01*
G01X334074Y231756D01*
G02X334093Y233297I1384J754D01*
G03X334118Y235580I-2015J1164D01*
G01X334093Y235622D01*
X334074Y235656D01*
G02X334093Y237197I1384J754D01*
G03X334118Y239480I-2015J1164D01*
G01X334093Y239522D01*
X334074Y239556D01*
G02X334093Y241097I1384J754D01*
G03X334118Y243380I-2015J1164D01*
G01X334093Y243422D01*
X334074Y243456D01*
G02X334093Y244997I1384J754D01*
G03X334118Y247280I-2015J1164D01*
G01X334093Y247322D01*
X334074Y247356D01*
G02X334093Y248897I1384J754D01*
G03X334118Y251180I-2015J1164D01*
G01X334093Y251222D01*
X334074Y251256D01*
G02X334093Y252797I1384J754D01*
G03X334118Y255080I-2015J1164D01*
G01X334093Y255122D01*
X334074Y255156D01*
G02X334093Y256697I1384J754D01*
G03X334118Y258980I-2015J1164D01*
G01X334093Y259022D01*
X334074Y259056D01*
G02X334093Y260597I1384J754D01*
G03X332335Y264072I-2015J1163D01*
G01X332078Y264329D01*
Y265660D01*
G01X318942Y199238D02*
X319004Y199300D01*
X319222D01*
X321870Y201948D01*
X322418Y202897D01*
Y205081D01*
X327248Y209911D01*
Y215802D01*
X328281Y216835D01*
X330081Y220053D01*
G03X330064Y221596I-1383J756D01*
G01X330063Y221597D01*
G02X330038Y223880I2015J1164D01*
G01X330063Y223922D01*
X330082Y223956D01*
G03X330063Y225497I-1384J754D01*
G02Y227823I2015J1163D01*
G03Y229397I-1365J787D01*
G01X330038Y229439D01*
G02X330063Y231722I2040J1119D01*
G01X330082Y231756D01*
G03X330063Y233297I-1384J754D01*
G02X330038Y235580I2015J1164D01*
G01X330063Y235622D01*
X330082Y235656D01*
G03X330063Y237197I-1384J754D01*
G02X330038Y239480I2015J1164D01*
G01X330063Y239522D01*
X330082Y239556D01*
G03X330063Y241097I-1384J754D01*
G02X330038Y243380I2015J1164D01*
G01X330063Y243422D01*
X330082Y243456D01*
G03X330063Y244997I-1384J754D01*
G02X330038Y247280I2015J1164D01*
G01X330063Y247322D01*
X330082Y247356D01*
G03X330063Y248897I-1384J754D01*
G02X330038Y251180I2015J1164D01*
G01X330059Y251217D01*
X330063Y251223D01*
G03X330552Y253568I-3319J1916D01*
G02X330713Y254747I1526J392D01*
G03X332071Y257845I-13361J7703D01*
G01X332078Y257852D01*
Y257860D01*
G01X325110Y197031D02*
Y197030D01*
X325171Y197091D01*
X325389D01*
X325775Y197477D01*
Y203758D01*
X330426Y208409D01*
Y213339D01*
X331468Y214381D01*
Y216021D01*
X333339Y217892D01*
X333443Y218072D01*
G03X333462Y219613I-1365J787D01*
G01X333443Y219647D01*
X333418Y219689D01*
G02X333443Y221972I2040J1119D01*
G03X333462Y223513I-1365J787D01*
G01X333443Y223547D01*
X333418Y223589D01*
G02X333443Y225872I2040J1119D01*
G03X333462Y227413I-1365J787D01*
G01X333443Y227447D01*
G02X333418Y229730I2015J1164D01*
G01X333443Y229772D01*
G03Y231346I-1365J787D01*
G02Y233672I2015J1163D01*
G03X333462Y235213I-1365J787D01*
G01X333443Y235247D01*
X333418Y235289D01*
G02X333443Y237572I2040J1119D01*
G03X333462Y239113I-1365J787D01*
G01X333443Y239147D01*
X333418Y239189D01*
G02X333443Y241472I2040J1119D01*
G03X333462Y243013I-1365J787D01*
G01X333443Y243047D01*
X333418Y243089D01*
G02X333443Y245372I2040J1119D01*
G03X333462Y246913I-1365J787D01*
G01X333443Y246947D01*
X333418Y246989D01*
G02X333443Y249272I2040J1119D01*
G03X333462Y250813I-1365J787D01*
G01X333443Y250847D01*
X333418Y250889D01*
G02X333443Y253172I2040J1119D01*
G03X333462Y254713I-1365J787D01*
G01X333443Y254747D01*
X333418Y254789D01*
G02X333443Y257072I2040J1119D01*
G03X333462Y258613I-1365J787D01*
G01X333443Y258647D01*
X333418Y258689D01*
G02X333443Y260972I2040J1119D01*
G03X332306Y263319I-1365J788D01*
G01X332078Y263091D01*
Y261760D01*
G01X301659Y232509D02*
X298415Y232885D01*
X298220D01*
G02X297253Y233263I58J1575D01*
G01X296215Y233812D01*
X295405Y234084D01*
X294840D01*
G03X293534Y233297I59J-1575D01*
G02X291570Y232134I-2015J1163D01*
G01X291475D01*
G03X290154Y231346I44J-1575D01*
G02X288224Y230184I-2015J1163D01*
G01X288068D01*
G03X286774Y229397I71J-1574D01*
G02X284829Y228234I-2015J1162D01*
G01X284688D01*
G03X283394Y227447I71J-1574D01*
G02X281430Y226284I-2015J1163D01*
G01X281320D01*
G03X280014Y225497I59J-1575D01*
G02X278084Y224335I-2015J1163D01*
G01X277955D01*
G03X276634Y223547I44J-1575D01*
G02X274689Y222384I-2015J1162D01*
G01X272140D01*
G01X267061Y354984D02*
X267918D01*
G02X269224Y354197I-59J-1575D01*
G03X271154Y353035I2015J1163D01*
G01X271283D01*
G02X272604Y352247I-44J-1575D01*
G03X274549Y351084I2015J1162D01*
G01X274678D01*
G02X275984Y350297I-59J-1575D01*
G03X277914Y349135I2015J1163D01*
G01X278043D01*
G02X279364Y348347I-44J-1575D01*
G03X281309Y347184I2015J1162D01*
G01X281438D01*
G02X282744Y346397I-59J-1575D01*
G03X284674Y345235I2015J1163D01*
G01X284803D01*
G02X286124Y344447I-44J-1575D01*
G03X288069Y343284I2015J1162D01*
G01X288198D01*
G02X289504Y342497I-59J-1575D01*
G03X291434Y341335I2015J1163D01*
G01X292118D01*
X293958Y340446D01*
G03X294896Y340135I939J1261D01*
G01X294902D01*
G03X296264Y340922I0J1572D01*
G02X296979Y341335I715J-412D01*
G01X268826Y383132D02*
G03X270439Y380335I2413J-472D01*
G01X271283D01*
G02X272604Y379547I-44J-1575D01*
G03X274549Y378384I2015J1162D01*
G01X274678D01*
G02X275984Y377597I-59J-1575D01*
G03X277914Y376435I2015J1163D01*
G01X278043D01*
G02X279364Y375647I-44J-1575D01*
G03X281309Y374484I2015J1162D01*
G01X281438D01*
G02X282744Y373697I-59J-1575D01*
G03X284708Y372534I2015J1163D01*
G01X284803D01*
G02X286124Y371746I-44J-1575D01*
G03X288054Y370584I2015J1163D01*
G01X288210D01*
G02X289504Y369797I-71J-1574D01*
G03X291449Y368634I2015J1162D01*
G01X291590D01*
G02X292884Y367847I-71J-1574D01*
G03X294848Y366684I2015J1163D01*
G01X294958D01*
G02X296264Y365897I-59J-1575D01*
G03X298194Y364735I2015J1163D01*
G01X298425D01*
X301659Y365109D01*
G01X332078Y335860D02*
X330713Y338974D01*
G02X330641Y340407I1365J787D01*
G03X330580Y341602I-1197J538D01*
G01X330063Y342498D01*
G02Y344824I2015J1163D01*
G03Y346398I-1365J787D01*
G02Y348724I2015J1163D01*
G03Y350298I-1365J787D01*
G02Y352624I2015J1163D01*
G03Y354198I-1365J787D01*
G02Y356524I2015J1163D01*
G03Y358098I-1365J787D01*
G02Y360424I2015J1163D01*
G03X328700Y362784I-1363J786D01*
G01X328698D01*
G02X326683Y366274I0J2327D01*
G03Y367847I-1363J787D01*
G02X326658Y370130I2015J1164D01*
G01X326683Y370172D01*
G03Y371746I-1365J787D01*
G02Y374072I2015J1163D01*
G03X325362Y376435I-1365J788D01*
G01X325233D01*
G02X323278Y379880I85J2325D01*
G01X323303Y379922D01*
X323322Y379956D01*
G03X321997Y382284I-1384J753D01*
G01X321938D01*
G02X319923Y383447I0J2327D01*
G03X318602Y384235I-1365J-787D01*
G01X318473D01*
G02X316543Y385397I85J2325D01*
G03X315237Y386184I-1365J-788D01*
G01X315108D01*
G02X312851Y388489I70J2326D01*
G01Y392138D01*
X310448Y394541D01*
Y403653D01*
X309675Y404426D01*
G01X332078Y343660D02*
X330871Y346443D01*
G03X330713Y346774I-2172J-834D01*
G02Y348348I1365J787D01*
G03Y350674I-2015J1163D01*
G02Y352248I1365J787D01*
G03Y354574I-2015J1163D01*
G02Y356148I1365J787D01*
G03Y358474I-2015J1163D01*
G02Y360048I1365J787D01*
G03X328700Y363534I-2013J1162D01*
G01X328699D01*
G02X327333Y365898I0J1577D01*
G03Y368223I-2016J1162D01*
G02Y369797I1365J787D01*
G01X327358Y369839D01*
G03X327333Y372122I-2040J1119D01*
G01X327314Y372156D01*
G02X327333Y373697I1384J754D01*
G03X325388Y377185I-2015J1163D01*
G01X325259D01*
G02X323934Y379513I59J1575D01*
G01X323953Y379547D01*
X323978Y379589D01*
G03X322023Y383034I-2040J1120D01*
G01X321938D01*
G02X320573Y383822I0J1576D01*
G03X318628Y384985I-2015J-1162D01*
G01X318499D01*
G02X317193Y385772I59J1575D01*
G03X315263Y386934I-2015J-1163D01*
G01X315121D01*
G02X313601Y388493I57J1576D01*
G01Y392446D01*
X311196Y394851D01*
Y403447D01*
X312175Y404426D01*
G01X328698Y337809D02*
X326749Y340431D01*
X326683Y340547D01*
X326658Y340589D01*
G02X326683Y342872I2040J1119D01*
G03X326702Y344413I-1365J787D01*
G01X326683Y344447D01*
X326658Y344489D01*
G02X326683Y346772I2040J1119D01*
G03X326702Y348313I-1365J787D01*
G01X326683Y348347D01*
X326658Y348389D01*
G02X326683Y350672I2040J1119D01*
G03X326702Y352213I-1365J787D01*
G01X326683Y352247D01*
X326658Y352289D01*
G02X326683Y354572I2040J1119D01*
G03X326702Y356113I-1365J787D01*
G01X326683Y356147D01*
X326658Y356189D01*
G02X326683Y358472I2040J1119D01*
G03X325362Y360835I-1365J788D01*
G01X325233D01*
G02X323278Y364280I85J2325D01*
G01X323303Y364322D01*
X323322Y364356D01*
G03X323303Y365897I-1384J754D01*
G02Y368223I2015J1163D01*
G03Y369797I-1365J787D01*
G01X323278Y369839D01*
G02X323303Y372122I2040J1119D01*
G01X323322Y372156D01*
G03X321997Y374484I-1384J753D01*
G01X321868D01*
G02X319923Y377972I70J2325D01*
G03X318602Y380335I-1365J788D01*
G01X318473D01*
G02X316543Y381497I85J2325D01*
G03X315237Y382284I-1365J-788D01*
G01X315108D01*
G02X313163Y383447I70J2325D01*
G03X311842Y384235I-1365J-787D01*
G01X311713D01*
G02X309758Y387680I85J2325D01*
G01X310173Y388417D01*
Y390016D01*
X307248Y392941D01*
Y396041D01*
X305248Y398041D01*
Y403009D01*
X304375Y403882D01*
G01X328698Y341709D02*
X327401Y344705D01*
X327314Y344856D01*
G02X327333Y346397I1384J754D01*
G03X327358Y348680I-2015J1164D01*
G01X327333Y348722D01*
X327314Y348756D01*
G02X327333Y350297I1384J754D01*
G03X327358Y352580I-2015J1164D01*
G01X327333Y352622D01*
X327314Y352656D01*
G02X327333Y354197I1384J754D01*
G03X327358Y356480I-2015J1164D01*
G01X327333Y356522D01*
X327314Y356556D01*
G02X327333Y358097I1384J754D01*
G03X325388Y361585I-2015J1163D01*
G01X325259D01*
G02X323934Y363913I59J1575D01*
G01X323953Y363947D01*
X323978Y363989D01*
G03X323953Y366272I-2040J1119D01*
G02X323934Y367813I1365J787D01*
G01X323953Y367847D01*
G03X323978Y370130I-2015J1164D01*
G01X323953Y370172D01*
G02Y371746I1365J787D01*
G03X322023Y375234I-2015J1163D01*
G01X321894D01*
G02X320573Y377597I44J1575D01*
G03X318628Y381085I-2015J1163D01*
G01X318499D01*
G02X317193Y381872I59J1575D01*
G03X315263Y383034I-2015J-1163D01*
G01X315134D01*
G02X313813Y383822I44J1575D01*
G03X311868Y384985I-2015J-1162D01*
G01X311739D01*
G02X310414Y387313I59J1575D01*
G01X310921Y388220D01*
Y390326D01*
X307996Y393251D01*
Y396351D01*
X305996Y398351D01*
Y403003D01*
X306875Y403882D01*
G01X335458Y337809D02*
Y336478D01*
X335230Y336250D01*
G02X334093Y338597I228J1559D01*
G03X334118Y340880I-2015J1164D01*
G01X334093Y340922D01*
X334074Y340956D01*
G02X334093Y342497I1384J754D01*
G03X334118Y344780I-2015J1164D01*
G01X334093Y344822D01*
X334074Y344856D01*
G02X334093Y346397I1384J754D01*
G03X334118Y348680I-2015J1164D01*
G01X334093Y348722D01*
X334074Y348756D01*
G02X334093Y350297I1384J754D01*
G03X334118Y352580I-2015J1164D01*
G01X334093Y352622D01*
X334074Y352656D01*
G02X334093Y354197I1384J754D01*
G03X334118Y356480I-2015J1164D01*
G01X334093Y356522D01*
X334074Y356556D01*
G02X334093Y358097I1384J754D01*
G03X334118Y360380I-2015J1164D01*
G01X334093Y360422D01*
X334074Y360456D01*
G02X334093Y361997I1384J754D01*
G03X332148Y365485I-2015J1163D01*
G01X332019D01*
G02X330694Y367813I59J1575D01*
G01X330713Y367847D01*
G03X330738Y370130I-2015J1164D01*
G01X330713Y370172D01*
G02Y371746I1365J787D01*
G03Y374072I-2015J1163D01*
G02X330694Y375613I1365J787D01*
G01X330713Y375647D01*
X330738Y375689D01*
G03X330713Y377972I-2040J1119D01*
G01X330712Y377973D01*
X329692Y379738D01*
X321938Y387492D01*
Y390413D01*
X319566Y392785D01*
X317812D01*
X317420Y393177D01*
X316968Y393959D01*
X316050Y395625D01*
Y406045D01*
X316205Y406200D01*
Y406287D01*
G01X335458Y345609D02*
G02X336823Y348724I14784J-4622D01*
G01X336827Y348731D01*
X336829Y348734D01*
X336842Y348756D01*
G03X336823Y350297I-1384J754D01*
G02X336798Y352580I2015J1164D01*
G01X336823Y352622D01*
X336842Y352656D01*
G03X336823Y354197I-1384J754D01*
G02X336798Y356480I2015J1164D01*
G01X336823Y356522D01*
X336842Y356556D01*
G03X336823Y358097I-1384J754D01*
G02X336798Y360380I2015J1164D01*
G01X336823Y360422D01*
X336842Y360456D01*
G03X336823Y361997I-1384J754D01*
G02X336798Y364280I2015J1164D01*
G01X336823Y364322D01*
X336842Y364356D01*
G03X335517Y366684I-1384J753D01*
G01X335407D01*
G02X333418Y370130I51J2326D01*
G01X333443Y370172D01*
G03Y371746I-1365J787D01*
G02Y374072I2015J1163D01*
G03X333462Y375613I-1365J787D01*
G01X333443Y375647D01*
X333418Y375689D01*
G02X333443Y377972I2040J1119D01*
G03X333462Y379513I-1365J787D01*
G01X333194Y379979D01*
X329198Y383975D01*
Y386530D01*
X318398Y397330D01*
Y403352D01*
X319530Y404484D01*
Y407918D01*
X319375Y408073D01*
Y408160D01*
G01X335458Y333909D02*
Y335240D01*
X335201Y335497D01*
G02X333443Y338972I257J2312D01*
G03X333462Y340513I-1365J787D01*
G01X333443Y340547D01*
X333418Y340589D01*
G02X333443Y342872I2040J1119D01*
G03X333462Y344413I-1365J787D01*
G01X333443Y344447D01*
X333418Y344489D01*
G02X333443Y346772I2040J1119D01*
G03X333462Y348313I-1365J787D01*
G01X333443Y348347D01*
X333418Y348389D01*
G02X333443Y350672I2040J1119D01*
G03X333462Y352213I-1365J787D01*
G01X333443Y352247D01*
X333418Y352289D01*
G02X333443Y354572I2040J1119D01*
G03X333462Y356113I-1365J787D01*
G01X333443Y356147D01*
X333418Y356189D01*
G02X333443Y358472I2040J1119D01*
G03X333462Y360013I-1365J787D01*
G01X333443Y360047D01*
X333418Y360089D01*
G02X333443Y362372I2040J1119D01*
G03X332122Y364735I-1365J788D01*
G01X331993D01*
G02X330063Y368223I85J2325D01*
G03Y369797I-1365J787D01*
G01X330038Y369839D01*
G02X330063Y372122I2040J1119D01*
G01X330082Y372156D01*
G03X330063Y373697I-1384J754D01*
G02X330038Y375980I2015J1164D01*
G01X330063Y376022D01*
X330082Y376056D01*
G03X330063Y377597I-1384J754D01*
G01X329092Y379277D01*
X321188Y387181D01*
Y390102D01*
X319255Y392035D01*
X317498D01*
X316824Y392709D01*
X316820Y392716D01*
X316315Y393590D01*
X315300Y395432D01*
Y406045D01*
X315145Y406200D01*
Y406287D01*
G01X335458Y341709D02*
G02X336823Y344824I14855J-4653D01*
G03X337020Y345815I-1365J786D01*
G02X337473Y348348I4215J553D01*
G01X337498Y348389D01*
G03X337473Y350672I-2040J1119D01*
G02X337454Y352213I1365J787D01*
G01X337473Y352247D01*
X337498Y352289D01*
G03X337473Y354572I-2040J1119D01*
G02X337454Y356113I1365J787D01*
G01X337473Y356147D01*
X337498Y356189D01*
G03X337473Y358472I-2040J1119D01*
G02X337454Y360013I1365J787D01*
G01X337473Y360047D01*
X337498Y360089D01*
G03X337473Y362372I-2040J1119D01*
G02X337454Y363913I1365J787D01*
G01X337473Y363947D01*
X337498Y363989D01*
G03X335509Y367435I-2040J1120D01*
G01X335414D01*
G02X334093Y369797I44J1575D01*
G01X334118Y369839D01*
G03X334093Y372122I-2040J1119D01*
G01X334074Y372156D01*
G02X334093Y373697I1384J754D01*
G03X334118Y375980I-2015J1164D01*
G01X334093Y376022D01*
X334074Y376056D01*
G02X334093Y377597I1384J754D01*
G03X334117Y379880I-2015J1163D01*
G01X334113Y379886D01*
X333795Y380439D01*
X329948Y384286D01*
Y386841D01*
X319148Y397641D01*
Y403041D01*
X320280Y404173D01*
Y407918D01*
X320435Y408073D01*
Y408160D01*
G01X342218Y337809D02*
X340921Y340805D01*
X340834Y340956D01*
G02X340853Y342497I1384J754D01*
G01X341501Y343620D01*
G02X342218Y344034I717J-414D01*
G01X342262D01*
G03X343583Y346397I-44J1575D01*
G02X343558Y348680I2015J1164D01*
G01X343583Y348722D01*
X343602Y348756D01*
G03X343583Y350297I-1384J754D01*
G02X343558Y352580I2015J1164D01*
G01X343583Y352622D01*
X343602Y352656D01*
G03X343583Y354197I-1384J754D01*
G02X343558Y356480I2015J1164D01*
G01X343583Y356522D01*
X343602Y356556D01*
G03X343583Y358097I-1384J754D01*
G02X343558Y360380I2015J1164D01*
G01X343583Y360422D01*
X343602Y360456D01*
G03X343583Y361997I-1384J754D01*
G02X343558Y364280I2015J1164D01*
G01X343583Y364322D01*
X343602Y364356D01*
G03X343583Y365897I-1384J754D01*
G02Y368223I2015J1163D01*
G03X342289Y370584I-1365J787D01*
G01X342133D01*
G02X340203Y374072I85J2325D01*
G03X340222Y375613I-1365J787D01*
G01X340203Y375647D01*
X340178Y375689D01*
G02X340203Y377972I2040J1119D01*
G03X340222Y379513I-1365J787D01*
G01X340203Y379547D01*
X340178Y379589D01*
G02X340203Y381872I2040J1119D01*
G03X340222Y383413I-1365J787D01*
G01X337732Y387733D01*
X329548Y395917D01*
Y404899D01*
X328748Y405699D01*
G01X342218Y341709D02*
X344167Y344331D01*
X344233Y344447D01*
X344258Y344489D01*
G03X344233Y346772I-2040J1119D01*
G02X344214Y348313I1365J787D01*
G01X344233Y348347D01*
X344258Y348389D01*
G03X344233Y350672I-2040J1119D01*
G02X344214Y352213I1365J787D01*
G01X344233Y352247D01*
X344258Y352289D01*
G03X344233Y354572I-2040J1119D01*
G02X344214Y356113I1365J787D01*
G01X344233Y356147D01*
X344258Y356189D01*
G03X344233Y358472I-2040J1119D01*
G02X344214Y360013I1365J787D01*
G01X344233Y360047D01*
X344258Y360089D01*
G03X344233Y362372I-2040J1119D01*
G02X344214Y363913I1365J787D01*
G01X344233Y363947D01*
X344258Y363989D01*
G03X344233Y366272I-2040J1119D01*
G02X344214Y367813I1365J787D01*
G01X344233Y367847D01*
G03X342288Y371335I-2015J1163D01*
G01X342147D01*
G02X340853Y373697I71J1574D01*
G03X340878Y375980I-2015J1164D01*
G01X340853Y376022D01*
X340834Y376056D01*
G02X340853Y377597I1384J754D01*
G03X340878Y379880I-2015J1164D01*
G01X340853Y379922D01*
X340834Y379956D01*
G02X340853Y381497I1384J754D01*
G03X340878Y383780I-2015J1164D01*
G01X338331Y388192D01*
X330296Y396227D01*
Y404899D01*
X331248Y405851D01*
G01X338838Y335860D02*
X337539Y338859D01*
X337473Y338972D01*
G02X337454Y340513I1365J787D01*
G01X337473Y340547D01*
X337498Y340589D01*
G03X337473Y342872I-2040J1119D01*
G02X337454Y344413I1365J787D01*
G01X338121Y345571D01*
G02X338838Y345985I717J-414D01*
G01X338897D01*
G03X340222Y348313I-59J1575D01*
G01X340203Y348347D01*
X340178Y348389D01*
G02X340203Y350672I2040J1119D01*
G03X340222Y352213I-1365J787D01*
G01X340203Y352247D01*
X340178Y352289D01*
G02X340203Y354572I2040J1119D01*
G03X340222Y356113I-1365J787D01*
G01X340203Y356147D01*
X340178Y356189D01*
G02X340203Y358472I2040J1119D01*
G03X340222Y360013I-1365J787D01*
G01X340203Y360047D01*
X340178Y360089D01*
G02X340203Y362372I2040J1119D01*
G03X340222Y363913I-1365J787D01*
G01X340203Y363947D01*
X340178Y363989D01*
G02X340203Y366272I2040J1119D01*
G03X338909Y368634I-1365J788D01*
G01X338768D01*
G02X336823Y372122I70J2325D01*
G01X336842Y372156D01*
G03X336823Y373697I-1384J754D01*
G02X336798Y375980I2015J1164D01*
G01X336823Y376022D01*
X336842Y376056D01*
G03X336823Y377597I-1384J754D01*
G02X336798Y379880I2015J1164D01*
G01X336823Y379922D01*
X336842Y379956D01*
G03X335517Y382284I-1384J753D01*
G01X335167D01*
X335165Y382286D01*
X334883D01*
X334882Y382287D01*
X334495D01*
X333136Y383646D01*
Y387995D01*
X326100Y395031D01*
Y401289D01*
X324248Y403141D01*
Y405299D01*
X323375Y406172D01*
G01X326848Y395341D02*
Y401641D01*
X325048Y403441D01*
Y405345D01*
X325875Y406172D01*
G01X359818Y199064D02*
Y201581D01*
X359068Y204830D01*
Y208128D01*
X357752Y210272D01*
G02X357733Y211813I1365J787D01*
G01X357752Y211847D01*
X357777Y211889D01*
G03X357752Y214172I-2040J1119D01*
G02X357541Y214979I1365J788D01*
G01Y231830D01*
X357283Y233215D01*
X356409Y234089D01*
X355933Y234393D01*
X348186Y238947D01*
G02X347613Y239522I792J1362D01*
G01X347547Y239638D01*
X345598Y242260D01*
G01X366079Y198554D02*
Y200413D01*
X364292Y202200D01*
Y203668D01*
X364892Y204703D01*
Y213554D01*
X364512Y214174D01*
G02Y215748I1365J787D01*
G03Y218074I-2015J1163D01*
G02Y219648I1365J787D01*
G03Y221974I-2015J1163D01*
G02Y223548I1365J787D01*
G03Y225874I-2015J1163D01*
G02Y227448I1365J787D01*
G03Y229774I-2015J1163D01*
G02Y231348I1365J787D01*
G03Y233674I-2015J1163D01*
G02Y235248I1365J787D01*
G03Y237574I-2015J1163D01*
G02X364302Y238405I1365J787D01*
G01Y241135D01*
X362803Y242634D01*
X362453D01*
G02X360921Y244200I44J1575D01*
G01Y246671D01*
X359792Y247800D01*
X357992D01*
X356352Y246160D01*
X352357D01*
G01X361818Y198627D02*
Y200033D01*
X360827Y204830D01*
Y234480D01*
X360437Y235485D01*
X359338Y236419D01*
X358537Y236851D01*
X348180Y242850D01*
G02X347613Y243422I798J1358D01*
G01X347547Y243538D01*
X345598Y246160D01*
G01X363868Y198651D02*
Y200824D01*
X363492Y201200D01*
Y203785D01*
X364073Y204788D01*
Y212995D01*
G03X363862Y213798I-1576J15D01*
G02Y216124I2015J1163D01*
G03Y217698I-1365J787D01*
G02Y220024I2015J1163D01*
G03Y221598I-1365J787D01*
G02Y223924I2015J1163D01*
G03Y225498I-1365J787D01*
G02Y227824I2015J1163D01*
G03Y229398I-1365J787D01*
G02Y231724I2015J1163D01*
G03Y233298I-1365J787D01*
G02Y235624I2015J1163D01*
G03X362541Y237986I-1365J787D01*
G01X362539Y237984D01*
X362427D01*
G02X360482Y241472I70J2325D01*
G03X360501Y243013I-1365J787D01*
G01X360414Y243164D01*
X359117Y246160D01*
G01X340988Y200519D02*
Y201300D01*
X342218Y205210D01*
G01X345598Y207159D02*
X347218Y205539D01*
Y202627D01*
X344988Y200397D01*
Y199498D01*
G01X342988Y199608D02*
Y200796D01*
X343980Y201788D01*
Y207347D01*
X342218Y209109D01*
G01X346988Y199062D02*
Y200206D01*
X348978Y202196D01*
Y205210D01*
G01X352357Y218860D02*
X350406Y216235D01*
X350307Y216062D01*
G03X350342Y213796I2050J-1102D01*
G02Y212222I-1364J-787D01*
G01X350307Y212162D01*
G03X350342Y209896I2050J-1102D01*
G02X350592Y208964I-1614J-932D01*
G01Y200500D01*
X350188Y200096D01*
Y199305D01*
G01X352357Y222760D02*
X354307Y220137D01*
X354372Y220024D01*
G02Y217698I-2015J-1163D01*
G03X354092Y216653I1811J-1045D01*
G01Y214542D01*
X353722Y214172D01*
G03X353697Y211889I2015J-1164D01*
G01X353722Y211847D01*
X353741Y211813D01*
G02X353722Y210272I-1384J-754D01*
G01X353631Y210114D01*
G03X353092Y208100I3494J-2014D01*
G01Y202382D01*
X354188Y201286D01*
Y200166D01*
G01X352188Y199802D02*
Y200980D01*
X351792Y201376D01*
Y207289D01*
G03X350993Y210273I-5970J0D01*
G02Y211847I1364J787D01*
G01X351028Y211907D01*
G03X350993Y214173I-2050J1102D01*
G02X351815Y216439I1364J787D01*
G01X352148Y216561D01*
G03X352992Y217100I-800J2183D01*
G03X353671Y217985I-3014J3015D01*
G01X353722Y218074D01*
G03X352929Y220329I-1365J787D01*
G01X351124Y221397D01*
X348978Y224709D01*
G01X355737Y213009D02*
X354438Y210010D01*
X354372Y209897D01*
G03X354092Y208863I1771J-1034D01*
G01Y203500D01*
X356188Y201404D01*
Y200081D01*
G01X342218Y384609D02*
X343515Y387605D01*
X343602Y387756D01*
G03X342237Y390085I-1384J753D01*
G01X341853D01*
X339209Y392729D01*
G01X345598Y386560D02*
X344299Y389559D01*
X344233Y389672D01*
G02X344061Y390807I1365J787D01*
G01Y392831D01*
X342392Y394500D01*
X341192D01*
X340292Y395400D01*
Y397400D01*
X342353Y399461D01*
Y401161D01*
G01X348978Y388509D02*
Y389259D01*
X347920Y390317D01*
G03X347613Y391623I-2322J143D01*
G02X347404Y392403I1352J780D01*
G01Y393654D01*
X348354Y394604D01*
Y396007D01*
G01X342218Y380709D02*
X343515Y383705D01*
X343583Y383822D01*
G02X345528Y384985I2015J-1162D01*
G01X345657D01*
G03X346982Y387313I-59J1575D01*
G01X346963Y387347D01*
X346938Y387389D01*
G02X346963Y389672I2040J1119D01*
G03X346982Y391213I-1365J787D01*
G01X346963Y391247D01*
G02X346489Y392251I7091J3962D01*
G01X346354Y393037D01*
Y395968D01*
G01X348978Y372909D02*
X349075Y373006D01*
G03X350155Y375613I-2607J2607D01*
G02X350307Y375962I2202J-752D01*
G01X350342Y376022D01*
G03Y377596I-1364J787D01*
G02X350307Y379862I2015J1164D01*
G01X350342Y379922D01*
G03Y381496I-1364J787D01*
G02X350307Y383762I2015J1164D01*
G01X350342Y383822D01*
G03Y385396I-1364J787D01*
G02X350307Y387662I2015J1164D01*
G01X350342Y387722D01*
G03X350618Y389580I-2184J1274D01*
G01Y394781D01*
X352918Y397081D01*
Y405606D01*
X353554Y406242D01*
Y407821D01*
G01X352357Y378760D02*
G02X353722Y381872I14816J-4643D01*
G03X353741Y383413I-1365J787D01*
G01X353722Y383447D01*
X353697Y383489D01*
G02X353722Y385772I2040J1119D01*
G03X353741Y387313I-1365J787D01*
G01X352953Y388683D01*
Y393715D01*
X355318Y396080D01*
Y404126D01*
X357554Y406362D01*
Y407727D01*
G01X352357Y374860D02*
X351056Y377866D01*
X350993Y377973D01*
G02Y379547I1364J787D01*
G01X351028Y379607D01*
G03X350993Y381873I-2050J1102D01*
G02Y383447I1364J787D01*
G01X351028Y383507D01*
G03X350993Y385773I-2050J1102D01*
G02Y387347I1364J787D01*
G03X351768Y388694I-551038J317938D01*
G01Y394179D01*
X354168Y396579D01*
Y404276D01*
X355554Y405662D01*
Y407821D01*
G01X355737Y384609D02*
X354445Y387594D01*
X354440Y387605D01*
X354118Y388162D01*
Y393080D01*
X356368Y395330D01*
Y403476D01*
X359554Y406662D01*
Y407781D01*
G01X348978Y357309D02*
X350276Y360308D01*
X350342Y360422D01*
G03Y361996I-1364J787D01*
G02X350307Y364262I2015J1164D01*
G01X350342Y364322D01*
G03Y365896I-1364J787D01*
G02X352272Y369385I2015J1164D01*
G01X352428D01*
G03X353722Y370172I-71J1574D01*
G02X355667Y371335I2015J-1162D01*
G01X355808D01*
G03X357102Y373697I-71J1574D01*
G02X357077Y375980I2015J1164D01*
G01X357102Y376022D01*
X357121Y376056D01*
G03X357102Y377597I-1384J754D01*
G02X357077Y379880I2015J1164D01*
G01X357102Y379922D01*
X357121Y379956D01*
G03X357418Y381121I-2138J1165D01*
G01Y388530D01*
X358218Y389330D01*
Y400326D01*
X359392Y401500D01*
G01X318558Y363160D02*
X315324Y363534D01*
X315134D01*
G02X313813Y364322I44J1575D01*
G03X311868Y365485I-2015J-1162D01*
G01X311739D01*
G02X310951Y365720I63J1648D01*
G01X338838Y343660D02*
X340787Y346281D01*
X340853Y346397D01*
G03X340878Y348680I-2015J1164D01*
G01X340853Y348722D01*
X340834Y348756D01*
G02X340853Y350297I1384J754D01*
G03X340878Y352580I-2015J1164D01*
G01X340853Y352622D01*
X340834Y352656D01*
G02X340853Y354197I1384J754D01*
G03X340878Y356480I-2015J1164D01*
G01X340853Y356522D01*
X340834Y356556D01*
G02X340853Y358097I1384J754D01*
G03X340878Y360380I-2015J1164D01*
G01X340853Y360422D01*
X340834Y360456D01*
G02X340853Y361997I1384J754D01*
G03X340878Y364280I-2015J1164D01*
G01X340853Y364322D01*
X340834Y364356D01*
G02X340853Y365897I1384J754D01*
G03X338923Y369385I-2015J1163D01*
G01X338767D01*
G02X337473Y371746I71J1574D01*
G03Y374072I-2015J1163D01*
G02X337454Y375613I1365J787D01*
G01X337473Y375647D01*
X337498Y375689D01*
G03X337473Y377972I-2040J1119D01*
G02X337454Y379513I1365J787D01*
G01X337473Y379547D01*
X337498Y379589D01*
G03X335543Y383034I-2040J1120D01*
G01X335193D01*
X335192Y383035D01*
X334805D01*
X333884Y383956D01*
Y388305D01*
X326848Y395341D01*
G01X296979Y341335D02*
X298364D01*
G03X300294Y342497I-85J2325D01*
G01X300360Y342610D01*
X301659Y345609D01*
G01X352357Y363160D02*
X353656Y366159D01*
X353722Y366272D01*
G02X355686Y367435I2015J-1163D01*
G01X355781D01*
G03X357102Y368223I-44J1575D01*
G02X359032Y369385I2015J-1163D01*
G01X359188D01*
G03X360482Y371746I-71J1574D01*
G02Y374072I2015J1163D01*
G03X360501Y375613I-1365J787D01*
G01X360482Y375647D01*
X360457Y375689D01*
G02X360482Y377972I2040J1119D01*
G03X360501Y379513I-1365J787D01*
G01X360482Y379547D01*
X360457Y379589D01*
G02X360482Y381872I2040J1119D01*
G03X360501Y383413I-1365J787D01*
G01X360482Y383447D01*
X360457Y383489D01*
G02X360482Y385772I2040J1119D01*
G03X360501Y387313I-1365J787D01*
G01X360002Y388205D01*
G02X359718Y389005I2202J1232D01*
G01X359728Y389015D01*
Y398986D01*
X360967Y400225D01*
G01X362497Y357309D02*
X364301Y360340D01*
Y367050D01*
G02X364493Y367813I1576J9D01*
G01X364512Y367847D01*
G03X364537Y370130I-2015J1164D01*
G01X364512Y370172D01*
G02Y371746I1365J787D01*
G03Y374072I-2015J1163D01*
G02X364493Y375613I1365J787D01*
G01X364512Y375647D01*
X364537Y375689D01*
G03X364512Y377972I-2040J1119D01*
G02X364493Y379513I1365J787D01*
G01X364512Y379547D01*
X364537Y379589D01*
G03X364512Y381872I-2040J1119D01*
G02X364493Y383413I1365J787D01*
G01X365318Y384853D01*
Y395976D01*
X365667Y396325D01*
G01X359117Y367060D02*
X362360Y367435D01*
X362541D01*
G03X363862Y369797I-44J1575D01*
G01X363837Y369839D01*
G02X363862Y372122I2040J1119D01*
G01X363881Y372156D01*
G03X363862Y373697I-1384J754D01*
G02X363837Y375980I2015J1164D01*
G01X363862Y376022D01*
X363881Y376056D01*
G03X363862Y377597I-1384J754D01*
G02X363837Y379880I2015J1164D01*
G01X363862Y379922D01*
X363881Y379956D01*
G03X363862Y381497I-1384J754D01*
G02X363837Y383780I2015J1164D01*
G01X363862Y383822D01*
X364096Y384239D01*
Y393696D01*
X363592Y394200D01*
Y397100D01*
X364146Y397654D01*
G01X359117Y351460D02*
X359108D01*
X357543Y353025D01*
Y367067D01*
G02X357733Y367813I1561J0D01*
G01X357752Y367847D01*
G02X359046Y368634I1365J-787D01*
G01X359187D01*
G03X361132Y372122I-70J2325D01*
G01X361113Y372156D01*
G02X361132Y373697I1384J754D01*
G03X361157Y375980I-2015J1164D01*
G01X361132Y376022D01*
X361113Y376056D01*
G02X361132Y377597I1384J754D01*
G03X361157Y379880I-2015J1164D01*
G01X361132Y379922D01*
X361113Y379956D01*
G02X361132Y381497I1384J754D01*
G03X361157Y383780I-2015J1164D01*
G01X361132Y383822D01*
X361113Y383856D01*
G02X361132Y385397I1384J754D01*
G03X361158Y387676I-2015J1163D01*
G01X360738Y388426D01*
Y389893D01*
X360745Y389900D01*
Y397153D01*
X362292Y398700D01*
G01X365877Y242260D02*
X367177Y239260D01*
X367242Y239148D01*
G02Y237574I-1365J-787D01*
G03Y235248I2015J-1163D01*
G02Y233674I-1365J-787D01*
G03Y231348I2015J-1163D01*
G02Y229774I-1365J-787D01*
G03Y227448I2015J-1163D01*
G02Y225874I-1365J-787D01*
G03Y223548I2015J-1163D01*
G02Y221974I-1365J-787D01*
G03Y219648I2015J-1163D01*
G02Y218074I-1365J-787D01*
G03Y215748I2015J-1163D01*
G02Y214174I-1365J-787D01*
G03X366930Y213000I2015J-1164D01*
G01Y211662D01*
X367492Y211100D01*
Y200699D01*
X368118Y200073D01*
Y198724D01*
G01X369257Y240309D02*
X367957Y237310D01*
X367892Y237198D01*
G03Y235624I1365J-787D01*
G02Y233298I-2015J-1163D01*
G03Y231724I1365J-787D01*
G02Y229398I-2015J-1163D01*
G03Y227824I1365J-787D01*
G02Y225498I-2015J-1163D01*
G03Y223924I1365J-787D01*
G02Y221598I-2015J-1163D01*
G03Y220024I1365J-787D01*
G02Y217698I-2015J-1163D01*
G03Y216124I1365J-787D01*
G02Y213798I-2015J-1163D01*
G03X367682Y212974I1365J-787D01*
G01Y212211D01*
X368392Y211501D01*
Y201700D01*
X370118Y199974D01*
Y198554D01*
G01X376017Y240309D02*
X377692Y238634D01*
Y212400D01*
X380971Y209121D01*
Y206309D01*
X384592Y202688D01*
Y198720D01*
X386518Y196794D01*
Y195037D01*
G01X372637Y242260D02*
X374318Y238698D01*
Y212482D01*
X375800Y211000D01*
X376352D01*
X377692Y209660D01*
Y206099D01*
X378292Y205500D01*
X380966Y202825D01*
Y200090D01*
X384518Y196538D01*
Y194697D01*
G01X372637Y207159D02*
Y203438D01*
X374434Y201642D01*
X379918Y196157D01*
Y192634D01*
X379318Y192034D01*
Y191223D01*
G01X372637Y211060D02*
Y211061D01*
X373937Y208060D01*
X374002Y207948D01*
G02X374264Y206969I-1698J-979D01*
G01Y203818D01*
X381318Y196764D01*
Y190630D01*
G01X369257Y213009D02*
X370002Y211291D01*
Y202197D01*
X372496Y199704D01*
X374118Y198081D01*
Y197381D01*
G01X369257Y216909D02*
X371017Y213280D01*
Y203081D01*
X376118Y197980D01*
Y196930D01*
G01X382777Y216909D02*
X386583D01*
X387792Y215700D01*
Y200500D01*
X391292Y197000D01*
Y194092D01*
X392448Y192936D01*
Y191624D01*
G01X379397Y218860D02*
X380216Y217113D01*
X382629Y214700D01*
X383392D01*
X384492Y213600D01*
Y206598D01*
X386592Y204498D01*
Y200300D01*
X390448Y196444D01*
Y191575D01*
G01X399676Y207159D02*
X402192Y204643D01*
Y198400D01*
X408198Y192394D01*
Y191151D01*
G01X392916Y211060D02*
X392092Y210236D01*
Y208200D01*
X391342Y207450D01*
Y200966D01*
X393829Y198479D01*
X397648Y191865D01*
Y190969D01*
G01X389537Y213009D02*
X391118Y209630D01*
Y208326D01*
X390492Y207700D01*
Y200600D01*
X392960Y198132D01*
X395648Y193480D01*
Y191381D01*
G01X396296Y213009D02*
X397968Y209280D01*
Y207031D01*
X398534Y205789D01*
X400663Y204692D01*
X401392Y203685D01*
Y197300D01*
X406198Y192494D01*
Y190981D01*
G01X396296Y216909D02*
X394996Y213910D01*
X394931Y213798D01*
G03Y212224I1365J-787D01*
G02Y209898I-2015J-1163D01*
G03Y208324I1365J-787D01*
G01X398061Y202973D01*
X399928Y196012D01*
X402898Y193042D01*
Y191500D01*
G01X400898Y191694D02*
Y192929D01*
X399198Y194629D01*
X397192Y202457D01*
X393970Y207780D01*
Y209180D01*
G02X394281Y210274I2326J-70D01*
G03Y211848I-1365J787D01*
G02Y214174I2015J1163D01*
G03Y215748I-1365J787D01*
G01X394216Y215860D01*
X392916Y218860D01*
G01X372637Y390460D02*
X373418Y391241D01*
Y393226D01*
X381592Y401400D01*
Y408614D01*
X383154Y410176D01*
Y411204D01*
G01X396296Y384609D02*
X402301D01*
X404992Y387300D01*
Y393901D01*
X411392Y400301D01*
Y401633D01*
G01X372637Y386560D02*
X374418Y388341D01*
Y393126D01*
X382392Y401100D01*
Y407240D01*
X385154Y410002D01*
Y411284D01*
G01X392916Y386560D02*
X391292Y388184D01*
Y391200D01*
X393592Y393500D01*
G01X389537Y384609D02*
Y386255D01*
X387892Y387900D01*
Y389100D01*
X392592Y393800D01*
G01X399676Y390460D02*
X401392Y392176D01*
Y393900D01*
X401792Y394300D01*
X403692D01*
X409392Y400000D01*
Y401553D01*
G01X369257Y384609D02*
X370554Y387605D01*
X370641Y387756D01*
G03X370622Y389297I-1384J754D01*
G02Y391623I2015J1163D01*
G03X370892Y392700I-1753J1012D01*
G01Y393000D01*
X379892Y402000D01*
Y404662D01*
X377954Y406600D01*
Y410841D01*
G01X396296Y380709D02*
X394996Y383709D01*
X394931Y383821D01*
G02Y385395I1365J787D01*
G01X395153Y385780D01*
G02X397092Y386900I1939J-1118D01*
G03X398092Y387900I0J1000D01*
G01Y391600D01*
G01X369257Y380709D02*
X370692Y382144D01*
Y383300D01*
X371319Y383927D01*
Y385597D01*
G03X371272Y385772I-351J0D01*
G02X371253Y387313I1365J787D01*
G01X371272Y387347D01*
X371297Y387389D01*
G03X371272Y389672I-2040J1119D01*
G02X371253Y391213I1365J787D01*
G02X371892Y392000I2444J-1332D01*
G01Y392800D01*
X380692Y401600D01*
Y406200D01*
X379954Y406938D01*
Y410706D01*
G01X392916Y378760D02*
X394216Y381759D01*
X394281Y381871D01*
G03Y383445I-1365J787D01*
G02Y385771I2015J1163D01*
G03X394491Y386595I-1365J787D01*
G01Y389295D01*
X396092Y390896D01*
Y392507D01*
G01X365877Y355360D02*
X367105Y358194D01*
G02X367242Y358472I2151J-887D01*
G03Y360046I-1365J787D01*
G02Y362372I2015J1163D01*
G03Y363946I-1365J787D01*
G02Y366272I2015J1163D01*
G03Y367846I-1365J787D01*
G02Y370172I2015J1163D01*
G03Y371746I-1365J787D01*
G02Y374072I2015J1163D01*
G03Y375646I-1365J787D01*
G02Y377972I2015J1163D01*
G03Y379546I-1365J787D01*
G02Y381872I2015J1163D01*
G03Y383446I-1365J787D01*
G02X366492Y386248I4861J2802D01*
G01Y394300D01*
X367042Y394850D01*
G01X403056Y361209D02*
X405592D01*
X408092Y363709D01*
Y393600D01*
X411042Y396550D01*
X413642D01*
X416593Y399501D01*
Y401566D01*
G01X369257Y357309D02*
X368892Y358135D01*
X368117Y359888D01*
G03X367892Y360422I-2240J-629D01*
G02Y361996I1365J787D01*
G03Y364322I-2015J1163D01*
G02Y365896I1365J787D01*
G03Y368222I-2015J1163D01*
G02Y369796I1365J787D01*
G03Y372122I-2015J1163D01*
G02Y373696I1365J787D01*
G03Y376022I-2015J1163D01*
G02Y377596I1365J787D01*
G03Y379922I-2015J1163D01*
G02Y381496I1365J787D01*
G03Y383822I-2015J1163D01*
G02X367592Y384942I1940J1120D01*
G01Y386300D01*
X367614Y386322D01*
Y393021D01*
X368692Y394099D01*
X369192D01*
X369693Y394600D01*
G01X376017Y357309D02*
X377827Y360389D01*
Y362503D01*
X377823Y362507D01*
Y378766D01*
G02X378013Y379513I1562J0D01*
G01X378032Y379547D01*
X378057Y379589D01*
G03X378032Y381872I-2040J1119D01*
G02X378013Y383413I1365J787D01*
G01X378032Y383447D01*
X378057Y383489D01*
G03X378032Y385772I-2040J1119D01*
G02X378013Y387313I1365J787D01*
G01X378032Y387347D01*
X378057Y387389D01*
G03X378032Y389672I-2040J1119D01*
G02X378013Y391213I1365J787D01*
G01X378032Y391247D01*
X378555Y392123D01*
X379078Y392486D01*
X379592Y393000D01*
X381192D01*
X382476Y394284D01*
G01X372637Y355360D02*
X373847Y358149D01*
G02X374002Y358472I2169J-842D01*
G03X374021Y360013I-1365J787D01*
G01X374002Y360047D01*
X373977Y360089D01*
G02X374002Y362372I2040J1119D01*
G03Y363946I-1365J787D01*
G02Y366272I2015J1163D01*
G03Y367846I-1365J787D01*
G02Y370172I2015J1163D01*
G03Y371746I-1365J787D01*
G02Y374072I2015J1163D01*
G03Y375646I-1365J787D01*
G02X375932Y379134I2015J1163D01*
G01X376061D01*
G03X377382Y381496I-44J1575D01*
G02Y383822I2015J1163D01*
G03Y385396I-1365J787D01*
G02Y387722I2015J1163D01*
G03Y389296I-1365J787D01*
G02Y391622I2015J1163D01*
G01X378741Y393972D01*
X379530Y394761D01*
G01X399676Y359260D02*
X400492Y360076D01*
Y361300D01*
X402360Y363168D01*
X404292D01*
X406492Y365368D01*
Y393400D01*
X414593Y401501D01*
Y402640D01*
G01X425974Y233746D02*
X425807Y233569D01*
G03X423974Y231037I11333J-10134D01*
G01X423958Y231009D01*
G03Y228683I2015J-1163D01*
G02X423978Y227143I-1365J-788D01*
G01X423959Y227109D01*
X423934Y227067D01*
G03X423959Y224784I2040J-1119D01*
G02X423978Y223243I-1365J-787D01*
G01X423959Y223209D01*
X423934Y223167D01*
G03X423959Y220884I2040J-1119D01*
G02X423978Y219343I-1365J-787D01*
G01X423959Y219309D01*
X423934Y219267D01*
G03X423959Y216984I2040J-1119D01*
G02X424170Y216196I-1364J-787D01*
G01Y215533D01*
X423809Y215172D01*
Y208253D01*
X423577Y208021D01*
Y205044D01*
X426270Y202351D01*
Y192841D01*
X425658Y192229D01*
Y189278D01*
X424957Y188577D01*
G01X425974Y241547D02*
X424608Y238433D01*
G03X425369Y236191I1365J-787D01*
G02X427223Y234705I-1636J-3940D01*
G02X426547Y232279I-1250J-959D01*
G03X424608Y230633I1328J-3530D01*
G03Y229059I1365J-787D01*
G02X424634Y226776I-2020J-1165D01*
G01X424609Y226734D01*
X424590Y226700D01*
G03X424609Y225159I1384J-754D01*
G02X424634Y222876I-2015J-1164D01*
G01X424609Y222834D01*
X424590Y222800D01*
G03X424609Y221259I1384J-754D01*
G02X424634Y218976I-2015J-1164D01*
G01X424609Y218934D01*
X424590Y218900D01*
G03X424609Y217359I1384J-754D01*
G02X424920Y216198I-2012J-1161D01*
G01Y215222D01*
X424559Y214861D01*
Y207945D01*
X424326Y207712D01*
Y205361D01*
X424328Y205359D01*
Y205357D01*
X427021Y202664D01*
X427020Y202663D01*
Y192530D01*
X426408Y191918D01*
Y189626D01*
X427457Y188577D01*
G01X419957Y189577D02*
X420998Y190618D01*
Y191841D01*
X423250Y194093D01*
Y201109D01*
X420558Y203801D01*
Y211071D01*
X420789Y211302D01*
Y214649D01*
X420579Y215034D01*
X420554Y215076D01*
G02X420579Y217359I2040J1119D01*
G03X420598Y218900I-1365J787D01*
G01X420579Y218934D01*
X420554Y218976D01*
G02X420579Y221259I2040J1119D01*
G03X420598Y222800I-1365J787D01*
G01X420579Y222834D01*
X420554Y222876D01*
G02X420579Y225159I2040J1119D01*
G03X420598Y226700I-1365J787D01*
G01X420579Y226734D01*
X420554Y226776D01*
G02X420578Y229059I2039J1120D01*
G03Y230633I-1364J787D01*
G02Y232959I2015J1163D01*
G01X421405Y234406D01*
G02X421453Y234471I304J-174D01*
G01X422594Y235696D01*
G01X422457Y189577D02*
X421748Y190286D01*
Y191530D01*
X424000Y193782D01*
Y201419D01*
X421307Y204112D01*
Y210762D01*
X421539Y210994D01*
Y214870D01*
X421210Y215443D01*
G02X421229Y216984I1384J754D01*
G03X421254Y219267I-2015J1164D01*
G01X421229Y219309D01*
X421210Y219343D01*
G02X421229Y220884I1384J754D01*
G03X421254Y223167I-2015J1164D01*
G01X421229Y223209D01*
X421210Y223243D01*
G02X421229Y224784I1384J754D01*
G03X421254Y227067I-2015J1164D01*
G01X421229Y227109D01*
X421210Y227143D01*
G02X421229Y228683I1382J753D01*
G03Y231009I-2015J1163D01*
G02Y232583I1364J787D01*
G01X421392Y232866D01*
X423041Y234185D01*
G03X423959Y236484I-447J1511D01*
G01X423893Y236597D01*
X422594Y239596D01*
G01X432733Y233746D02*
X433887Y233081D01*
X433981Y232730D01*
G03X434098Y230634I2132J-932D01*
G01Y230633D01*
G02Y229059I-1365J-787D01*
G03X434073Y226776I2018J-1164D01*
G01X434098Y226734D01*
X434117Y226700D01*
G02X434098Y225159I-1384J-754D01*
G03X434073Y222876I2015J-1164D01*
G01X434098Y222834D01*
X434117Y222800D01*
G02X434098Y221259I-1384J-754D01*
G03X434073Y218976I2015J-1164D01*
G01X434098Y218934D01*
X434117Y218900D01*
G02X434098Y217359I-1384J-754D01*
G03X434073Y215076I2015J-1164D01*
G01X434098Y215034D01*
X434117Y215000D01*
G02X434098Y213459I-1384J-754D01*
G03X433788Y212303I2002J-1156D01*
G01Y207646D01*
X436558Y204876D01*
Y191577D01*
X438578Y189557D01*
Y186686D01*
X437771Y185879D01*
G01X432733Y241547D02*
X434098Y238433D01*
G02X434285Y237376I-1365J-787D01*
G03X434748Y234909I3741J-575D01*
G02Y232583I-2015J-1163D01*
G03Y231009I1365J-787D01*
G02Y228683I-2015J-1163D01*
G03X434729Y227143I1363J-787D01*
G01X434748Y227109D01*
X434773Y227067D01*
G02X434748Y224784I-2040J-1119D01*
G03X434729Y223243I1365J-787D01*
G01X434748Y223209D01*
X434773Y223167D01*
G02X434748Y220884I-2040J-1119D01*
G03X434729Y219343I1365J-787D01*
G01X434731Y219339D01*
X434748Y219309D01*
X434773Y219267D01*
G02X434748Y216984I-2040J-1119D01*
G03X434729Y215443I1365J-787D01*
G01X434748Y215409D01*
X434773Y215367D01*
G02X434748Y213084I-2040J-1119D01*
G03X434538Y212300I1359J-784D01*
G01Y207954D01*
X437306Y205186D01*
Y191890D01*
X439328Y189868D01*
Y187064D01*
X440271Y186121D01*
G01X429354Y231797D02*
Y231789D01*
X429347Y231782D01*
G02X427989Y228684I-14719J4605D01*
G03X427970Y227143I1365J-787D01*
G01X427989Y227109D01*
X428014Y227067D01*
G02X427989Y224784I-2040J-1119D01*
G03X427970Y223243I1365J-787D01*
G01X427989Y223209D01*
X428014Y223167D01*
G02X427989Y220884I-2040J-1119D01*
G03X427970Y219343I1365J-787D01*
G01X427989Y219309D01*
X428014Y219267D01*
G02X427989Y216984I-2040J-1119D01*
G01X427703Y216488D01*
Y208736D01*
X428497Y207942D01*
Y205460D01*
X430041Y203916D01*
Y189309D01*
X431142Y188208D01*
Y186255D01*
X431297Y186100D01*
Y186013D01*
G01X429354Y243496D02*
Y242165D01*
X429610Y241909D01*
G02X431404Y238494I-256J-2313D01*
G01X431369Y238434D01*
G03Y236860I1364J-787D01*
G02X431394Y234575I-2015J-1165D01*
G01X431369Y234533D01*
G03Y232959I1364J-787D01*
G01X431394Y232917D01*
G02X431369Y230634I-2040J-1119D01*
G03Y229060I1364J-787D01*
G02X431404Y226794I-2015J-1164D01*
G01X431369Y226734D01*
G03Y225160I1364J-787D01*
G02X431404Y222894I-2015J-1164D01*
G01X431369Y222834D01*
G03Y221260I1364J-787D01*
G02X431404Y218994I-2015J-1164D01*
G01X431369Y218934D01*
G03Y217360I1364J-787D01*
G02X431404Y215094I-2015J-1164D01*
G01X431337Y214978D01*
G03X431368Y213459I1396J-731D01*
G01X431403Y213399D01*
G02X431368Y211131I-2050J-1103D01*
G03X431331Y209621I1365J-789D01*
G03X431339Y209603I1442J630D01*
G01X431899Y208635D01*
Y206854D01*
X433060Y205693D01*
Y191622D01*
X434842Y189840D01*
Y186655D01*
X434997Y186500D01*
Y186413D01*
G01X429354Y235696D02*
Y235688D01*
X429347Y235681D01*
G02X427989Y232583I-14719J4605D01*
G03X427828Y231404I1365J-787D01*
G02X427339Y229059I-3808J-429D01*
G03X427314Y226776I2015J-1164D01*
G01X427339Y226734D01*
X427358Y226700D01*
G02X427339Y225159I-1384J-754D01*
G03X427314Y222876I2015J-1164D01*
G01X427339Y222834D01*
X427358Y222800D01*
G02X427339Y221259I-1384J-754D01*
G03X427314Y218976I2015J-1164D01*
G01X427362Y218896D01*
G02X427339Y217360I-1388J-747D01*
G01Y217359D01*
X426953Y216689D01*
Y208425D01*
X427747Y207631D01*
Y205149D01*
X429291Y203605D01*
Y188998D01*
X430392Y187897D01*
Y186255D01*
X430237Y186100D01*
Y186013D01*
G01X429354Y239596D02*
Y240927D01*
X429581Y241154D01*
G02X430718Y238809I-227J-1558D01*
G01X430683Y238749D01*
G03X430718Y236483I2050J-1102D01*
G02Y234909I-1364J-787D01*
G03X430693Y232626I2015J-1164D01*
G01X430718Y232584D01*
G02Y231010I-1364J-787D01*
G01X430693Y230968D01*
G03X430718Y228683I2040J-1120D01*
G02Y227109I-1364J-787D01*
G01X430683Y227049D01*
G03X430718Y224783I2050J-1102D01*
G02Y223209I-1364J-787D01*
G01X430683Y223149D01*
G03X430718Y220883I2050J-1102D01*
G02Y219309I-1364J-787D01*
G01X430683Y219249D01*
G03X430718Y216983I2050J-1102D01*
G02Y215409I-1364J-787D01*
G01X430693Y215367D01*
G03X430718Y213084I2040J-1119D01*
G01X430737Y213050D01*
G02X430718Y211507I-1384J-755D01*
G03X430683Y209239I2015J-1165D01*
G01X431149Y208433D01*
Y206543D01*
X432310Y205382D01*
Y191311D01*
X434092Y189529D01*
Y186655D01*
X433937Y186500D01*
Y186413D01*
G01X437166Y210346D02*
Y208537D01*
X439408Y206295D01*
Y194498D01*
X443528Y190378D01*
Y189334D01*
X442771Y188577D01*
G01X436113Y239596D02*
X438062Y236975D01*
X438128Y236859D01*
G02Y234533I-2015J-1163D01*
G03Y232959I1365J-787D01*
G01X438153Y232917D01*
G02X438128Y230634I-2040J-1119D01*
G01X438109Y230600D01*
G03X438128Y229059I1384J-754D01*
G02X438153Y226776I-2015J-1164D01*
G01X438128Y226734D01*
X438109Y226700D01*
G03X438128Y225159I1384J-754D01*
G02X438153Y222876I-2015J-1164D01*
G01X438128Y222834D01*
X438109Y222800D01*
G03X438128Y221259I1384J-754D01*
G02X438153Y218976I-2015J-1164D01*
G01X438128Y218934D01*
X438109Y218900D01*
G03X438128Y217359I1384J-754D01*
G02X438153Y215076I-2015J-1164D01*
G01X438128Y215034D01*
X438109Y215000D01*
G03X438128Y213459I1384J-754D01*
G02Y211133I-2015J-1163D01*
G01X438109Y211099D01*
G03X437917Y210346I1384J-754D01*
G01Y208849D01*
X440158Y206608D01*
Y194810D01*
X444278Y190690D01*
Y189570D01*
X445271Y188577D01*
G01X456393Y247396D02*
X454444Y244775D01*
X454378Y244659D01*
G03X454353Y242376I2015J-1164D01*
G01X454378Y242334D01*
X454397Y242300D01*
G02X454378Y240759I-1384J-754D01*
G03X454353Y238476I2015J-1164D01*
G01X454378Y238434D01*
X454397Y238400D01*
G02X454378Y236859I-1384J-754D01*
G03Y234533I2015J-1163D01*
G02Y232959I-1365J-787D01*
G01X454353Y232917D01*
G03X454378Y230634I2040J-1119D01*
G01X454397Y230600D01*
G02X454378Y229059I-1384J-754D01*
G03X454353Y226776I2015J-1164D01*
G01X454378Y226734D01*
X454397Y226700D01*
G02X454378Y225159I-1384J-754D01*
G03X454353Y222876I2015J-1164D01*
G01X454378Y222834D01*
X454397Y222800D01*
G02X454378Y221259I-1384J-754D01*
G03X454353Y218976I2015J-1164D01*
G01X454378Y218934D01*
X454397Y218900D01*
G02X454378Y217359I-1384J-754D01*
G03X454353Y215076I2015J-1164D01*
G01X454378Y215034D01*
X454397Y215000D01*
G02X454378Y213459I-1384J-754D01*
G01X454210Y213168D01*
X454068Y213026D01*
Y210719D01*
X452938Y209589D01*
Y187823D01*
X453724Y187037D01*
Y186257D01*
X454284Y185697D01*
G01X456393Y255196D02*
X455094Y252197D01*
X455028Y252084D01*
G03X455009Y250543I1365J-787D01*
G01X455028Y250509D01*
G03X455663Y249899I1366J786D01*
G01X457212Y248819D01*
X457635Y248397D01*
X457758Y248184D01*
G02X457777Y246643I-1365J-787D01*
G01X457596Y246328D01*
X456818Y245640D01*
X455754Y244937D01*
G03X455009Y242743I639J-1441D01*
G01X455028Y242709D01*
X455053Y242667D01*
G02X455028Y240384I-2040J-1119D01*
G03X455009Y238843I1365J-787D01*
G01X455028Y238809D01*
X455053Y238767D01*
G02X455028Y236484I-2040J-1119D01*
G03X455009Y234943I1365J-787D01*
G01X455028Y234909D01*
G02X455053Y232626I-2015J-1164D01*
G01X455028Y232584D01*
G03Y231010I1365J-787D01*
G02Y228684I-2015J-1163D01*
G03X455009Y227143I1365J-787D01*
G01X455028Y227109D01*
X455053Y227067D01*
G02X455028Y224784I-2040J-1119D01*
G03X455009Y223243I1365J-787D01*
G01X455028Y223209D01*
X455053Y223167D01*
G02X455028Y220884I-2040J-1119D01*
G03X455009Y219343I1365J-787D01*
G01X455028Y219309D01*
X455053Y219267D01*
G02X455028Y216984I-2040J-1119D01*
G03X455009Y215443I1365J-787D01*
G01X455028Y215409D01*
X455053Y215367D01*
G02X455028Y213084I-2040J-1119D01*
G01X455026Y213085D01*
X454818Y212725D01*
Y210403D01*
X453688Y209273D01*
Y188204D01*
X456492Y185400D01*
G01X453013Y249347D02*
X451406Y247128D01*
G03X450998Y246609I1606J-1682D01*
G01X450973Y246567D01*
G03X450998Y244284I2040J-1119D01*
G02X451017Y242743I-1365J-787D01*
G01X450998Y242709D01*
X450973Y242667D01*
G03X450998Y240384I2040J-1119D01*
G02X451017Y238843I-1365J-787D01*
G01X450998Y238809D01*
X450973Y238767D01*
G03X450998Y236484I2040J-1119D01*
G02X451017Y234943I-1365J-787D01*
G01X450998Y234909D01*
G03X450973Y232626I2015J-1164D01*
G01X450998Y232584D01*
G02Y231010I-1365J-787D01*
G03Y228684I2015J-1163D01*
G02X451017Y227143I-1365J-787D01*
G01X450998Y227109D01*
X450973Y227067D01*
G03X450998Y224784I2040J-1119D01*
G02X451017Y223243I-1365J-787D01*
G01X450998Y223209D01*
X450973Y223167D01*
G03X450998Y220884I2040J-1119D01*
G02X451017Y219343I-1365J-787D01*
G01X450998Y219309D01*
X450973Y219267D01*
G03X450998Y216984I2040J-1119D01*
G02X451017Y215443I-1365J-787D01*
G01X450998Y215409D01*
X450973Y215367D01*
G03X450998Y213084I2040J-1119D01*
G02X451209Y212294I-1365J-788D01*
G01Y210968D01*
X449918Y209677D01*
Y186374D01*
X449392Y185848D01*
G01X454166Y248192D02*
X452415Y246905D01*
G03X451648Y244659I598J-1458D01*
G02X451673Y242376I-2015J-1164D01*
G01X451648Y242334D01*
X451629Y242300D01*
G03X451648Y240759I1384J-754D01*
G02X451673Y238476I-2015J-1164D01*
G01X451648Y238434D01*
X451629Y238400D01*
G03X451648Y236859I1384J-754D01*
G02Y234533I-2015J-1163D01*
G03Y232959I1365J-787D01*
G01X451673Y232917D01*
G02X451648Y230634I-2040J-1119D01*
G01X451629Y230600D01*
G03X451648Y229059I1384J-754D01*
G02X451673Y226776I-2015J-1164D01*
G01X451648Y226734D01*
X451629Y226700D01*
G03X451648Y225159I1384J-754D01*
G02X451673Y222876I-2015J-1164D01*
G01X451648Y222834D01*
X451629Y222800D01*
G03X451648Y221259I1384J-754D01*
G02X451673Y218976I-2015J-1164D01*
G01X451648Y218934D01*
X451629Y218900D01*
G03X451648Y217359I1384J-754D01*
G02X451673Y215076I-2015J-1164D01*
G01X451648Y215034D01*
X451629Y215000D01*
G03X451648Y213459I1384J-754D01*
G02X451960Y212294I-2015J-1164D01*
G01Y210658D01*
X450668Y209366D01*
Y186593D01*
X451592Y185669D01*
G01X458719Y212285D02*
Y202971D01*
X457048Y201300D01*
Y199908D01*
X457608Y198442D01*
Y190412D01*
X460863Y187157D01*
Y184142D01*
X461018Y183987D01*
Y183900D01*
G01X459773Y257147D02*
Y255816D01*
X460030Y255559D01*
G02X461788Y252084I-257J-2312D01*
G03X461769Y250543I1365J-787D01*
G01X461788Y250509D01*
X461813Y250467D01*
G02X461788Y248184I-2040J-1119D01*
G03X461769Y246643I1365J-787D01*
G01X461788Y246609D01*
X461813Y246567D01*
G02X461788Y244284I-2040J-1119D01*
G03X461769Y242743I1365J-787D01*
G01X461788Y242709D01*
X461813Y242667D01*
G02X461788Y240384I-2040J-1119D01*
G03X461769Y238843I1365J-787D01*
G01X461788Y238809D01*
X461813Y238767D01*
G02X461788Y236484I-2040J-1119D01*
G03X461769Y234943I1365J-787D01*
G01X461788Y234909D01*
G02X461813Y232626I-2015J-1164D01*
G01X461788Y232584D01*
G03Y231010I1365J-787D01*
G02Y228684I-2015J-1163D01*
G03X461769Y227143I1365J-787D01*
G01X461788Y227109D01*
X461813Y227067D01*
G02X461788Y224784I-2040J-1119D01*
G03X461769Y223243I1365J-787D01*
G01X461788Y223209D01*
X461813Y223167D01*
G02X461788Y220884I-2040J-1119D01*
G03X461769Y219343I1365J-787D01*
G01X461788Y219309D01*
X461813Y219267D01*
G02X461788Y216984I-2040J-1119D01*
G01X461787Y216983D01*
G03X461768Y215444I1366J-786D01*
G01X462226Y214650D01*
Y213108D01*
X461739Y212621D01*
Y201489D01*
X461204Y200954D01*
Y200246D01*
X460448Y198734D01*
Y194340D01*
X464664Y190124D01*
Y186155D01*
X464819Y186000D01*
Y185913D01*
G01X459773Y249347D02*
Y249339D01*
X459766Y249332D01*
G02X458408Y246234I-14719J4605D01*
G03X458247Y245055I1365J-787D01*
G02X457758Y242710I-3808J-429D01*
G03Y240384I2015J-1163D01*
G02X457777Y238843I-1365J-787D01*
G01X457758Y238809D01*
X457733Y238767D01*
G03X457758Y236484I2040J-1119D01*
G02X457777Y234943I-1365J-787D01*
G01X457758Y234909D01*
G03X457733Y232626I2015J-1164D01*
G01X457758Y232584D01*
G02Y231010I-1365J-787D01*
G03Y228684I2015J-1163D01*
G02X457777Y227143I-1365J-787D01*
G01X457758Y227109D01*
X457733Y227067D01*
G03X457758Y224784I2040J-1119D01*
G02X457777Y223243I-1365J-787D01*
G01X457758Y223209D01*
X457733Y223167D01*
G03X457758Y220884I2040J-1119D01*
G02X457777Y219343I-1365J-787D01*
G01X457758Y219309D01*
X457733Y219267D01*
G03X457758Y216984I2040J-1119D01*
G02X457777Y215443I-1365J-787D01*
G01X457758Y215409D01*
X457733Y215367D01*
G03X457758Y213084I2040J-1119D01*
G01X457759Y213083D01*
G02X457969Y212288I-1363J-785D01*
G01Y203282D01*
X456298Y201611D01*
Y199769D01*
X456858Y198303D01*
Y190101D01*
X460113Y186846D01*
Y184142D01*
X459958Y183987D01*
Y183900D01*
G01X459773Y253247D02*
Y254578D01*
X460001Y254806D01*
G02X461138Y252459I-228J-1559D01*
G03X461113Y250176I2015J-1164D01*
G01X461138Y250134D01*
X461157Y250100D01*
G02X461138Y248559I-1384J-754D01*
G03X461113Y246276I2015J-1164D01*
G01X461138Y246234D01*
X461157Y246200D01*
G02X461138Y244659I-1384J-754D01*
G03X461113Y242376I2015J-1164D01*
G01X461138Y242334D01*
X461157Y242300D01*
G02X461138Y240759I-1384J-754D01*
G03X461113Y238476I2015J-1164D01*
G01X461138Y238434D01*
X461157Y238400D01*
G02X461138Y236859I-1384J-754D01*
G03Y234533I2015J-1163D01*
G02Y232959I-1365J-787D01*
G01X461113Y232917D01*
G03X461138Y230634I2040J-1119D01*
G01X461157Y230600D01*
G02X461138Y229059I-1384J-754D01*
G03X461113Y226776I2015J-1164D01*
G01X461138Y226734D01*
X461157Y226700D01*
G02X461138Y225159I-1384J-754D01*
G03X461113Y222876I2015J-1164D01*
G01X461138Y222834D01*
X461157Y222800D01*
G02X461138Y221259I-1384J-754D01*
G03X461113Y218976I2015J-1164D01*
G01X461138Y218934D01*
X461157Y218900D01*
G02X461138Y217359I-1384J-754D01*
G03X461113Y215076I2015J-1164D01*
G01X461476Y214448D01*
Y213419D01*
X460989Y212932D01*
Y201800D01*
X460454Y201265D01*
Y200424D01*
X459698Y198912D01*
Y194029D01*
X463914Y189813D01*
Y186155D01*
X463759Y186000D01*
Y185913D01*
G01X437166Y210346D02*
G02X437478Y211509I2327J-1D01*
G01X437497Y211543D01*
G03X437478Y213084I-1384J754D01*
G02X437453Y215367I2015J1164D01*
G01X437478Y215409D01*
X437497Y215443D01*
G03X437478Y216984I-1384J754D01*
G02X437453Y219267I2015J1164D01*
G01X437478Y219309D01*
X437497Y219343D01*
G03X437478Y220884I-1384J754D01*
G02X437453Y223167I2015J1164D01*
G01X437478Y223209D01*
X437497Y223243D01*
G03X437478Y224784I-1384J754D01*
G02X437453Y227067I2015J1164D01*
G01X437478Y227109D01*
X437497Y227143D01*
G03X437478Y228684I-1384J754D01*
G02Y231010I2015J1163D01*
G03Y232584I-1365J787D01*
G01X437411Y232699D01*
X436113Y235696D01*
G01X466533Y249347D02*
X467687Y248681D01*
X467781Y248329D01*
G03X467873Y246276I2131J-933D01*
G01X467898Y246234D01*
G02X467917Y246200I-613J-365D01*
G02X467898Y244659I-1384J-754D01*
G03X467873Y242376I2015J-1164D01*
G01X467898Y242334D01*
X467917Y242300D01*
G02X467898Y240759I-1384J-754D01*
G03X467873Y238476I2015J-1164D01*
G01X467898Y238434D01*
X467917Y238400D01*
G02X467898Y236859I-1384J-754D01*
G03Y234533I2015J-1163D01*
G02Y232959I-1365J-787D01*
G01X467873Y232917D01*
G03X467898Y230634I2040J-1119D01*
G01X467917Y230600D01*
G02X467898Y229059I-1384J-754D01*
G03X467873Y226776I2015J-1164D01*
G01X467898Y226734D01*
X467917Y226700D01*
G02X467898Y225159I-1384J-754D01*
G03X467873Y222876I2015J-1164D01*
G01X467898Y222834D01*
X467917Y222800D01*
G02X467898Y221259I-1384J-754D01*
G03X467873Y218976I2015J-1164D01*
G01X467898Y218934D01*
X467917Y218900D01*
G02X467898Y217359I-1384J-754D01*
G01X467588Y216821D01*
Y208517D01*
X468160Y207945D01*
Y194121D01*
X473320Y188961D01*
Y187927D01*
X472448Y187055D01*
G01X466533Y253247D02*
X467431Y252039D01*
X468426Y250700D01*
G02X468548Y248184I-1893J-1353D01*
G03X468529Y246643I1365J-787D01*
G01X468548Y246609D01*
X468573Y246567D01*
G02X468548Y244284I-2040J-1119D01*
G03X468529Y242743I1365J-787D01*
G01X468548Y242709D01*
X468573Y242667D01*
G02X468548Y240384I-2040J-1119D01*
G03X468529Y238843I1365J-787D01*
G01X468548Y238809D01*
X468573Y238767D01*
G02X468548Y236484I-2040J-1119D01*
G03X468529Y234943I1365J-787D01*
G01X468548Y234909D01*
G02X468573Y232626I-2015J-1164D01*
G01X468548Y232584D01*
G03Y231010I1365J-787D01*
G02Y228684I-2015J-1163D01*
G03X468529Y227143I1365J-787D01*
G01X468548Y227109D01*
X468573Y227067D01*
G02X468548Y224784I-2040J-1119D01*
G03X468529Y223243I1365J-787D01*
G01X468548Y223209D01*
X468573Y223167D01*
G02X468548Y220884I-2040J-1119D01*
G03X468529Y219343I1365J-787D01*
G01X468548Y219309D01*
X468573Y219267D01*
G02X468548Y216984I-2040J-1119D01*
G01X468338Y216620D01*
Y208828D01*
X468910Y208256D01*
Y194432D01*
X474070Y189272D01*
Y187933D01*
X474948Y187055D01*
G01X463153Y247396D02*
X464307Y246731D01*
X464401Y246380D01*
G03X464518Y244284I2132J-932D01*
G02Y242710I-1365J-787D01*
G03X464493Y240427I2018J-1164D01*
G01X464518Y240385D01*
X464537Y240351D01*
G02X464518Y238810I-1384J-754D01*
G03X464493Y236527I2015J-1164D01*
G01X464518Y236485D01*
X464537Y236451D01*
G02X464518Y234910I-1384J-754D01*
G03X464493Y232627I2015J-1164D01*
G01X464518Y232585D01*
X464537Y232551D01*
G02X464518Y231010I-1384J-754D01*
G03X464493Y228727I2015J-1164D01*
G01X464518Y228685D01*
X464537Y228651D01*
G02X464518Y227110I-1384J-754D01*
G03Y224784I2015J-1163D01*
G02Y223208I-1365J-788D01*
G03Y220882I2015J-1163D01*
G02Y219306I-1365J-788D01*
G03X464493Y219267I272J-202D01*
G03X464518Y216984I2040J-1119D01*
G02X464729Y216196I-1366J-788D01*
G01Y214912D01*
X464009Y214192D01*
Y202424D01*
X465134Y201299D01*
Y192873D01*
X468322Y189685D01*
Y187929D01*
X467448Y187055D01*
G01X464705Y251027D02*
G03X465168Y248560I3741J-575D01*
G02Y246234I-2015J-1163D01*
G03Y244660I1365J-787D01*
G02Y242334I-2015J-1163D01*
G03X465149Y240794I1363J-787D01*
G01X465168Y240760D01*
X465193Y240718D01*
G02X465168Y238435I-2040J-1119D01*
G03X465149Y236894I1365J-787D01*
G01X465168Y236860D01*
X465193Y236818D01*
G02X465168Y234535I-2040J-1119D01*
G03X465149Y232994I1365J-787D01*
G01X465168Y232960D01*
X465193Y232918D01*
G02X465168Y230635I-2040J-1119D01*
G03X465149Y229094I1365J-787D01*
G01X465168Y229060D01*
X465193Y229018D01*
G02X465168Y226735I-2040J-1119D01*
G03Y225159I1365J-788D01*
G02Y222833I-2015J-1163D01*
G03Y221257I1365J-788D01*
G02Y218931I-2015J-1163D01*
G02X465149Y218900I-597J344D01*
G03X465168Y217359I1384J-754D01*
G02X465480Y216196I-2015J-1164D01*
G01Y214600D01*
X464759Y213879D01*
Y202744D01*
X465884Y201619D01*
Y193184D01*
X469072Y189996D01*
Y187931D01*
X469948Y187055D01*
G01X474709Y210266D02*
X474389Y211735D01*
G02X474657Y213459I2361J516D01*
G03X474676Y215000I-1365J787D01*
G01X474657Y215034D01*
X474632Y215076D01*
G02X474657Y217359I2040J1119D01*
G03X474676Y218900I-1365J787D01*
G01X474657Y218934D01*
X474632Y218976D01*
G02X474657Y221259I2040J1119D01*
G03X474676Y222800I-1365J787D01*
G01X474657Y222834D01*
X474632Y222876D01*
G02X474657Y225159I2040J1119D01*
G03X474676Y226700I-1365J787D01*
G01X474657Y226734D01*
X474632Y226776D01*
G02X474657Y229059I2040J1119D01*
G03X474676Y230600I-1365J787D01*
G01X474657Y230634D01*
G02X474632Y232917I2015J1164D01*
G01X474657Y232959D01*
G03Y234533I-1365J787D01*
G02Y236859I2015J1163D01*
G03X474676Y238400I-1365J787D01*
G01X474657Y238434D01*
X474632Y238476D01*
G02X474657Y240759I2040J1119D01*
G03Y242334I-1364J787D01*
G02Y244660I2015J1163D01*
G01X474673Y244688D01*
G02X476506Y247220I13166J-7602D01*
G01X476672Y247396D01*
G01X474709Y210266D02*
Y203200D01*
X477392Y200517D01*
Y197815D01*
X481592Y193615D01*
Y193300D01*
G01X476672Y255196D02*
X475598Y252749D01*
X475307Y252084D01*
G03X476068Y249842I1365J-787D01*
G02X477922Y248356I-1636J-3940D01*
G02X477246Y245930I-1250J-959D01*
G03X475307Y244284I1328J-3530D01*
G03Y242710I1365J-787D01*
G02Y240384I-2017J-1163D01*
G03X475288Y238843I1365J-787D01*
G01X475307Y238809D01*
X475332Y238767D01*
G02X475307Y236484I-2040J-1119D01*
G03X475288Y234943I1365J-787D01*
G01X475307Y234909D01*
G02X475332Y232626I-2015J-1164D01*
G01X475307Y232584D01*
G03Y231010I1365J-787D01*
G02Y228684I-2015J-1163D01*
G03X475288Y227143I1365J-787D01*
G01X475307Y227109D01*
X475332Y227067D01*
G02X475307Y224784I-2040J-1119D01*
G03X475288Y223243I1365J-787D01*
G01X475307Y223209D01*
X475332Y223167D01*
G02X475307Y220884I-2040J-1119D01*
G03X475288Y219343I1365J-787D01*
G01X475307Y219309D01*
X475332Y219267D01*
G02X475307Y216984I-2040J-1119D01*
G03X475288Y215443I1365J-787D01*
G01X475307Y215409D01*
X475332Y215367D01*
G02X475307Y213084I-2040J-1119D01*
G03X475213Y211632I1423J-821D01*
G01X475458Y211043D01*
Y203512D01*
X478192Y200778D01*
Y198696D01*
X478142Y198646D01*
Y198130D01*
X482072Y194200D01*
X483492D01*
G01X473292Y249347D02*
X473061Y249098D01*
G03X471293Y246638I11400J-10059D01*
G01X471277Y246610D01*
G03Y244284I2015J-1163D01*
G02Y242710I-1364J-787D01*
G03Y240383I2017J-1163D01*
G02Y238809I-1364J-787D01*
G01X471242Y238749D01*
G03X471277Y236483I2050J-1102D01*
G02Y234909I-1364J-787D01*
G03X471252Y232626I2015J-1164D01*
G01X471277Y232584D01*
G02Y231010I-1364J-787D01*
G01X471252Y230968D01*
G03X471277Y228683I2040J-1120D01*
G02Y227109I-1364J-787D01*
G01X471242Y227049D01*
G03X471277Y224783I2050J-1102D01*
G02Y223209I-1364J-787D01*
G01X471242Y223149D01*
G03X471277Y220883I2050J-1102D01*
G02Y219309I-1364J-787D01*
G01X471242Y219249D01*
G03X471277Y216983I2050J-1102D01*
G02Y215409I-1364J-787D01*
G01X471235Y215336D01*
G03X471277Y213082I2057J-1089D01*
G02X471488Y212294I-1364J-788D01*
G01Y207989D01*
X471690Y207787D01*
Y199145D01*
X479592Y191243D01*
Y189700D01*
X479792Y189500D01*
G01X473292Y253247D02*
X473950Y251600D01*
X474403Y250465D01*
G02X474230Y248081I-1111J-1118D01*
G01X474142Y247995D01*
X472757Y247116D01*
G03X471941Y246257I1306J-2058D01*
G01X471928Y246234D01*
G03Y244660I1364J-787D01*
G02Y242334I-2015J-1163D01*
G03Y240760I1364J-787D01*
G02X471963Y238494I-2015J-1164D01*
G01X471928Y238434D01*
G03Y236860I1364J-787D01*
G02X471953Y234575I-2015J-1165D01*
G01X471928Y234533D01*
G03Y232959I1364J-787D01*
G01X471953Y232917D01*
G02X471928Y230634I-2040J-1119D01*
G03Y229060I1364J-787D01*
G02X471963Y226794I-2015J-1164D01*
G01X471928Y226734D01*
G03Y225160I1364J-787D01*
G02X471963Y222894I-2015J-1164D01*
G01X471928Y222834D01*
G03Y221260I1364J-787D01*
G02X471963Y218994I-2015J-1164D01*
G01X471928Y218934D01*
G03Y217360I1364J-787D01*
G02X471963Y215094I-2015J-1164D01*
G01X471896Y214978D01*
G03X471928Y213459I1396J-730D01*
G02X472241Y212294I-2015J-1166D01*
G01Y208297D01*
X472440Y208098D01*
Y199456D01*
X480344Y191552D01*
Y191548D01*
X481142Y190750D01*
G01X458719Y212285D02*
G03X458409Y213458I-2323J14D01*
G01X458408Y213459D01*
G02X458389Y215000I1365J787D01*
G01X458408Y215034D01*
X458433Y215076D01*
G03X458408Y217359I-2040J1119D01*
G02X458389Y218900I1365J787D01*
G01X458408Y218934D01*
X458433Y218976D01*
G03X458408Y221259I-2040J1119D01*
G02X458389Y222800I1365J787D01*
G01X458408Y222834D01*
X458433Y222876D01*
G03X458408Y225159I-2040J1119D01*
G02X458389Y226700I1365J787D01*
G01X458408Y226734D01*
X458433Y226776D01*
G03X458408Y229059I-2040J1119D01*
G02X458389Y230600I1365J787D01*
G01X458408Y230634D01*
G03X458433Y232917I-2015J1164D01*
G01X458408Y232959D01*
G02Y234533I1365J787D01*
G03Y236859I-2015J1163D01*
G02X458389Y238400I1365J787D01*
G01X458408Y238434D01*
X458433Y238476D01*
G03X458408Y240759I-2040J1119D01*
G02Y242334I1366J787D01*
G03X459766Y245432I-13361J7703D01*
G01X459773Y245439D01*
Y245447D01*
G01X480052Y249347D02*
X480045Y249332D01*
G02X478687Y246234I-14719J4605D01*
G03X478526Y245055I1365J-787D01*
G02X478037Y242710I-3808J-429D01*
G03Y240384I2015J-1163D01*
G02X478056Y238843I-1365J-787D01*
G01X478037Y238809D01*
X478012Y238767D01*
G03X478037Y236484I2040J-1119D01*
G02X478056Y234943I-1365J-787D01*
G01X478037Y234909D01*
G03X478012Y232626I2015J-1164D01*
G01X478037Y232584D01*
G02Y231010I-1365J-787D01*
G03Y228684I2015J-1163D01*
G02X478056Y227143I-1365J-787D01*
G01X478037Y227109D01*
X478012Y227067D01*
G03X478037Y224784I2040J-1119D01*
G02X478056Y223243I-1365J-787D01*
G01X478037Y223209D01*
X478012Y223167D01*
G03X478037Y220884I2040J-1119D01*
G02X478056Y219343I-1365J-787D01*
G01X478037Y219309D01*
X478012Y219267D01*
G03X478037Y216984I2040J-1119D01*
G02X478056Y215443I-1365J-787D01*
G01X478037Y215409D01*
X478012Y215367D01*
G03X478037Y213084I2040J-1119D01*
G01X478038Y213083D01*
G02X477993Y211439I-1363J-785D01*
G01Y211438D01*
X477728Y211029D01*
Y204803D01*
X479842Y202689D01*
Y200149D01*
X482491Y197500D01*
X483712D01*
X485730Y195482D01*
Y195262D01*
X485792Y195200D01*
G01X521731Y255196D02*
G03X519721Y255558I-2404J-7588D01*
G03X518282Y255572I-895J-18049D01*
G03X516337Y254409I70J-2325D01*
G02X513607I-1365J787D01*
G03X511611Y255749I-2363J-1364D01*
G01X509074D01*
X507461Y257362D01*
X506734Y259117D01*
Y260591D01*
X506187Y261911D01*
X505482Y262616D01*
X504377D01*
X503243Y262147D01*
X502632Y261536D01*
X500590Y260690D01*
X499288Y259388D01*
X498697D01*
G03X498142Y259472I-623J-2241D01*
G01X498013D01*
G02X496707Y260259I59J1575D01*
G03X494777Y261421I-2015J-1163D01*
G01X493899D01*
X490792Y262708D01*
X489700Y263800D01*
X485908D01*
X483108Y266600D01*
X479500D01*
X477200Y268900D01*
X475458D01*
X473942Y270416D01*
X472642D01*
X471926Y269700D01*
X471300D01*
X470600Y269000D01*
X469000D01*
X460630Y277370D01*
Y278470D01*
G01X482265Y264565D02*
X484082D01*
X486031Y262616D01*
X489484D01*
X491429Y260671D01*
X494751D01*
G02X496057Y259884I-59J-1575D01*
G03X497987Y258722I2015J1163D01*
G01X498116D01*
G02X499437Y257934I-44J-1575D01*
G03X500181Y257504I744J429D01*
G01X502204D01*
X503564Y258864D01*
X505506D01*
X506261Y258109D01*
X506691Y257071D01*
X508763Y254999D01*
X511556D01*
G02X512957Y254034I-313J-1954D01*
G03X516987I2015J1162D01*
G02X519703Y254057I1365J-787D01*
G01X519716Y254034D01*
G03X521731Y251296I12362J6987D01*
G01X472100Y337800D02*
X472539Y338476D01*
G02X474328Y339421I1873J-1380D01*
G01X474413D01*
G03X475764Y340186I0J1575D01*
G01X475777Y340209D01*
G02X477722Y341372I2015J-1162D01*
G01X477851D01*
G03X479157Y342159I-59J1575D01*
G02X481087Y343321I2015J-1163D01*
G01X481216D01*
G03X482537Y344109I-44J1575D01*
G02X484482Y345272I2015J-1162D01*
G01X484611D01*
G03X485917Y346059I-59J1575D01*
G02X487847Y347221I2015J-1163D01*
G01X487976D01*
G03X489297Y348009I-44J1575D01*
G02X491242Y349172I2015J-1162D01*
G01X491371D01*
G03X492677Y349959I-59J1575D01*
G02X494607Y351121I2015J-1163D01*
G01X494736D01*
G03X496057Y351909I-44J1575D01*
G02X498002Y353072I2015J-1162D01*
G01X498131D01*
G03X499437Y353859I-59J1575D01*
G02X501367Y355021I2015J-1163D01*
G01X501496D01*
G03X502817Y355809I-44J1575D01*
G02X504762Y356972I2015J-1162D01*
G01X504891D01*
G03X506197Y357759I-59J1575D01*
G02X508127Y358921I2015J-1163D01*
G01X508256D01*
G03X509577Y359709I-44J1575D01*
G02X511522Y360872I2015J-1162D01*
G01X511651D01*
G03X512957Y361659I-59J1575D01*
G02X514887Y362821I2015J-1163D01*
G01X515016D01*
G03X516337Y363609I-44J1575D01*
G02X518282Y364772I2015J-1162D01*
G01X518352D01*
G03X519703Y365537I0J1575D01*
G01X519716Y365560D01*
G02X521633Y366721I2015J-1164D01*
G01X521775D01*
G03X523096Y367509I-44J1575D01*
G02X525041Y368672I2015J-1162D01*
G01X525170D01*
G03X526476Y369459I-59J1575D01*
G02X528440Y370622I2015J-1163D01*
G01X528535D01*
G03X529856Y371410I-44J1575D01*
G02X531786Y372572I2015J-1163D01*
G01X531942D01*
G03X533236Y373359I-71J1574D01*
G02X535181Y374522I2015J-1162D01*
G01X535322D01*
G03X536616Y375309I-71J1574D01*
G02X538580Y376472I2015J-1163D01*
G01X538690D01*
G03X539996Y377259I-59J1575D01*
G02X541926Y378421I2015J-1163D01*
G01X542055D01*
G03X543376Y379209I-44J1575D01*
G02X545321Y380372I2015J-1162D01*
G01X545450D01*
G03X546756Y381159I-59J1575D01*
G02X547093Y381607I2014J-1164D01*
G01Y393493D01*
G01X453013Y253247D02*
X453726Y251600D01*
X454245Y250400D01*
X454310Y250251D01*
X454397Y250100D01*
G02X454378Y248559I-1384J-754D01*
G01X454166Y248192D01*
G01X463153Y255196D02*
X464518Y252084D01*
G02X464705Y251027I-1365J-787D01*
G01X550500Y389400D02*
Y382900D01*
X549171Y381571D01*
X548712D01*
G03X547406Y380784I59J-1575D01*
G02X545476Y379622I-2015J1163D01*
G01X545347D01*
G03X544026Y378834I44J-1575D01*
G02X542081Y377671I-2015J1162D01*
G01X541952D01*
G03X540646Y376884I59J-1575D01*
G02X538682Y375721I-2015J1163D01*
G01X538587D01*
G03X537266Y374933I44J-1575D01*
G02X535336Y373771I-2015J1163D01*
G01X535180D01*
G03X533886Y372984I71J-1574D01*
G02X531941Y371821I-2015J1162D01*
G01X531800D01*
G03X530506Y371034I71J-1574D01*
G02X528542Y369871I-2015J1163D01*
G01X528432D01*
G03X527126Y369084I59J-1575D01*
G02X525196Y367922I-2015J1163D01*
G01X525067D01*
G03X523746Y367134I44J-1575D01*
G02X521801Y365971I-2015J1162D01*
G01X521731D01*
G03X520380Y365206I0J-1575D01*
G01X520367Y365183D01*
G02X518450Y364022I-2015J1164D01*
G01X518308D01*
G03X516987Y363234I44J-1575D01*
G02X515042Y362071I-2015J1162D01*
G01X514913D01*
G03X513607Y361284I59J-1575D01*
G02X511677Y360122I-2015J1163D01*
G01X511548D01*
G03X510227Y359334I44J-1575D01*
G02X508282Y358171I-2015J1162D01*
G01X508153D01*
G03X506847Y357384I59J-1575D01*
G02X504917Y356222I-2015J1163D01*
G01X504788D01*
G03X503467Y355434I44J-1575D01*
G02X501522Y354271I-2015J1162D01*
G01X501393D01*
G03X500087Y353484I59J-1575D01*
G02X498157Y352322I-2015J1163D01*
G01X498028D01*
G03X496707Y351534I44J-1575D01*
G02X494762Y350371I-2015J1162D01*
G01X494633D01*
G03X493327Y349584I59J-1575D01*
G02X491397Y348422I-2015J1163D01*
G01X491268D01*
G03X489947Y347634I44J-1575D01*
G02X488002Y346471I-2015J1162D01*
G01X487873D01*
G03X486567Y345684I59J-1575D01*
G02X484637Y344522I-2015J1163D01*
G01X484508D01*
G03X483187Y343734I44J-1575D01*
G02X481242Y342571I-2015J1162D01*
G01X481113D01*
G03X479807Y341784I59J-1575D01*
G02X477877Y340622I-2015J1163D01*
G01X477792D01*
G03X476441Y339857I0J-1575D01*
G01X476000Y339100D01*
Y336413D01*
X475087Y335500D01*
X472800D01*
G01X463800Y289500D02*
X463900Y289400D01*
Y287100D01*
X466359Y284641D01*
X471748D01*
X473129Y286022D01*
X477836D01*
G02X479157Y285234I-44J-1575D01*
G03X481102Y284071I2015J1162D01*
G01X481314D01*
X484552Y284447D01*
G01X427094Y364396D02*
X425145Y367018D01*
X425079Y367134D01*
G03X423758Y367922I-1365J-787D01*
G01X423714D01*
G02X421582Y369314I-4J2322D01*
G02X421699Y371410I2132J932D01*
G03Y372984I-1365J787D01*
G01X421674Y373026D01*
G02X421699Y375309I2040J1119D01*
G01X421718Y375343D01*
G03X421699Y376884I-1384J754D01*
G02X421674Y379167I2015J1164D01*
G01X421699Y379209D01*
X421718Y379243D01*
G03X421699Y380784I-1384J754D01*
G02X421674Y383067I2015J1164D01*
G01X421699Y383109D01*
X421718Y383143D01*
G03X421699Y384684I-1384J754D01*
G02X421674Y386967I2015J1164D01*
G01X421699Y387009D01*
X421718Y387043D01*
G03X421699Y388584I-1384J754D01*
G02X421674Y390867I2015J1164D01*
G01X421699Y390909D01*
X421718Y390943D01*
G03X421699Y392484I-1384J754D01*
G02X423701Y395974I2015J1163D01*
G01X423715Y395973D01*
X423743D01*
G03X425290Y397548I-28J1575D01*
G01Y408883D01*
X427248Y410841D01*
Y412357D01*
X426372Y413233D01*
G01X423714Y370247D02*
X422560Y369582D01*
X422250Y369666D01*
G02X422349Y371034I1464J582D01*
G03X422374Y373317I-2015J1164D01*
G01X422349Y373359D01*
G02Y374933I1365J787D01*
G03Y377259I-2015J1163D01*
G02X422330Y378800I1365J787D01*
G01X422349Y378834D01*
X422374Y378876D01*
G03X422349Y381159I-2040J1119D01*
G02X422330Y382700I1365J787D01*
G01X422349Y382734D01*
X422374Y382776D01*
G03X422349Y385059I-2040J1119D01*
G02X422330Y386600I1365J787D01*
G01X422349Y386634D01*
X422374Y386676D01*
G03X422349Y388959I-2040J1119D01*
G02X422330Y390500I1365J787D01*
G01X422349Y390534D01*
X422374Y390576D01*
G03X422349Y392859I-2040J1119D01*
G02X423670Y395222I1365J788D01*
G01X423714D01*
X423784Y395221D01*
G03X426043Y397548I-69J2327D01*
G01Y408572D01*
X427996Y410525D01*
Y412357D01*
X428872Y413233D01*
G01X437233Y366347D02*
Y367678D01*
X436977Y367934D01*
G02X435193Y371368I256J2313D01*
G01X435218Y371410D01*
G03Y372984I-1364J787D01*
G01X435193Y373026D01*
G02X435218Y375309I2040J1119D01*
G03Y376883I-1364J787D01*
G02X435183Y379149I2015J1164D01*
G01X435218Y379209D01*
G03Y380783I-1364J787D01*
G02X435183Y383049I2015J1164D01*
G01X435218Y383109D01*
G03Y384683I-1364J787D01*
G02X437163Y388172I2015J1163D01*
G01X437292D01*
G03X438598Y388959I-59J1575D01*
G02X440528Y390121I2015J-1163D01*
G01X440657D01*
G03X441978Y390909I-44J1575D01*
G02X443895Y392071I2015J-1162D01*
G01X444064D01*
G03X445358Y394432I-71J1574D01*
G02X445333Y396715I2015J1164D01*
G01X445358Y396757D01*
G03Y398331I-1365J787D01*
G02Y400657I2015J1163D01*
G03X445385Y402183I-1365J787D01*
G01X445316Y402304D01*
G02X445358Y404558I2057J1089D01*
G01X445673Y405102D01*
Y406200D01*
X444881Y406992D01*
G01X437233Y370247D02*
Y368916D01*
X437006Y368689D01*
G02X435869Y371034I227J1558D01*
G03X435894Y373317I-2017J1164D01*
G01X435869Y373359D01*
G02Y374933I1364J787D01*
G01X435894Y374975D01*
G03X435869Y377260I-2040J1120D01*
G02Y378834I1364J787D01*
G01X435904Y378894D01*
G03X435869Y381160I-2050J1102D01*
G02Y382734I1364J787D01*
G01X435904Y382794D01*
G03X435869Y385060I-2050J1102D01*
G02X437233Y387422I1364J787D01*
G01X437318D01*
G03X439248Y388584I-85J2325D01*
G02X440554Y389371I1365J-788D01*
G01X440683D01*
G03X442628Y390534I-70J2325D01*
G02X443922Y391321I1365J-787D01*
G01X444091D01*
G03X446008Y394808I-98J2324D01*
G02Y396382I1365J787D01*
G01X446033Y396424D01*
G03X446008Y398707I-2040J1119D01*
G01X445989Y398741D01*
G02X446008Y400282I1384J754D01*
G03X446033Y402565I-2015J1164D01*
G01X445974Y402666D01*
G02X446008Y404182I1399J727D01*
G01X446730Y405431D01*
X447015Y405716D01*
X448248D01*
X449023Y406491D01*
G01X423714Y358547D02*
Y359878D01*
X423458Y360134D01*
G02X421699Y363610I256J2313D01*
G03X420378Y365972I-1365J787D01*
G01X420249D01*
G02X418319Y369460I85J2325D01*
G03Y371034I-1365J787D01*
G02X418294Y373317I2015J1164D01*
G01X418319Y373359D01*
G03Y374933I-1365J787D01*
G02Y377259I2015J1163D01*
G03X418338Y378800I-1365J787D01*
G01X418319Y378834D01*
X418294Y378876D01*
G02X418319Y381159I2040J1119D01*
G03X418338Y382700I-1365J787D01*
G01X418319Y382734D01*
X418294Y382776D01*
G02X418319Y385059I2040J1119D01*
G03X418338Y386600I-1365J787D01*
G01X418319Y386634D01*
X418294Y386676D01*
G02X418319Y388959I2040J1119D01*
G03X418338Y390500I-1365J787D01*
G01X418319Y390534D01*
X418294Y390576D01*
G02X418319Y392859I2040J1119D01*
G03X418530Y393647I-1363J787D01*
G01Y395657D01*
X421372Y398499D01*
Y411038D01*
G01X423714Y366347D02*
G03X420419Y366722I-3295J-14289D01*
G01X420290D01*
G02X418969Y369084I44J1575D01*
G03Y371410I-2015J1163D01*
G02Y372984I1365J787D01*
G01X418994Y373026D01*
G03X418969Y375309I-2040J1119D01*
G01X418950Y375343D01*
G02X418969Y376884I1384J754D01*
G03X418994Y379167I-2015J1164D01*
G01X418969Y379209D01*
X418950Y379243D01*
G02X418969Y380784I1384J754D01*
G03X418994Y383067I-2015J1164D01*
G01X418969Y383109D01*
X418950Y383143D01*
G02X418969Y384684I1384J754D01*
G03X418994Y386967I-2015J1164D01*
G01X418969Y387009D01*
X418950Y387043D01*
G02X418969Y388584I1384J754D01*
G03X418994Y390867I-2015J1164D01*
G01X418969Y390909D01*
X418950Y390943D01*
G02X418969Y392484I1384J754D01*
G03X419281Y393647I-2015J1164D01*
G01Y395347D01*
X422139Y398205D01*
Y408914D01*
X423872Y410647D01*
G01X433854Y364396D02*
X431905Y367018D01*
X431839Y367134D01*
X431814Y367176D01*
G02X431839Y369459I2040J1119D01*
G03X431858Y371000I-1365J787D01*
G01X431839Y371034D01*
G02X431814Y373317I2015J1164D01*
G01X431839Y373359D01*
G03Y374933I-1365J787D01*
G02Y377259I2015J1163D01*
G03X431858Y378800I-1365J787D01*
G01X431839Y378834D01*
X431814Y378876D01*
G02X431839Y381159I2040J1119D01*
G03X431858Y382700I-1365J787D01*
G01X431839Y382734D01*
X431814Y382776D01*
G02X431839Y385059I2040J1119D01*
G03X431858Y386600I-1365J787D01*
G01X431839Y386634D01*
X431814Y386676D01*
G02X433769Y390121I2040J1120D01*
G01X433854D01*
G03X435205Y390886I0J1575D01*
G01X435218Y390909D01*
G02X437163Y392072I2015J-1162D01*
G01X437292D01*
G03X438598Y392859I-59J1575D01*
G02X440528Y394021I2015J-1163D01*
G01X440684D01*
G03X441978Y396382I-71J1574D01*
G01X441953Y396424D01*
G02X441978Y398707I2040J1119D01*
G03X441997Y400248I-1365J787D01*
G01X441978Y400282D01*
G02Y402608I2015J1163D01*
G01X441997Y402642D01*
G03X441978Y404084I-1293J704D01*
G01X441289Y405273D01*
X439921Y406641D01*
G01X433854Y372197D02*
X432523D01*
X432296Y372424D01*
G02X432401Y372802I1558J-229D01*
G02X432489Y372984I1093J-416D01*
G01X432514Y373026D01*
G03X432489Y375309I-2040J1119D01*
G02X432470Y375343I1184J684D01*
G02X432489Y376884I1384J754D01*
G03X432514Y379167I-2015J1164D01*
G01X432489Y379209D01*
X432470Y379243D01*
G02X432489Y380784I1384J754D01*
G03X432514Y383067I-2015J1164D01*
G01X432489Y383109D01*
X432470Y383143D01*
G02X432489Y384684I1384J754D01*
G03X432514Y386967I-2015J1164D01*
G01X432489Y387009D01*
X432470Y387043D01*
G02X433795Y389371I1384J753D01*
G01X433924D01*
G03X435869Y390534I-70J2325D01*
G01X435882Y390557D01*
G02X437233Y391322I1351J-810D01*
G01X437318D01*
G03X439248Y392484I-85J2325D01*
G02X440532Y393270I1365J-788D01*
G01X440698D01*
G03X442653Y396715I-85J2325D01*
G01X442628Y396757D01*
X442609Y396791D01*
G02X442628Y398332I1384J754D01*
G03Y400658I-2015J1163D01*
G02Y402232I1365J787D01*
G01X442653Y402274D01*
G03X442628Y404559I-2040J1120D01*
G01X442392Y404966D01*
X442381Y404977D01*
Y406641D01*
G01X443993Y354647D02*
X442044Y357268D01*
X441978Y357384D01*
G02X441953Y359667I2015J1164D01*
G01X441978Y359709D01*
X441997Y359743D01*
G03X441978Y361284I-1384J754D01*
G02X441953Y363567I2015J1164D01*
G01X441978Y363609D01*
X441997Y363643D01*
G03X441978Y365184I-1384J754D01*
G02X441953Y367467I2015J1164D01*
G01X441978Y367509D01*
X441997Y367543D01*
G03X441978Y369084I-1384J754D01*
G02Y371410I2015J1163D01*
G03Y372984I-1365J787D01*
G01X441953Y373026D01*
G02X441978Y375309I2040J1119D01*
G01X441997Y375343D01*
G03X441978Y376884I-1384J754D01*
G02X441953Y379167I2015J1164D01*
G01X441978Y379209D01*
X441997Y379243D01*
G03X441978Y380784I-1384J754D01*
G02X443923Y384272I2015J1163D01*
G01X444052D01*
G03X445358Y385059I-59J1575D01*
G02X447288Y386221I2015J-1163D01*
G01X447417D01*
G03X448738Y387009I-44J1575D01*
G02X450683Y388172I2015J-1162D01*
G01X450812D01*
G03X452118Y388959I-59J1575D01*
G02X454048Y390121I2015J-1163D01*
G01X454177D01*
G03X455498Y390909I-44J1575D01*
G02X457443Y392072I2015J-1162D01*
G01X457572D01*
G03X458905Y394385I-59J1575D01*
G01X458843Y394493D01*
G02X458878Y396759I2050J1102D01*
G03X458905Y398285I-1365J787D01*
G01X458843Y398393D01*
G02X458878Y400659I2050J1102D01*
G03X458905Y402185I-1365J787D01*
G01X458843Y402293D01*
G02X458878Y404559I2050J1102D01*
G03X458905Y406085I-1365J787D01*
G01X458843Y406193D01*
G02X458878Y408459I2050J1102D01*
G03X458905Y409985I-1365J787D01*
G01X458843Y410093D01*
G02X458878Y412359I2050J1102D01*
G03X458905Y413885I-1365J787D01*
G01X458843Y413993D01*
G02X458878Y416259I2050J1102D01*
G03X458384Y418360I-1365J788D01*
G01X457398Y419480D01*
X456473Y420405D01*
G01X443993Y362447D02*
X442694Y365446D01*
X442628Y365559D01*
G02X442609Y367100I1365J787D01*
G01X442628Y367134D01*
X442653Y367176D01*
G03X442628Y369459I-2040J1119D01*
G02X442609Y371000I1365J787D01*
G01X442628Y371034D01*
G03X442653Y373317I-2015J1164D01*
G01X442628Y373359D01*
G02Y374933I1365J787D01*
G03Y377259I-2015J1163D01*
G02X442609Y378800I1365J787D01*
G01X442628Y378834D01*
X442653Y378876D01*
G03X442628Y381159I-2040J1119D01*
G02X443949Y383522I1365J788D01*
G01X444078D01*
G03X446008Y384684I-85J2325D01*
G02X447314Y385471I1365J-788D01*
G01X447443D01*
G03X449388Y386634I-70J2325D01*
G02X450709Y387422I1365J-787D01*
G01X450838D01*
G03X452768Y388584I-85J2325D01*
G02X454074Y389371I1365J-788D01*
G01X454203D01*
G03X456148Y390534I-70J2325D01*
G02X457469Y391322I1365J-787D01*
G01X457598D01*
G03X459553Y394767I-85J2325D01*
G01X459528Y394809D01*
X459501Y394857D01*
G02X459528Y396383I1392J739D01*
G03X459563Y398649I-2015J1164D01*
G01X459501Y398757D01*
G02X459528Y400283I1392J739D01*
G03X459563Y402549I-2015J1164D01*
G01X459501Y402657D01*
G02X459528Y404183I1392J739D01*
G03X459563Y406449I-2015J1164D01*
G01X459501Y406557D01*
G02X459528Y408083I1392J739D01*
G03X459563Y410349I-2015J1164D01*
G01X459501Y410457D01*
G02X459528Y411983I1392J739D01*
G03X459563Y414249I-2015J1164D01*
G01X459528Y414309D01*
X459501Y414357D01*
G02X459528Y415883I1392J739D01*
G03X459563Y418149I-2015J1164D01*
G01X459528Y418209D01*
G03X459261Y418582I-2015J-1160D01*
G01X458973Y419509D01*
Y420405D01*
G01X474079Y419941D02*
X474846Y419174D01*
Y418817D01*
X472767Y416738D01*
G03X472373Y413976I1644J-1644D01*
G01X472398Y413934D01*
X472417Y413900D01*
G02X472398Y412359I-1384J-754D01*
G03X472373Y410076I2015J-1164D01*
G01X472398Y410034D01*
X472417Y410000D01*
G02X472398Y408459I-1384J-754D01*
G03X472373Y406176I2015J-1164D01*
G01X472398Y406134D01*
X472417Y406100D01*
G02X472398Y404559I-1384J-754D01*
G03X472373Y402276I2015J-1164D01*
G01X472398Y402234D01*
X472417Y402200D01*
G02X472398Y400659I-1384J-754D01*
G03X472373Y398376I2015J-1164D01*
G01X472398Y398334D01*
X472417Y398300D01*
G02X472398Y396759I-1384J-754D01*
G03X472373Y394476I2015J-1164D01*
G01X472398Y394434D01*
X472417Y394400D01*
G02X472398Y392859I-1384J-754D01*
G03X472373Y390576I2015J-1164D01*
G01X472398Y390534D01*
X472417Y390500D01*
G02X472398Y388959I-1384J-754D01*
G03X472373Y386676I2015J-1164D01*
G01X472398Y386634D01*
X472417Y386600D01*
G02X471092Y384272I-1384J-753D01*
G01X470963D01*
G03X469018Y383109I70J-2325D01*
G02X467697Y382321I-1365J787D01*
G01X467568D01*
G03X465638Y381159I85J-2325D01*
G02X464332Y380372I-1365J788D01*
G01X464203D01*
G03X462258Y379209I70J-2325D01*
G02X460937Y378421I-1365J787D01*
G01X460808D01*
G03X458878Y377259I85J-2325D01*
G02X457572Y376472I-1365J788D01*
G01X457462D01*
G03X455473Y373026I51J-2326D01*
G01X455498Y372984D01*
G02Y371410I-1365J-787D01*
G03Y369084I2015J-1163D01*
G02X455517Y367543I-1365J-787D01*
G01X455498Y367509D01*
X455473Y367467D01*
G03X455498Y365184I2040J-1119D01*
G02X454634Y362902I-1365J-788D01*
G03X452418Y360681I1117J-3330D01*
G03X452537Y358743I2468J-821D01*
G01X454133Y356596D01*
G01X476579Y419941D02*
X475596Y418958D01*
Y418507D01*
X473299Y416210D01*
G03X473029Y414343I1113J-1114D01*
G01X473048Y414309D01*
X473073Y414267D01*
G02X473048Y411984I-2040J-1119D01*
G03X473029Y410443I1365J-787D01*
G01X473048Y410409D01*
X473073Y410367D01*
G02X473048Y408084I-2040J-1119D01*
G03X473029Y406543I1365J-787D01*
G01X473048Y406509D01*
X473073Y406467D01*
G02X473048Y404184I-2040J-1119D01*
G03X473029Y402643I1365J-787D01*
G01X473048Y402609D01*
X473073Y402567D01*
G02X473048Y400284I-2040J-1119D01*
G03X473029Y398743I1365J-787D01*
G01X473048Y398709D01*
X473073Y398667D01*
G02X473048Y396384I-2040J-1119D01*
G03X473029Y394843I1365J-787D01*
G01X473048Y394809D01*
X473073Y394767D01*
G02X473048Y392484I-2040J-1119D01*
G03X473029Y390943I1365J-787D01*
G01X473048Y390909D01*
X473073Y390867D01*
G02X473048Y388584I-2040J-1119D01*
G03X473029Y387043I1365J-787D01*
G01X473048Y387009D01*
X473073Y386967D01*
G02X471118Y383522I-2040J-1120D01*
G01X470989D01*
G03X469668Y382734I44J-1575D01*
G02X467723Y381571I-2015J1162D01*
G01X467594D01*
G03X466288Y380784I59J-1575D01*
G02X464358Y379622I-2015J1163D01*
G01X464229D01*
G03X462908Y378834I44J-1575D01*
G02X460963Y377671I-2015J1162D01*
G01X460834D01*
G03X459528Y376884I59J-1575D01*
G02X457564Y375721I-2015J1163D01*
G01X457469D01*
G03X456148Y373359I44J-1575D01*
G01X456173Y373317D01*
G02X456148Y371034I-2040J-1119D01*
G01X456129Y371000D01*
G03X456148Y369459I1384J-754D01*
G02X456173Y367176I-2015J-1164D01*
G01X456148Y367134D01*
X456129Y367100D01*
G03X456148Y365559I1384J-754D01*
G02X456173Y363276I-2015J-1164D01*
G01X456148Y363234D01*
X456082Y363118D01*
X454133Y360496D01*
G01X440613Y356596D02*
X438664Y359218D01*
X438598Y359334D01*
X438573Y359376D01*
G02X438598Y361659I2040J1119D01*
G03X438617Y363200I-1365J787D01*
G01X438598Y363234D01*
X438573Y363276D01*
G02X438598Y365559I2040J1119D01*
G03X438617Y367100I-1365J787D01*
G01X438598Y367134D01*
X438573Y367176D01*
G02X438598Y369459I2040J1119D01*
G03X438617Y371000I-1365J787D01*
G01X438598Y371034D01*
G02X438573Y373317I2015J1164D01*
G01X438598Y373359D01*
G03Y374933I-1365J787D01*
G02Y377259I2015J1163D01*
G03X438617Y378800I-1365J787D01*
G01X438598Y378834D01*
X438573Y378876D01*
G02X438598Y381159I2040J1119D01*
G03X438617Y382700I-1365J787D01*
G01X438598Y382734D01*
X438573Y382776D01*
G02X440528Y386221I2040J1120D01*
G01X440657D01*
G03X441978Y387009I-44J1575D01*
G02X443923Y388172I2015J-1162D01*
G01X444052D01*
G03X445358Y388959I-59J1575D01*
G02X447288Y390121I2015J-1163D01*
G01X447417D01*
G03X448738Y390909I-44J1575D01*
G02X450683Y392072I2015J-1162D01*
G01X450812D01*
G03X452118Y392859I-59J1575D01*
G02X454048Y394021I2015J-1163D01*
G01X454177D01*
G03X455498Y396384I-44J1575D01*
G02X455473Y398667I2015J1164D01*
G01X455498Y398709D01*
X455517Y398743D01*
G03X455498Y400284I-1384J754D01*
G02X455473Y402567I2015J1164D01*
G01X455498Y402609D01*
X455517Y402643D01*
G03X455498Y404184I-1384J754D01*
G02X455473Y406467I2015J1164D01*
G01X455498Y406509D01*
X455517Y406543D01*
G03X455498Y408084I-1384J754D01*
G02X455473Y410367I2015J1164D01*
G01X455498Y410409D01*
X455517Y410443D01*
G03X455498Y411984I-1384J754D01*
G02X455186Y413147I2015J1164D01*
G01Y414103D01*
X452529Y416760D01*
Y418885D01*
X451473Y419941D01*
G01X440613Y360496D02*
X439316Y363492D01*
X439229Y363643D01*
G02X439248Y365184I1384J754D01*
G03X439273Y367467I-2015J1164D01*
G01X439248Y367509D01*
X439229Y367543D01*
G02X439248Y369084I1384J754D01*
G03Y371410I-2015J1163D01*
G02Y372984I1365J787D01*
G01X439273Y373026D01*
G03X439248Y375309I-2040J1119D01*
G01X439229Y375343D01*
G02X439248Y376884I1384J754D01*
G03X439273Y379167I-2015J1164D01*
G01X439248Y379209D01*
X439229Y379243D01*
G02X439248Y380784I1384J754D01*
G03X439273Y383067I-2015J1164D01*
G01X439248Y383109D01*
X439229Y383143D01*
G02X440554Y385471I1384J753D01*
G01X440683D01*
G03X442628Y386634I-70J2325D01*
G02X443949Y387422I1365J-787D01*
G01X444078D01*
G03X446008Y388584I-85J2325D01*
G02X447314Y389371I1365J-788D01*
G01X447443D01*
G03X449388Y390534I-70J2325D01*
G02X450709Y391322I1365J-787D01*
G01X450838D01*
G03X452768Y392484I-85J2325D01*
G02X454074Y393271I1365J-788D01*
G01X454203D01*
G03X456148Y396759I-70J2325D01*
G02X456129Y398300I1365J787D01*
G01X456148Y398334D01*
X456173Y398376D01*
G03X456148Y400659I-2040J1119D01*
G02X456129Y402200I1365J787D01*
G01X456148Y402234D01*
X456173Y402276D01*
G03X456148Y404559I-2040J1119D01*
G02X456129Y406100I1365J787D01*
G01X456148Y406134D01*
X456173Y406176D01*
G03X456148Y408459I-2040J1119D01*
G02X456129Y410000I1365J787D01*
G01X456148Y410034D01*
X456173Y410076D01*
G03X456148Y412359I-2040J1119D01*
G02X455937Y413147I1365J788D01*
G01Y414415D01*
X453279Y417073D01*
Y419247D01*
X454192Y420160D01*
G01X450753Y354647D02*
X449454Y357646D01*
X449388Y357759D01*
G02X449369Y359300I1365J787D01*
G01X449388Y359334D01*
X449413Y359376D01*
G03X449388Y361659I-2040J1119D01*
G02X449890Y363765I1365J787D01*
G03X450418Y364181I-2096J3203D01*
G02X451384Y364903I2026J-1703D01*
G03X452137Y367100I-631J1444D01*
G01X452118Y367134D01*
X452093Y367176D01*
G02X452118Y369459I2040J1119D01*
G03X452137Y371000I-1365J787D01*
G01X452118Y371034D01*
G02X452093Y373317I2015J1164D01*
G01X452118Y373359D01*
G03Y374933I-1365J787D01*
G02X454048Y378421I2015J1163D01*
G01X454177D01*
G03X455498Y379209I-44J1575D01*
G02X457443Y380372I2015J-1162D01*
G01X457572D01*
G03X458878Y381159I-59J1575D01*
G02X460808Y382321I2015J-1163D01*
G01X460937D01*
G03X462258Y383109I-44J1575D01*
G02X464203Y384272I2015J-1162D01*
G01X464332D01*
G03X465638Y385059I-59J1575D01*
G02X467568Y386221I2015J-1163D01*
G01X467697D01*
G03X469018Y388584I-44J1575D01*
G02X468993Y390867I2015J1164D01*
G01X469018Y390909D01*
X469037Y390943D01*
G03X469018Y392484I-1384J754D01*
G02X468993Y394767I2015J1164D01*
G01X469018Y394809D01*
X469037Y394843D01*
G03X469018Y396384I-1384J754D01*
G02X468993Y398667I2015J1164D01*
G01X469018Y398709D01*
X469037Y398743D01*
G03X469018Y400284I-1384J754D01*
G02X468993Y402567I2015J1164D01*
G01X469018Y402609D01*
X469037Y402643D01*
G03X469018Y404184I-1384J754D01*
G02X468993Y406467I2015J1164D01*
G01X469018Y406509D01*
X469037Y406543D01*
G03X469018Y408084I-1384J754D01*
G02X468993Y410367I2015J1164D01*
G01X469018Y410409D01*
X469037Y410443D01*
G03X469018Y411984I-1384J754D01*
G02X468993Y414267I2015J1164D01*
G01X469018Y414309D01*
X469037Y414343D01*
G03X469018Y415884I-1384J754D01*
G02X468706Y417047I2015J1164D01*
G01X471579Y421025D02*
X470698Y420144D01*
Y419128D01*
X469457Y417887D01*
Y417047D01*
G03X469668Y416259I1576J0D01*
G02X469693Y413976I-2015J-1164D01*
G01X469668Y413934D01*
X469649Y413900D01*
G03X469668Y412359I1384J-754D01*
G02X469693Y410076I-2015J-1164D01*
G01X469668Y410034D01*
X469649Y410000D01*
G03X469668Y408459I1384J-754D01*
G02X469693Y406176I-2015J-1164D01*
G01X469668Y406134D01*
X469649Y406100D01*
G03X469668Y404559I1384J-754D01*
G02X469693Y402276I-2015J-1164D01*
G01X469668Y402234D01*
X469649Y402200D01*
G03X469668Y400659I1384J-754D01*
G02X469693Y398376I-2015J-1164D01*
G01X469668Y398334D01*
X469649Y398300D01*
G03X469668Y396759I1384J-754D01*
G02X469693Y394476I-2015J-1164D01*
G01X469668Y394434D01*
X469649Y394400D01*
G03X469668Y392859I1384J-754D01*
G02X469693Y390576I-2015J-1164D01*
G01X469668Y390534D01*
X469649Y390500D01*
G03X469668Y388959I1384J-754D01*
G02X467723Y385471I-2015J-1163D01*
G01X467594D01*
G03X466288Y384684I59J-1575D01*
G02X464358Y383522I-2015J1163D01*
G01X464229D01*
G03X462908Y382734I44J-1575D01*
G02X460963Y381571I-2015J1162D01*
G01X460834D01*
G03X459528Y380784I59J-1575D01*
G02X457598Y379622I-2015J1163D01*
G01X457469D01*
G03X456148Y378834I44J-1575D01*
G02X454203Y377671I-2015J1162D01*
G01X454074D01*
G03X452749Y375343I59J-1575D01*
G01X452768Y375309D01*
G02X452793Y373026I-2015J-1164D01*
G01X452768Y372984D01*
G03Y371410I1365J-787D01*
G02Y369084I-2015J-1163D01*
G03X452749Y367543I1365J-787D01*
G01X452768Y367509D01*
X452793Y367467D01*
G02X452768Y365184I-2040J-1119D01*
G01X452702Y365068D01*
X450753Y362447D01*
G01X464273Y354647D02*
X462415Y357146D01*
X462324Y357268D01*
X462258Y357384D01*
G02X462233Y359667I2015J1164D01*
G01X462258Y359709D01*
X462277Y359743D01*
G03X462258Y361284I-1384J754D01*
G02X462233Y363567I2015J1164D01*
G01X462258Y363609D01*
X462277Y363643D01*
G03X462258Y365184I-1384J754D01*
G02X462233Y367467I2015J1164D01*
G01X462258Y367509D01*
X462277Y367543D01*
G03X462258Y369084I-1384J754D01*
G02X464188Y372572I2015J1163D01*
G01X464344D01*
G03X465638Y373359I-71J1574D01*
G02X467583Y374522I2015J-1162D01*
G01X467724D01*
G03X469018Y375309I-71J1574D01*
G02X470982Y376472I2015J-1163D01*
G01X471092D01*
G03X472398Y377259I-59J1575D01*
G02X474328Y378421I2015J-1163D01*
G01X474413D01*
G03X475764Y379186I0J1575D01*
G01X475777Y379209D01*
G02X477722Y380372I2015J-1162D01*
G01X477851D01*
G03X479157Y381159I-59J1575D01*
G02X481087Y382321I2015J-1163D01*
G01X481216D01*
G03X482537Y384684I-44J1575D01*
G02Y387012I2017J1164D01*
G03Y388584I-1362J786D01*
G02X482512Y390867I2015J1164D01*
G01X482537Y390909D01*
X482556Y390943D01*
G03X482537Y392484I-1384J754D01*
G02X482512Y394767I2015J1164D01*
G01X482537Y394809D01*
X482556Y394843D01*
G03X482537Y396384I-1384J754D01*
G02X482512Y398667I2015J1164D01*
G01X482537Y398709D01*
X482556Y398743D01*
G03X482537Y400284I-1384J754D01*
G02X482512Y402567I2015J1164D01*
G01X482537Y402609D01*
X482556Y402643D01*
G03X482537Y404184I-1384J754D01*
G02X484482Y407672I2015J1163D01*
G01X484611D01*
G03X485628Y408116I-57J1517D01*
G01X487057Y409545D01*
Y411732D01*
X486148Y412641D01*
G01X464273Y362447D02*
X462974Y365446D01*
X462908Y365559D01*
G02X462889Y367100I1365J787D01*
G01X462908Y367134D01*
X462933Y367176D01*
G03X462908Y369459I-2040J1119D01*
G02X464202Y371821I1365J788D01*
G01X464343D01*
G03X466288Y372984I-70J2325D01*
G02X467582Y373771I1365J-787D01*
G01X467738D01*
G03X469668Y374933I-85J2325D01*
G02X470989Y375721I1365J-787D01*
G01X471084D01*
G03X473048Y376884I-51J2326D01*
G02X474354Y377671I1365J-788D01*
G01X474483D01*
G03X476428Y378834I-70J2325D01*
G01X476441Y378857D01*
G02X477792Y379622I1351J-810D01*
G01X477877D01*
G03X479807Y380784I-85J2325D01*
G02X481113Y381571I1365J-788D01*
G01X481242D01*
G03X483187Y385059I-70J2325D01*
G02Y386636I1368J788D01*
G03Y388959I-2015J1161D01*
G02X483168Y390500I1365J787D01*
G01X483187Y390534D01*
X483212Y390576D01*
G03X483187Y392859I-2040J1119D01*
G02X483168Y394400I1365J787D01*
G01X483187Y394434D01*
X483212Y394476D01*
G03X483187Y396759I-2040J1119D01*
G02X483168Y398300I1365J787D01*
G01X483187Y398334D01*
X483212Y398376D01*
G03X483187Y400659I-2040J1119D01*
G02X483168Y402200I1365J787D01*
G01X483187Y402234D01*
X483212Y402276D01*
G03X483187Y404559I-2040J1119D01*
G02X484508Y406922I1365J788D01*
G01X484637D01*
G03X485989Y407417I-85J2325D01*
G01X487814Y409242D01*
Y413499D01*
X488648Y414333D01*
G01X474413Y356596D02*
X472464Y359218D01*
X472398Y359334D01*
X472373Y359376D01*
G02X474328Y362821I2040J1120D01*
G01X474413D01*
G03X475764Y363586I0J1575D01*
G01X475777Y363609D01*
G02X477722Y364772I2015J-1162D01*
G01X477851D01*
G03X479157Y365559I-59J1575D01*
G02X481087Y366721I2015J-1163D01*
G01X481216D01*
G03X482537Y367509I-44J1575D01*
G02X484482Y368672I2015J-1162D01*
G01X484611D01*
G03X485917Y369459I-59J1575D01*
G02X487881Y370622I2015J-1163D01*
G01X487976D01*
G03X489297Y371410I-44J1575D01*
G02X491227Y372572I2015J-1163D01*
G01X491383D01*
G03X492677Y373359I-71J1574D01*
G02X494622Y374522I2015J-1162D01*
G01X494763D01*
G03X496057Y376884I-71J1574D01*
G02X496032Y379167I2015J1164D01*
G01X496057Y379209D01*
G03Y380786I-1366J788D01*
G02Y383112I2015J1163D01*
G03Y384686I-1365J787D01*
G02Y387012I2015J1163D01*
G03Y388586I-1365J787D01*
G02X496076Y390943I2016J1162D01*
G03X496057Y392484I-1384J754D01*
G02Y394810I2015J1163D01*
G03Y396384I-1365J787D01*
G01X496032Y396426D01*
G02X497987Y399871I2040J1120D01*
G01X498116D01*
G03X499437Y400659I-44J1575D01*
G02X501382Y401822I2015J-1162D01*
G01X501877D01*
X502363Y402308D01*
Y404889D01*
X502951Y405477D01*
Y406743D01*
G01X474413Y360496D02*
X476364Y363121D01*
X476441Y363257D01*
G02X477792Y364022I1351J-810D01*
G01X477877D01*
G03X479807Y365184I-85J2325D01*
G02X481113Y365971I1365J-788D01*
G01X481242D01*
G03X483187Y367134I-70J2325D01*
G02X484508Y367922I1365J-787D01*
G01X484637D01*
G03X486567Y369084I-85J2325D01*
G02X487873Y369871I1365J-788D01*
G01X487983D01*
G03X489947Y371034I-51J2326D01*
G02X491241Y371821I1365J-787D01*
G01X491382D01*
G03X493327Y372984I-70J2325D01*
G02X494621Y373771I1365J-787D01*
G01X494777D01*
G03X496707Y377259I-85J2325D01*
G02X496688Y378800I1365J787D01*
G01X496707Y378834D01*
X496732Y378876D01*
G03X496707Y381162I-2046J1121D01*
G02Y382736I1365J787D01*
G03Y385062I-2015J1163D01*
G02Y386636I1365J787D01*
G03Y388962I-2015J1163D01*
G02Y390534I1362J786D01*
G01X496732Y390576D01*
G03X496707Y392859I-2040J1119D01*
G02X496688Y394400I1365J787D01*
G01X496707Y394434D01*
G03X496732Y396717I-2015J1164D01*
G01X496707Y396759D01*
G02X498028Y399121I1365J787D01*
G01X498142D01*
G03X500087Y400284I-70J2325D01*
G02X501408Y401072I1365J-787D01*
G01X502188D01*
X503113Y401997D01*
Y404578D01*
X503438Y404903D01*
X504791D01*
G01X460893Y356596D02*
X458944Y359218D01*
X458878Y359334D01*
X458853Y359376D01*
G02X458878Y361659I2040J1119D01*
G03X458897Y363200I-1365J787D01*
G01X458878Y363234D01*
X458853Y363276D01*
G02X458878Y365559I2040J1119D01*
G03X458897Y367100I-1365J787D01*
G01X458878Y367134D01*
X458853Y367176D01*
G02X458878Y369459I2040J1119D01*
G03X458897Y371000I-1365J787D01*
G01X458878Y371034D01*
G02X460823Y374522I2015J1163D01*
G01X460964D01*
G03X462258Y375309I-71J1574D01*
G02X464222Y376472I2015J-1163D01*
G01X464332D01*
G03X465638Y377259I-59J1575D01*
G02X467568Y378421I2015J-1163D01*
G01X467697D01*
G03X469018Y379209I-44J1575D01*
G02X470963Y380372I2015J-1162D01*
G01X471092D01*
G03X472398Y381159I-59J1575D01*
G02X474328Y382321I2015J-1163D01*
G01X474413D01*
G03X475764Y383086I0J1575D01*
G01X475777Y383109D01*
G02X477722Y384272I2015J-1162D01*
G01X477851D01*
G03X479157Y385062I-64J1580D01*
G03Y386636I-1365J787D01*
G02Y388962I2015J1163D01*
G03X479261Y389175I-1221J728D01*
G03X479176Y390500I-1469J571D01*
G01X479157Y390534D01*
X479132Y390576D01*
G02X479157Y392859I2040J1119D01*
G03X479176Y394400I-1365J787D01*
G01X479157Y394434D01*
X479132Y394476D01*
G02X479157Y396759I2040J1119D01*
G03X479176Y398300I-1365J787D01*
G01X479157Y398334D01*
X479132Y398376D01*
G02X479157Y400659I2040J1119D01*
G03X479176Y402200I-1365J787D01*
G01X479157Y402234D01*
X479132Y402276D01*
G02X479157Y404559I2040J1119D01*
G03X479176Y406100I-1365J787D01*
G01X479157Y406134D01*
X479132Y406176D01*
G02X481087Y409621I2040J1120D01*
G01X481216D01*
G03X482537Y411984I-44J1575D01*
G01X482092Y412429D01*
Y413643D01*
X481148Y414587D01*
G01X460893Y360496D02*
X459596Y363492D01*
X459509Y363643D01*
G02X459528Y365184I1384J754D01*
G03X459553Y367467I-2015J1164D01*
G01X459528Y367509D01*
X459509Y367543D01*
G02X459528Y369084I1384J754D01*
G03Y371410I-2015J1163D01*
G02X460822Y373771I1365J787D01*
G01X460978D01*
G03X462908Y374933I-85J2325D01*
G02X464229Y375721I1365J-787D01*
G01X464324D01*
G03X466288Y376884I-51J2326D01*
G02X467594Y377671I1365J-788D01*
G01X467723D01*
G03X469668Y378834I-70J2325D01*
G02X470989Y379622I1365J-787D01*
G01X471118D01*
G03X473048Y380784I-85J2325D01*
G02X474354Y381571I1365J-788D01*
G01X474483D01*
G03X476428Y382734I-70J2325D01*
G01X476441Y382757D01*
G02X477792Y383522I1351J-810D01*
G01X477877D01*
G03X479807Y384686I-89J2329D01*
G03Y387012I-2015J1163D01*
G02Y388586I1365J787D01*
G03X479881Y388723I-2430J1401D01*
G03X479832Y390867I-2089J1025D01*
G01X479807Y390909D01*
X479788Y390943D01*
G02X479807Y392484I1384J754D01*
G03X479832Y394767I-2015J1164D01*
G01X479807Y394809D01*
X479788Y394843D01*
G02X479807Y396384I1384J754D01*
G03X479832Y398667I-2015J1164D01*
G01X479807Y398709D01*
X479788Y398743D01*
G02X479807Y400284I1384J754D01*
G03X479832Y402567I-2015J1164D01*
G01X479807Y402609D01*
X479788Y402643D01*
G02X479807Y404184I1384J754D01*
G03X479832Y406467I-2015J1164D01*
G01X479807Y406509D01*
X479788Y406543D01*
G02X481113Y408871I1384J753D01*
G01X481242D01*
G03X483187Y412359I-70J2325D01*
G01X482880Y412891D01*
Y413819D01*
X483992Y414931D01*
G01X471033Y354647D02*
X469734Y357646D01*
X469668Y357759D01*
G02X469649Y359300I1365J787D01*
G01X469668Y359334D01*
X469693Y359376D01*
G03X469668Y361659I-2040J1119D01*
G02X470176Y363769I1365J787D01*
G03X470968Y364571I-1424J2198D01*
G02X471520Y364848I1186J-1675D01*
G03X472398Y365559I-487J1499D01*
G02X474328Y366721I2015J-1163D01*
G01X474413D01*
G03X475764Y367486I0J1575D01*
G01X475777Y367509D01*
G02X477722Y368672I2015J-1162D01*
G01X477851D01*
G03X479157Y369459I-59J1575D01*
G02X481121Y370622I2015J-1163D01*
G01X481216D01*
G03X482537Y371410I-44J1575D01*
G02X484467Y372572I2015J-1163D01*
G01X484623D01*
G03X485917Y373359I-71J1574D01*
G02X487862Y374522I2015J-1162D01*
G01X488003D01*
G03X489297Y375309I-71J1574D01*
G02X491242Y376473I2017J-1163D01*
G03X491383I70J1563D01*
G03X492677Y378835I-71J1574D01*
G02X492652Y381118I2015J1164D01*
G01X492677Y381160D01*
X492696Y381194D01*
G03X492677Y382736I-1384J754D01*
G02Y385062I2015J1163D01*
G03X492652Y386676I-1362J786D01*
G02X492677Y388959I2040J1119D01*
G03X492696Y390500I-1365J787D01*
G01X492677Y390534D01*
X492652Y390576D01*
G02X492677Y392859I2040J1119D01*
G03X492696Y394400I-1365J787D01*
G01X492677Y394434D01*
G02X492652Y396717I2015J1164D01*
G01X492677Y396759D01*
G03Y398333I-1365J787D01*
G02X494607Y401821I2015J1163D01*
G01X494736D01*
G03X496057Y402609I-44J1575D01*
G02X497987Y403771I2015J-1163D01*
G01X498731Y404515D01*
Y408515D01*
X499351Y409135D01*
Y410343D01*
G01X471033Y362447D02*
X472982Y365068D01*
X473048Y365184D01*
G02X474354Y365971I1365J-788D01*
G01X474483D01*
G03X476428Y367134I-70J2325D01*
G01X476441Y367157D01*
G02X477792Y367922I1351J-810D01*
G01X477877D01*
G03X479807Y369084I-85J2325D01*
G02X481113Y369871I1365J-788D01*
G01X481223D01*
G03X483187Y371034I-51J2326D01*
G02X484481Y371821I1365J-787D01*
G01X484622D01*
G03X486567Y372984I-70J2325D01*
G02X487861Y373771I1365J-787D01*
G01X488017D01*
G03X489947Y374933I-85J2325D01*
G02X491268Y375721I1365J-787D01*
G03X491397Y375722I47J2240D01*
G03X493327Y379210I-85J2325D01*
G02X493308Y380751I1365J787D01*
G01X493327Y380785D01*
X493352Y380827D01*
G03X493327Y383112I-2045J1120D01*
G02Y384686I1365J787D01*
G03Y387009I-2015J1161D01*
G01X493308Y387043D01*
G02X493327Y388584I1384J754D01*
G03X493352Y390867I-2015J1164D01*
G01X493327Y390909D01*
X493308Y390943D01*
G02X493327Y392484I1384J754D01*
G03Y394810I-2015J1163D01*
G02Y396384I1365J787D01*
G01X493352Y396426D01*
G03X493327Y398709I-2040J1119D01*
G01X493308Y398743D01*
G02X494633Y401071I1384J753D01*
G01X494777D01*
G03X496707Y402233I-85J2325D01*
G02X497665Y402968I1365J-787D01*
G01X497664D01*
G02X498014Y403021I409J-1522D01*
G01X498309Y403032D01*
X499481Y404204D01*
Y408204D01*
X499845Y408568D01*
X501126D01*
G01X430474Y366347D02*
Y365016D01*
X430246Y364788D01*
G02X429090Y367100I228J1559D01*
G01X429109Y367134D01*
X429134Y367176D01*
G03X427145Y370622I-2040J1120D01*
G01X427050D01*
G02X425729Y372984I44J1575D01*
G01X425754Y373026D01*
G03X425729Y375309I-2040J1119D01*
G01X425710Y375343D01*
G02X425729Y376884I1384J754D01*
G03X425754Y379167I-2015J1164D01*
G01X425729Y379209D01*
X425710Y379243D01*
G02X425729Y380784I1384J754D01*
G03X425754Y383067I-2015J1164D01*
G01X425729Y383109D01*
X425710Y383143D01*
G02X425729Y384684I1384J754D01*
G03X425754Y386967I-2015J1164D01*
G01X425729Y387009D01*
X425710Y387043D01*
G02X425729Y388584I1384J754D01*
G03X425754Y390867I-2015J1164D01*
G01X425729Y390909D01*
X425710Y390943D01*
G02X427075Y393272I1384J753D01*
G01X427145D01*
G03X429109Y394435I-51J2326D01*
G01X429753Y395549D01*
X432422Y398219D01*
Y412332D01*
X432577Y412487D01*
Y412574D01*
G01X447373Y356596D02*
Y355265D01*
X447145Y355037D01*
G02X446008Y357384I228J1559D01*
G03X446033Y359667I-2015J1164D01*
G01X446008Y359709D01*
X445989Y359743D01*
G02X446008Y361284I1384J754D01*
G03X446033Y363567I-2015J1164D01*
G01X446008Y363609D01*
X445989Y363643D01*
G02X446008Y365184I1384J754D01*
G03X446033Y367467I-2015J1164D01*
G01X446008Y367509D01*
X445989Y367543D01*
G02X446008Y369084I1384J754D01*
G03Y371410I-2015J1163D01*
G02Y372984I1365J787D01*
G01X446033Y373026D01*
G03X446008Y375309I-2040J1119D01*
G01X445989Y375343D01*
G02X446008Y376884I1384J754D01*
G03X446033Y379167I-2015J1164D01*
G01X446008Y379209D01*
X445989Y379243D01*
G02X447314Y381571I1384J753D01*
G01X447443D01*
G03X449388Y382734I-70J2325D01*
G02X450709Y383522I1365J-787D01*
G01X450838D01*
G03X452768Y384684I-85J2325D01*
G02X454074Y385471I1365J-788D01*
G01X454203D01*
G03X456148Y386634I-70J2325D01*
G02X457469Y387422I1365J-787D01*
G01X457598D01*
G03X459528Y388584I-85J2325D01*
G02X460834Y389371I1365J-788D01*
G01X460963D01*
G03X462908Y392858I-70J2325D01*
G02Y394432I1365J787D01*
G03X462933Y396715I-2015J1164D01*
G01X462908Y396757D01*
X462889Y396791D01*
G02X462908Y398332I1384J754D01*
G03Y400658I-2015J1163D01*
G02Y402232I1365J787D01*
G01X462933Y402274D01*
G03X462908Y404559I-2040J1120D01*
G02X462881Y406085I1365J787D01*
G01X462943Y406193D01*
G03X462908Y408459I-2050J1102D01*
G02X462881Y409985I1365J787D01*
G01X462943Y410093D01*
G03X462908Y412359I-2050J1102D01*
G02X462881Y413885I1365J787D01*
G01X462943Y413993D01*
G03X462909Y416258I-2050J1102D01*
G01X462908D01*
X462535Y416903D01*
Y421758D01*
X462690Y421913D01*
Y422000D01*
G01X467653Y356596D02*
Y355265D01*
X467425Y355037D01*
G02X466288Y357384I228J1559D01*
G03X466313Y359667I-2015J1164D01*
G01X466288Y359709D01*
X466269Y359743D01*
G02X466288Y361284I1384J754D01*
G03X466313Y363567I-2015J1164D01*
G01X466288Y363609D01*
X466269Y363643D01*
G02X466288Y365184I1384J754D01*
G03X466313Y367467I-2015J1164D01*
G01X466288Y367509D01*
X466269Y367543D01*
G02X467594Y369871I1384J753D01*
G01X467704D01*
G03X469668Y371034I-51J2326D01*
G02X470962Y371821I1365J-787D01*
G01X471103D01*
G03X473048Y372984I-70J2325D01*
G02X474342Y373771I1365J-787D01*
G01X474498D01*
G03X476428Y374933I-85J2325D01*
G01X476441Y374956D01*
G02X477792Y375721I1351J-810D01*
G01X477843D01*
G03X479807Y376884I-51J2326D01*
G02X481113Y377671I1365J-788D01*
G01X481242D01*
G03X483187Y378834I-70J2325D01*
G02X484508Y379622I1365J-787D01*
G01X484637D01*
G03X486592Y383067I-85J2325D01*
G01X486567Y383109D01*
X486548Y383143D01*
G02X486567Y384684I1384J754D01*
G03X486592Y386967I-2015J1164D01*
G01X486567Y387009D01*
X486548Y387043D01*
G02X486567Y388584I1384J754D01*
G03X486592Y390867I-2015J1164D01*
G01X486567Y390909D01*
X486548Y390943D01*
G02X486567Y392484I1384J754D01*
G03Y394810I-2015J1163D01*
G02Y396384I1365J787D01*
G03X486592Y398667I-2015J1164D01*
G01X486567Y398709D01*
X486548Y398743D01*
G02X486567Y400284I1384J754D01*
G03X486592Y402567I-2015J1164D01*
G01X486567Y402609D01*
X486548Y402643D01*
G02X487873Y404971I1384J753D01*
G01X488002D01*
G03X489947Y406134I-70J2325D01*
G02X491268Y406922I1365J-787D01*
G01X491553D01*
X492193Y407562D01*
Y411273D01*
X492348Y411428D01*
Y411515D01*
G01X430474Y370247D02*
G03X429747Y371772I-1963J0D01*
G01X429058Y372300D01*
G02X428459Y375309I1416J1846D01*
G01X428478Y375343D01*
G03X428459Y376884I-1384J754D01*
G02X428434Y379167I2015J1164D01*
G01X428459Y379209D01*
X428478Y379243D01*
G03X428459Y380784I-1384J754D01*
G02X428434Y383067I2015J1164D01*
G01X428459Y383109D01*
X428478Y383143D01*
G03X428459Y384684I-1384J754D01*
G02X428434Y386967I2015J1164D01*
G01X428459Y387009D01*
X428478Y387043D01*
G03X428459Y388584I-1384J754D01*
G02X430404Y392072I2015J1163D01*
G01X430533D01*
G03X431839Y392859I-59J1575D01*
G01X432531Y394058D01*
X435422Y396949D01*
Y412332D01*
X435267Y412487D01*
Y412574D01*
G01X447373Y364396D02*
G02X448739Y367511I14819J-4642D01*
G01X448738Y367510D01*
G03Y369084I-1365J787D01*
G02Y371410I2017J1163D01*
G03Y372984I-1365J787D01*
G01X448713Y373026D01*
G02X448738Y375309I2040J1119D01*
G01X448757Y375343D01*
G03X448738Y376884I-1384J754D01*
G02X450683Y380372I2015J1163D01*
G01X450812D01*
G03X452118Y381159I-59J1575D01*
G02X454048Y382321I2015J-1163D01*
G01X454177D01*
G03X455498Y383109I-44J1575D01*
G02X457443Y384272I2015J-1162D01*
G01X457572D01*
G03X458878Y385059I-59J1575D01*
G02X460808Y386221I2015J-1163D01*
G01X460937D01*
G03X462258Y387009I-44J1575D01*
G02X464203Y388172I2015J-1162D01*
G01X464332D01*
G03X465657Y390500I-59J1575D01*
G01X465638Y390534D01*
G02Y392858I2015J1162D01*
G01X465657Y392892D01*
G03X465638Y394433I-1384J754D01*
G02X465613Y396715I2018J1163D01*
G03X465759Y397020I-1349J833D01*
G03X465638Y398333I-1486J525D01*
G02X465613Y400615I2018J1163D01*
G03X465657Y400692I-1874J1122D01*
G03X465638Y402233I-1384J754D01*
G02Y404559I2015J1163D01*
G03X465657Y406100I-1365J787D01*
G01X465638Y406134D01*
X465613Y406176D01*
G02X465638Y408459I2040J1119D01*
G03X465657Y410000I-1365J787D01*
G01X465638Y410034D01*
X465613Y410076D01*
G02X465638Y412359I2040J1119D01*
G03X465657Y413900I-1365J787D01*
G01X465638Y413934D01*
X465613Y413976D01*
G02X465638Y416259I2040J1119D01*
G01X465848Y416623D01*
Y417837D01*
X465548Y418137D01*
Y421758D01*
X465393Y421913D01*
Y422000D01*
G01X467653Y364396D02*
G03X468722Y366618I-2692J2663D01*
G02X470963Y368672I2310J-271D01*
G01X471092D01*
G03X472398Y369459I-59J1575D01*
G02X474362Y370622I2015J-1163D01*
G01X474413D01*
G03X475764Y371387I0J1575D01*
G01X475777Y371410D01*
G02X477707Y372572I2015J-1163D01*
G01X477863D01*
G03X479157Y373359I-71J1574D01*
G02X481102Y374522I2015J-1162D01*
G01X481243D01*
G03X482537Y375309I-71J1574D01*
G02X484501Y376472I2015J-1163D01*
G01X484611D01*
G03X485917Y377259I-59J1575D01*
G02X487847Y378421I2015J-1163D01*
G01X487976D01*
G03X489297Y380784I-44J1575D01*
G02X489272Y383067I2015J1164D01*
G01X489297Y383109D01*
G03Y384686I-1366J788D01*
G02Y387012I2015J1163D01*
G03Y388584I-1362J786D01*
G02X489272Y390867I2015J1164D01*
G01X489297Y390909D01*
X489316Y390943D01*
G03X489297Y392484I-1384J754D01*
G02Y394810I2015J1163D01*
G03Y396384I-1365J787D01*
G01X489272Y396426D01*
G02X489297Y398709I2040J1119D01*
G01X489316Y398743D01*
G03X489297Y400284I-1384J754D01*
G02X491242Y403772I2015J1163D01*
G01X491371D01*
G03X492677Y404559I-59J1575D01*
G02X494605Y405721I2015J-1163D01*
G01X494733D01*
X495133Y406121D01*
Y410141D01*
X494978Y410296D01*
Y410383D01*
G01X430474Y362447D02*
Y363778D01*
X430218Y364034D01*
G02X428434Y367467I256J2313D01*
G01X428459Y367509D01*
X428478Y367543D01*
G03X427153Y369871I-1384J753D01*
G01X427043D01*
G02X425054Y373317I51J2326D01*
G01X425079Y373359D01*
G03Y374933I-1365J787D01*
G02Y377259I2015J1163D01*
G03X425098Y378800I-1365J787D01*
G01X425079Y378834D01*
X425054Y378876D01*
G02X425079Y381159I2040J1119D01*
G03X425098Y382700I-1365J787D01*
G01X425079Y382734D01*
X425054Y382776D01*
G02X425079Y385059I2040J1119D01*
G03X425098Y386600I-1365J787D01*
G01X425079Y386634D01*
X425054Y386676D01*
G02X425079Y388959I2040J1119D01*
G03X425098Y390500I-1365J787D01*
G01X425079Y390534D01*
X425054Y390576D01*
G02X427043Y394022I2040J1120D01*
G01X427113D01*
G03X428459Y394810I-19J1576D01*
G01X429151Y396009D01*
X431672Y398530D01*
Y412332D01*
X431517Y412487D01*
Y412574D01*
G01X447373Y352696D02*
Y354027D01*
X447116Y354284D01*
G02X445358Y357759I257J2312D01*
G03X445377Y359300I-1365J787D01*
G01X445358Y359334D01*
X445333Y359376D01*
G02X445358Y361659I2040J1119D01*
G03X445377Y363200I-1365J787D01*
G01X445358Y363234D01*
X445333Y363276D01*
G02X445358Y365559I2040J1119D01*
G03X445377Y367100I-1365J787D01*
G01X445358Y367134D01*
X445333Y367176D01*
G02X445358Y369459I2040J1119D01*
G03X445377Y371000I-1365J787D01*
G01X445358Y371034D01*
G02X445333Y373317I2015J1164D01*
G01X445358Y373359D01*
G03Y374933I-1365J787D01*
G02Y377259I2015J1163D01*
G03X445377Y378800I-1365J787D01*
G01X445358Y378834D01*
X445333Y378876D01*
G02X447288Y382321I2040J1120D01*
G01X447417D01*
G03X448738Y383109I-44J1575D01*
G02X450683Y384272I2015J-1162D01*
G01X450812D01*
G03X452118Y385059I-59J1575D01*
G02X454048Y386221I2015J-1163D01*
G01X454177D01*
G03X455498Y387009I-44J1575D01*
G02X457443Y388172I2015J-1162D01*
G01X457572D01*
G03X458878Y388959I-59J1575D01*
G02X460808Y390121I2015J-1163D01*
G01X460937D01*
G03X462258Y392483I-44J1575D01*
G01X462233Y392525D01*
G02X462258Y394808I2040J1119D01*
G03Y396382I-1365J787D01*
G01X462233Y396424D01*
G02X462258Y398707I2040J1119D01*
G03X462277Y400248I-1365J787D01*
G01X462258Y400282D01*
G02Y402608I2015J1163D01*
G01X462277Y402642D01*
G03X462258Y404183I-1384J754D01*
G02X462223Y406449I2015J1164D01*
G01X462285Y406557D01*
G03X462258Y408083I-1392J739D01*
G02X462223Y410349I2015J1164D01*
G01X462285Y410457D01*
G03X462258Y411983I-1392J739D01*
G02X462223Y414249I2015J1164D01*
G01X462230Y414258D01*
X462286Y414357D01*
G03X462281Y415843I-1393J738D01*
G01X461785Y416702D01*
Y421758D01*
X461630Y421913D01*
Y422000D01*
G01X467653Y352696D02*
Y354027D01*
X467396Y354284D01*
G02X465638Y357759I257J2312D01*
G03X465657Y359300I-1365J787D01*
G01X465638Y359334D01*
X465613Y359376D01*
G02X465638Y361659I2040J1119D01*
G03X465657Y363200I-1365J787D01*
G01X465638Y363234D01*
X465613Y363276D01*
G02X465638Y365559I2040J1119D01*
G03X465657Y367100I-1365J787D01*
G01X465638Y367134D01*
X465613Y367176D01*
G02X467602Y370622I2040J1120D01*
G01X467697D01*
G03X469018Y371410I-44J1575D01*
G02X470948Y372572I2015J-1163D01*
G01X471104D01*
G03X472398Y373359I-71J1574D01*
G02X474343Y374522I2015J-1162D01*
G01X474461D01*
G03X475777Y375309I-48J1574D01*
G02X477741Y376472I2015J-1163D01*
G01X477851D01*
G03X479157Y377259I-59J1575D01*
G02X481087Y378421I2015J-1163D01*
G01X481216D01*
G03X482537Y379209I-44J1575D01*
G02X484482Y380372I2015J-1162D01*
G01X484611D01*
G03X485936Y382700I-59J1575D01*
G01X485917Y382734D01*
X485892Y382776D01*
G02X485917Y385059I2040J1119D01*
G03X485936Y386600I-1365J787D01*
G01X485917Y386634D01*
X485892Y386676D01*
G02X485917Y388959I2040J1119D01*
G03X485936Y390500I-1365J787D01*
G01X485917Y390534D01*
X485892Y390576D01*
G02X485917Y392859I2040J1119D01*
G03X485936Y394400I-1365J787D01*
G01X485917Y394434D01*
G02Y396760I2015J1163D01*
G03Y398334I-1365J787D01*
G01X485892Y398376D01*
G02X485917Y400659I2040J1119D01*
G03X485936Y402200I-1365J787D01*
G01X485917Y402234D01*
X485892Y402276D01*
G02X487847Y405721I2040J1120D01*
G01X487976D01*
G03X489297Y406509I-44J1575D01*
G02X491242Y407672I2015J-1162D01*
G01X491443Y407873D01*
Y411273D01*
X491288Y411428D01*
Y411515D01*
G01X430474Y374146D02*
Y372815D01*
X430246Y372587D01*
G02X429515Y372896I228J1559D01*
G02X429109Y374933I959J1250D01*
G03Y377259I-2015J1163D01*
G02X429090Y378800I1365J787D01*
G01X429109Y378834D01*
X429134Y378876D01*
G03X429109Y381159I-2040J1119D01*
G02X429090Y382700I1365J787D01*
G01X429109Y382734D01*
X429134Y382776D01*
G03X429109Y385059I-2040J1119D01*
G02X429090Y386600I1365J787D01*
G01X429109Y386634D01*
X429134Y386676D01*
G03X429109Y388959I-2040J1119D01*
G02X430430Y391322I1365J788D01*
G01X430559D01*
G03X432489Y392484I-85J2325D01*
G01X433131Y393596D01*
X436172Y396637D01*
Y412332D01*
X436327Y412487D01*
Y412574D01*
G01X447373Y360496D02*
G02X448725Y363588I14866J-4659D01*
G01X448764Y363656D01*
G03X448922Y364691I-1390J742D01*
G02X449389Y367135I3748J551D01*
G01X449388Y367134D01*
G03X449413Y369417I-2015J1164D01*
G01X449388Y369459D01*
G02Y371034I1363J787D01*
G03X449413Y373317I-2015J1164D01*
G01X449388Y373359D01*
G02Y374933I1365J787D01*
G03Y377259I-2015J1163D01*
G02X450709Y379622I1365J788D01*
G01X450838D01*
G03X452768Y380784I-85J2325D01*
G02X454074Y381571I1365J-788D01*
G01X454203D01*
G03X456148Y382734I-70J2325D01*
G02X457469Y383522I1365J-787D01*
G01X457598D01*
G03X459528Y384684I-85J2325D01*
G02X460834Y385471I1365J-788D01*
G01X460963D01*
G03X462908Y386634I-70J2325D01*
G02X464229Y387422I1365J-787D01*
G01X464358D01*
G03X466313Y390867I-85J2325D01*
G01X466288Y390909D01*
G02Y392483I1365J787D01*
G01X466313Y392525D01*
G03X466288Y394808I-2040J1119D01*
G02Y396382I1365J787D01*
G03X466425Y396659I-1997J1160D01*
G03X466288Y398708I-2141J886D01*
G02Y400282I1365J787D01*
G03X466313Y400325I-850J523D01*
G03X466288Y402608I-2040J1119D01*
G02Y404184I1365J788D01*
G03X466313Y406467I-2015J1164D01*
G01X466288Y406509D01*
X466269Y406543D01*
G02X466288Y408084I1384J754D01*
G03X466313Y410367I-2015J1164D01*
G01X466288Y410409D01*
X466269Y410443D01*
G02X466288Y411984I1384J754D01*
G03X466313Y414267I-2015J1164D01*
G01X466288Y414309D01*
X466269Y414343D01*
G02X466288Y415884I1384J754D01*
G01X466598Y416422D01*
Y418148D01*
X466298Y418448D01*
Y421758D01*
X466453Y421913D01*
Y422000D01*
G01X467653Y360496D02*
G03X468709Y362559I-1754J2200D01*
G02X469018Y363609I2324J-113D01*
G02X469378Y364082I2016J-1161D01*
G03X469668Y365559I-954J954D01*
G02X470989Y367922I1366J787D01*
G01X471118D01*
G03X473048Y369084I-85J2325D01*
G02X474354Y369871I1365J-788D01*
G01X474464D01*
G03X476428Y371034I-51J2326D01*
G02X477744Y371821I1364J-787D01*
G01X477862D01*
G03X479807Y372984I-70J2325D01*
G02X481101Y373771I1365J-787D01*
G01X481257D01*
G03X483187Y374933I-85J2325D01*
G02X484508Y375721I1365J-787D01*
G01X484603D01*
G03X486567Y376884I-51J2326D01*
G02X487873Y377671I1365J-788D01*
G01X488002D01*
G03X489947Y381159I-70J2325D01*
G02X489928Y382700I1365J787D01*
G01X489947Y382734D01*
G03Y385062I-2020J1164D01*
G02Y386636I1366J787D01*
G03Y388959I-2015J1161D01*
G02X489928Y390500I1365J787D01*
G01X489947Y390534D01*
X489972Y390576D01*
G03X489947Y392859I-2040J1119D01*
G02X489928Y394400I1365J787D01*
G01X489947Y394434D01*
G03X489972Y396717I-2015J1164D01*
G01X489947Y396759D01*
G02Y398333I1365J787D01*
G03Y400659I-2015J1163D01*
G02X491268Y403022I1365J788D01*
G01X491397D01*
G03X493327Y404184I-85J2325D01*
G02X494633Y404971I1365J-788D01*
G01X495044D01*
G01X468706Y417047D02*
Y418199D01*
X469948Y419441D01*
Y420156D01*
X469079Y421025D01*
G01X756176Y-4300D02*
Y-2567D01*
G01Y4724D02*
X753924Y6976D01*
G01X545273Y208089D02*
X543376Y209184D01*
G03X542082Y209971I-1365J-787D01*
G01X541926D01*
G02X539996Y211133I85J2325D01*
G03X537266I-1365J-787D01*
G02X535336Y209971I-2015J1163D01*
G01X535166D01*
G02X533236Y211133I85J2325D01*
G03X530506I-1365J-787D01*
G02X528576Y209971I-2015J1163D01*
G01X528406D01*
G02X526476Y211133I85J2325D01*
G03X525155Y211921I-1365J-787D01*
G01X525060D01*
G02X523096Y213084I51J2326D01*
G03X521790Y213871I-1365J-788D01*
G01X521661D01*
G02X519716Y215034I70J2325D01*
G01X519703Y215057D01*
G03X518352Y215822I-1351J-810D01*
G01X518267D01*
G02X516337Y216984I85J2325D01*
G03X515031Y217771I-1365J-788D01*
G01X514902D01*
G02X512957Y221259I70J2325D01*
G03X512976Y222800I-1365J787D01*
G01X512957Y222834D01*
X512932Y222876D01*
G02X512957Y225159I2040J1119D01*
G03X512976Y226700I-1365J787D01*
G01X512957Y226734D01*
X512932Y226776D01*
G02X512957Y229059I2040J1119D01*
G03X512976Y230600I-1365J787D01*
G01X512957Y230634D01*
G02X512932Y232917I2015J1164D01*
G01X512957Y232959D01*
G03Y234533I-1365J787D01*
G02Y236859I2015J1163D01*
G03X512976Y238400I-1365J787D01*
G01X512957Y238434D01*
X512932Y238476D01*
G02X512957Y240759I2040J1119D01*
G03X512976Y242300I-1365J787D01*
G01X512957Y242334D01*
X512932Y242376D01*
G02X511592Y245447I11503J6847D01*
G01X486812Y249347D02*
X487966Y248681D01*
X488060Y248329D01*
G03X488152Y246276I2131J-933D01*
G01X488177Y246234D01*
G02X488362Y245844I-799J-618D01*
G02X488177Y244603I-1667J-386D01*
G03Y242388I1919J-1108D01*
G01X488268Y242230D01*
G02X488269Y240768I-1268J-732D01*
G01X488249Y240739D01*
G03X488152Y238476I1818J-1211D01*
G01X488177Y238434D01*
X488196Y238400D01*
G02X488177Y236859I-1384J-754D01*
G03Y234533I2015J-1163D01*
G02Y232959I-1365J-787D01*
G01X488152Y232917D01*
G03X488177Y230634I2040J-1119D01*
G01X488196Y230600D01*
G02X488177Y229059I-1384J-754D01*
G03X488152Y226776I2015J-1164D01*
G01X488177Y226734D01*
X488196Y226700D01*
G02X488177Y225159I-1384J-754D01*
G03X488152Y222876I2015J-1164D01*
G01X488177Y222834D01*
X488196Y222800D01*
G02X488177Y221259I-1384J-754D01*
G03X488152Y218976I2015J-1164D01*
G01X488177Y218934D01*
X488196Y218900D01*
G02X488177Y217359I-1384J-754D01*
G03X488152Y215076I2015J-1164D01*
G01X488177Y215034D01*
X488196Y215000D01*
G02X488177Y213459I-1384J-754D01*
G03X487960Y211638I2015J-1164D01*
G01X488818Y210780D01*
Y210089D01*
X493692Y205215D01*
Y204500D01*
G01X486812Y253247D02*
X487957Y251600D01*
X488387Y250981D01*
X488645Y250723D01*
G02X488827Y248127I-1833J-1433D01*
G03X488840Y246665I1249J-720D01*
G01X488868Y246618D01*
G02Y244298I-2010J-1160D01*
G01X488827Y244227D01*
G03X488792Y243085I1048J-604D01*
G01X488943Y242781D01*
G02X488870Y240233I-2423J-1206D01*
G01X488835Y240172D01*
G03X488827Y238809I1199J-689D01*
G01X488852Y238767D01*
G02X488827Y236484I-2040J-1119D01*
G03X488808Y234943I1365J-787D01*
G01X488827Y234909D01*
G02X488852Y232626I-2015J-1164D01*
G01X488827Y232584D01*
G03Y231010I1365J-787D01*
G02Y228684I-2015J-1163D01*
G03X488808Y227143I1365J-787D01*
G01X488827Y227109D01*
X488852Y227067D01*
G02X488827Y224784I-2040J-1119D01*
G03X488808Y223243I1365J-787D01*
G01X488827Y223209D01*
X488852Y223167D01*
G02X488827Y220884I-2040J-1119D01*
G03X488808Y219343I1365J-787D01*
G01X488827Y219309D01*
X488852Y219267D01*
G02X488827Y216984I-2040J-1119D01*
G03X488808Y215443I1365J-787D01*
G01X488827Y215409D01*
X488852Y215367D01*
G02X488827Y213084I-2040J-1119D01*
G03X488629Y212094I1365J-788D01*
G01X489568Y211155D01*
Y210400D01*
X494468Y205500D01*
X495392D01*
G01X483432Y247396D02*
X484586Y246731D01*
X484680Y246380D01*
G03X484797Y244284I2132J-932D01*
G02Y242710I-1365J-787D01*
G03Y240384I2017J-1163D01*
G02X484816Y238843I-1365J-787D01*
G01X484797Y238809D01*
X484772Y238767D01*
G03X484797Y236484I2040J-1119D01*
G02X484816Y234943I-1365J-787D01*
G01X484797Y234909D01*
G03X484772Y232626I2015J-1164D01*
G01X484797Y232584D01*
G02Y231010I-1365J-787D01*
G03Y228684I2015J-1163D01*
G02X484816Y227143I-1365J-787D01*
G01X484797Y227109D01*
X484772Y227067D01*
G03X484797Y224784I2040J-1119D01*
G02X484816Y223243I-1365J-787D01*
G01X484797Y223209D01*
X484772Y223167D01*
G03X484797Y220884I2040J-1119D01*
G02X484816Y219343I-1365J-787D01*
G01X484797Y219309D01*
X484772Y219267D01*
G03X484797Y216984I2040J-1119D01*
G02X484816Y215443I-1365J-787D01*
G01X484797Y215409D01*
X484772Y215367D01*
G03X484797Y213084I2040J-1119D01*
G02X484816Y211543I-1365J-787D01*
G03X484797Y209183I2000J-1196D01*
G03X485377Y208516I1996J1150D01*
G02X485964Y207311I-936J-1202D01*
G01Y206287D01*
X491801Y200450D01*
X491842D01*
G01X483432Y255196D02*
X484797Y252084D01*
G02X484984Y251027I-1365J-787D01*
G03X485447Y248560I3741J-575D01*
G02Y246234I-2015J-1163D01*
G03Y244660I1365J-787D01*
G02Y242334I-2015J-1163D01*
G03Y240759I1364J-787D01*
G02X485472Y238476I-2015J-1164D01*
G01X485447Y238434D01*
X485428Y238400D01*
G03X485447Y236859I1384J-754D01*
G02Y234533I-2015J-1163D01*
G03Y232959I1365J-787D01*
G01X485472Y232917D01*
G02X485447Y230634I-2040J-1119D01*
G01X485428Y230600D01*
G03X485447Y229059I1384J-754D01*
G02X485472Y226776I-2015J-1164D01*
G01X485447Y226734D01*
X485428Y226700D01*
G03X485447Y225159I1384J-754D01*
G02X485472Y222876I-2015J-1164D01*
G01X485447Y222834D01*
X485428Y222800D01*
G03X485447Y221259I1384J-754D01*
G02X485472Y218976I-2015J-1164D01*
G01X485447Y218934D01*
X485428Y218900D01*
G03X485447Y217359I1384J-754D01*
G02X485472Y215076I-2015J-1164D01*
G01X485447Y215034D01*
X485428Y215000D01*
G03X485447Y213459I1384J-754D01*
G02Y211133I-2015J-1163D01*
G03Y209558I1364J-788D01*
G01X485445Y209557D01*
G03X485842Y209103I1347J778D01*
G02X486718Y207311I-1374J-1782D01*
G01Y206600D01*
X490518Y202800D01*
X492592D01*
G01X480052Y245447D02*
X480045Y245432D01*
G02X478687Y242334I-14719J4605D01*
G03Y240759I1366J-787D01*
G02X478712Y238476I-2015J-1164D01*
G01X478687Y238434D01*
X478668Y238400D01*
G03X478687Y236859I1384J-754D01*
G02Y234533I-2015J-1163D01*
G03Y232959I1365J-787D01*
G01X478712Y232917D01*
G02X478687Y230634I-2040J-1119D01*
G01X478668Y230600D01*
G03X478687Y229059I1384J-754D01*
G02X478712Y226776I-2015J-1164D01*
G01X478687Y226734D01*
X478668Y226700D01*
G03X478687Y225159I1384J-754D01*
G02X478712Y222876I-2015J-1164D01*
G01X478687Y222834D01*
X478668Y222800D01*
G03X478687Y221259I1384J-754D01*
G02X478712Y218976I-2015J-1164D01*
G01X478687Y218934D01*
X478668Y218900D01*
G03X478687Y217359I1384J-754D01*
G02X478712Y215076I-2015J-1164D01*
G01X478687Y215034D01*
X478668Y215000D01*
G03X478687Y213459I1384J-754D01*
G02X478622Y211029I-2012J-1162D01*
G01X478478Y210807D01*
Y205114D01*
X480592Y203000D01*
Y200460D01*
X482802Y198250D01*
X484024D01*
X486262Y196012D01*
X486480D01*
X486542Y195950D01*
G01X480052Y257147D02*
Y255816D01*
X480309Y255559D01*
G02X482067Y252084I-257J-2312D01*
G03X482048Y250543I1365J-787D01*
G01X482067Y250509D01*
X482092Y250467D01*
G02X482067Y248184I-2040J-1119D01*
G03X482048Y246643I1365J-787D01*
G01X482067Y246609D01*
X482092Y246567D01*
G02X482067Y244284I-2040J-1119D01*
G03X482048Y242743I1365J-787D01*
G01X482067Y242709D01*
X482092Y242667D01*
G02X482067Y240384I-2040J-1119D01*
G03X482048Y238843I1365J-787D01*
G01X482067Y238809D01*
X482092Y238767D01*
G02X482067Y236484I-2040J-1119D01*
G03X482048Y234943I1365J-787D01*
G01X482067Y234909D01*
G02X482092Y232626I-2015J-1164D01*
G01X482067Y232584D01*
G03Y231010I1365J-787D01*
G02Y228684I-2015J-1163D01*
G03X482048Y227143I1365J-787D01*
G01X482067Y227109D01*
X482092Y227067D01*
G02X482067Y224784I-2040J-1119D01*
G03X482048Y223243I1365J-787D01*
G01X482067Y223209D01*
X482092Y223167D01*
G02X482067Y220884I-2040J-1119D01*
G03X482048Y219343I1365J-787D01*
G01X482067Y219309D01*
X482092Y219267D01*
G02X482067Y216984I-2040J-1119D01*
G03X482048Y215443I1365J-787D01*
G01X482067Y215409D01*
X482092Y215367D01*
G02X482067Y213084I-2040J-1119D01*
G03X482048Y211543I1365J-787D01*
G01X482647Y210505D01*
Y202706D01*
X484153Y201200D01*
X486774D01*
X487512Y200462D01*
X487730D01*
X487792Y200400D01*
G01X480052Y253247D02*
Y254578D01*
X480280Y254806D01*
G02X481417Y252459I-228J-1559D01*
G03X481392Y250176I2015J-1164D01*
G01X481417Y250134D01*
X481436Y250100D01*
G02X481417Y248559I-1384J-754D01*
G03X481392Y246276I2015J-1164D01*
G01X481417Y246234D01*
X481436Y246200D01*
G02X481417Y244659I-1384J-754D01*
G03X481392Y242376I2015J-1164D01*
G01X481417Y242334D01*
X481436Y242300D01*
G02X481417Y240759I-1384J-754D01*
G03X481392Y238476I2015J-1164D01*
G01X481417Y238434D01*
X481436Y238400D01*
G02X481417Y236859I-1384J-754D01*
G03Y234533I2015J-1163D01*
G02Y232959I-1365J-787D01*
G01X481392Y232917D01*
G03X481417Y230634I2040J-1119D01*
G01X481436Y230600D01*
G02X481417Y229059I-1384J-754D01*
G03X481392Y226776I2015J-1164D01*
G01X481417Y226734D01*
X481436Y226700D01*
G02X481417Y225159I-1384J-754D01*
G03X481392Y222876I2015J-1164D01*
G01X481417Y222834D01*
X481436Y222800D01*
G02X481417Y221259I-1384J-754D01*
G03X481392Y218976I2015J-1164D01*
G01X481417Y218934D01*
X481436Y218900D01*
G02X481417Y217359I-1384J-754D01*
G03X481392Y215076I2015J-1164D01*
G01X481417Y215034D01*
X481436Y215000D01*
G02X481417Y213459I-1384J-754D01*
G03Y211133I2015J-1163D01*
G01X481897Y210303D01*
Y202395D01*
X483842Y200450D01*
X486463D01*
X487042Y199871D01*
Y199650D01*
G01X543100Y206822D02*
X541967D01*
G02X540646Y207610I44J1575D01*
G03X538716Y208772I-2015J-1163D01*
G01X538546D01*
G03X536616Y207610I85J-2325D01*
G02X533886I-1365J787D01*
G03X531956Y208772I-2015J-1163D01*
G01X531786D01*
G03X529856Y207610I85J-2325D01*
G02X527126I-1365J787D01*
G03X525196Y208772I-2015J-1163D01*
G01X525040D01*
G02X523746Y209559I71J1574D01*
G03X521801Y210722I-2015J-1162D01*
G01X521683D01*
G02X520367Y211509I48J1574D01*
G03X518403Y212672I-2015J-1163D01*
G01X518293D01*
G02X516987Y213459I59J1575D01*
G03X515057Y214621I-2015J-1163D01*
G01X514928D01*
G02X513607Y215409I44J1575D01*
G03X511662Y216572I-2015J-1162D01*
G01X511533D01*
G02X510208Y218900I59J1575D01*
G01X510227Y218934D01*
X510252Y218976D01*
G03X510227Y221259I-2040J1119D01*
G02X510208Y222800I1365J787D01*
G01X510227Y222834D01*
X510252Y222876D01*
G03X510227Y225159I-2040J1119D01*
G02X510208Y226700I1365J787D01*
G01X510227Y226734D01*
X510252Y226776D01*
G03X510227Y229059I-2040J1119D01*
G02X510208Y230600I1365J787D01*
G01X510227Y230634D01*
G03X510252Y232917I-2015J1164D01*
G01X510227Y232959D01*
G02Y234533I1365J787D01*
G03Y236859I-2015J1163D01*
G02X510208Y238400I1365J787D01*
G01X510227Y238434D01*
X510252Y238476D01*
G03X510227Y240759I-2040J1119D01*
G02X510208Y242300I1365J787D01*
G01X510227Y242334D01*
X510252Y242376D01*
G03X510227Y244659I-2040J1119D01*
G02X510208Y246200I1365J787D01*
G01X510227Y246234D01*
X510252Y246276D01*
G03X510227Y248559I-2040J1119D01*
G02X509844Y250679I2757J1593D01*
G03X508979Y253000I-2445J410D01*
G01X670795Y89189D02*
X669596Y87990D01*
X667900D01*
G01X542341Y206059D02*
X542031D01*
G02X539996Y207234I0J2349D01*
G03X538702Y208021I-1365J-787D01*
G01X538560D01*
G03X537266Y207234I71J-1574D01*
G02X533236I-2015J1163D01*
G03X531942Y208021I-1365J-787D01*
G01X531800D01*
G03X530506Y207234I71J-1574D01*
G02X526476I-2015J1163D01*
G03X525182Y208021I-1365J-787D01*
G01X525041D01*
G02X523096Y209184I70J2325D01*
G03X521802Y209971I-1365J-787D01*
G01X521646D01*
G02X519716Y211133I85J2325D01*
G01X519703Y211156D01*
G03X518352Y211921I-1351J-810D01*
G01X518301D01*
G02X516337Y213084I51J2326D01*
G03X515031Y213871I-1365J-788D01*
G01X514902D01*
G02X512957Y215034I70J2325D01*
G03X511636Y215822I-1365J-787D01*
G01X511507D01*
G02X509552Y219267I85J2325D01*
G01X509577Y219309D01*
X509596Y219343D01*
G03X509577Y220884I-1384J754D01*
G02X509552Y223167I2015J1164D01*
G01X509577Y223209D01*
X509596Y223243D01*
G03X509577Y224784I-1384J754D01*
G02X509552Y227067I2015J1164D01*
G01X509577Y227109D01*
X509596Y227143D01*
G03X509577Y228684I-1384J754D01*
G02Y231010I2015J1163D01*
G03Y232584I-1365J787D01*
G01X509552Y232626D01*
G02X509577Y234909I2040J1119D01*
G01X509596Y234943D01*
G03X509577Y236484I-1384J754D01*
G02X509552Y238767I2015J1164D01*
G01X509577Y238809D01*
X509596Y238843D01*
G03X509577Y240384I-1384J754D01*
G02X509552Y242667I2015J1164D01*
G01X509577Y242709D01*
X509596Y242743D01*
G03X509577Y244284I-1384J754D01*
G02X509552Y246567I2015J1164D01*
G01X509577Y246609D01*
X509596Y246643D01*
G03X509577Y248184I-1384J754D01*
G02X508212Y251296I13451J7755D01*
G01X514972D02*
X515199Y251523D01*
X517529D01*
G02X518282Y251672I822J-2176D01*
G01X518422D01*
G02X520367Y250509I-70J-2325D01*
G01X520380Y250486D01*
G03X521731Y249721I1351J810D01*
G01X521775D01*
G03X523096Y250509I-44J1575D01*
G02X525041Y251672I2015J-1162D01*
G01X525181D01*
G02X527126Y250509I-70J-2325D01*
G03X528447Y249721I1365J787D01*
G01X528576D01*
G02X530506Y248559I-85J-2325D01*
G03X531812Y247772I1365J788D01*
G01X531930D01*
G03X533236Y248559I-59J1575D01*
G02X535166Y249721I2015J-1163D01*
G01X535295D01*
G03X536616Y250509I-44J1575D01*
G02X538561Y251672I2015J-1162D01*
G01X538690D01*
G03X539996Y252459I-59J1575D01*
G02X541926Y253621I2015J-1163D01*
G01X542055D01*
G03X543376Y254409I-44J1575D01*
G02X545321Y255572I2015J-1162D01*
G01X545450D01*
G03X546756Y256359I-59J1575D01*
G02X548686Y257521I2015J-1163D01*
G01X548815D01*
G03X550136Y258309I-44J1575D01*
G02X552081Y259472I2015J-1162D01*
G01X552210D01*
G03X553516Y260259I-59J1575D01*
G02X555446Y261421I2015J-1163D01*
G01X556269D01*
X556669Y261821D01*
X560051D01*
X560451Y261421D01*
G01X533006Y239294D02*
X532450D01*
G02X531956Y239222I-581J2253D01*
G01X531786D01*
G02X529856Y240384I85J2325D01*
G03X528550Y241171I-1365J-788D01*
G01X528421D01*
G02X526476Y242334I70J2325D01*
G03X525155Y243122I-1365J-787D01*
G01X525026D01*
G02X523096Y244284I85J2325D01*
G03X521790Y245071I-1365J-788D01*
G01X521661D01*
G02X518352Y245447I0J14748D01*
G01X531871Y257147D02*
G02X535166Y257521I3295J-14328D01*
G01X535295D01*
G03X536616Y258309I-44J1575D01*
G02X538561Y259472I2015J-1162D01*
G01X538690D01*
G03X539996Y260259I-59J1575D01*
G02X541926Y261421I2015J-1163D01*
G01X542055D01*
G03X543376Y262209I-44J1575D01*
G02X545321Y263372I2015J-1162D01*
G01X545450D01*
G03X546756Y264159I-59J1575D01*
G02X548686Y265321I2015J-1163D01*
G01X548815D01*
G03X550136Y266109I-44J1575D01*
G02X552081Y267272I2015J-1162D01*
G01X552210D01*
G03X553516Y268059I-59J1575D01*
G02X555446Y269221I2015J-1163D01*
G01X555575D01*
G03X556896Y270009I-44J1575D01*
G02X558841Y271172I2015J-1162D01*
G01X562471D01*
X563099Y271800D01*
X569625D01*
G01X528491Y255196D02*
G02X531652Y255024I890J-12780D01*
G03X533156Y255671I263J1460D01*
G02X535192Y256771I2036J-1334D01*
G01X535321D01*
G03X537266Y257934I-70J2325D01*
G02X538587Y258722I1365J-787D01*
G01X538716D01*
G03X540646Y259884I-85J2325D01*
G02X541952Y260671I1365J-788D01*
G01X542081D01*
G03X544026Y261834I-70J2325D01*
G02X545347Y262622I1365J-787D01*
G01X545476D01*
G03X547406Y263784I-85J2325D01*
G02X548712Y264571I1365J-788D01*
G01X548841D01*
G03X550786Y265734I-70J2325D01*
G02X552107Y266522I1365J-787D01*
G01X552236D01*
G03X554166Y267684I-85J2325D01*
G02X555472Y268471I1365J-788D01*
G01X555601D01*
G03X557546Y269634I-70J2325D01*
G02X558867Y270422I1365J-787D01*
G01X563222D01*
X563275Y270475D01*
X569500D01*
G01X516987Y250134D02*
G02X518308Y250922I1365J-787D01*
G01X518352D01*
G02X519703Y250157I0J-1575D01*
G01X519716Y250134D01*
G03X521661Y248971I2015J1162D01*
G01X521801D01*
G03X523746Y250134I-70J2325D01*
G02X525067Y250922I1365J-787D01*
G01X525155D01*
G02X526476Y250134I-44J-1575D01*
G03X528421Y248971I2015J1162D01*
G01X528550D01*
G02X529856Y248184I-59J-1575D01*
G03X531786Y247022I2015J1163D01*
G01X531956D01*
G03X533886Y248184I-85J2325D01*
G02X535192Y248971I1365J-788D01*
G01X535321D01*
G03X537266Y250134I-70J2325D01*
G02X538587Y250922I1365J-787D01*
G01X538716D01*
G03X540646Y252084I-85J2325D01*
G02X541952Y252871I1365J-788D01*
G01X542081D01*
G03X544026Y254034I-70J2325D01*
G02X545347Y254822I1365J-787D01*
G01X545476D01*
G03X547406Y255984I-85J2325D01*
G02X548712Y256771I1365J-788D01*
G01X548841D01*
G03X550786Y257934I-70J2325D01*
G02X552107Y258722I1365J-787D01*
G01X552236D01*
G03X554166Y259884I-85J2325D01*
G02X555472Y260671I1365J-788D01*
G01X559429D01*
X570700Y249400D01*
G01X554645Y285615D02*
X553516Y283659D01*
G02X552210Y282872I-1365J788D01*
G01X552081D01*
G03X550136Y281709I70J-2325D01*
G02X548815Y280921I-1365J787D01*
G01X548686D01*
G03X546756Y279759I85J-2325D01*
G02X545450Y278972I-1365J788D01*
G01X545340D01*
G03X543376Y277809I51J-2326D01*
G02X542055Y277021I-1365J787D01*
G01X541926D01*
G03X539996Y275859I85J-2325D01*
G02X538702Y275072I-1365J787D01*
G01X538561D01*
G03X536616Y273909I70J-2325D01*
G02X535295Y273121I-1365J787D01*
G01X535166D01*
G03X533236Y271959I85J-2325D01*
G02X531930Y271172I-1365J788D01*
G01X531801D01*
G03X529856Y270009I70J-2325D01*
G02X528535Y269221I-1365J787D01*
G01X528406D01*
G03X525111Y268847I0J-14702D01*
G01X518352Y241547D02*
G02X521959Y241155I-3510J-49084D01*
G02X523096Y240384I-228J-1560D01*
G03X525026Y239222I2015J1163D01*
G01X525155D01*
G02X526476Y238434I-44J-1575D01*
G02X526809Y237803I-8262J-4763D01*
G01X521731Y243496D02*
Y242165D01*
X521987Y241909D01*
G02X523746Y240759I-256J-2312D01*
G03X525052Y239972I1365J788D01*
G01X525181D01*
G02X527126Y238809I-70J-2325D01*
G03X528447Y238021I1365J787D01*
G01X528576D01*
G01X525111Y249347D02*
G02X527126Y246609I-11227J-10372D01*
G03X528447Y245821I1365J787D01*
G01X528576D01*
G02X530506Y244659I-85J-2325D01*
G03X531812Y243872I1365J788D01*
G01X531930D01*
G03X533236Y244659I-59J1575D01*
G02X535166Y245821I2015J-1163D01*
G01X535295D01*
G03X536616Y246609I-44J1575D01*
G02X538561Y247772I2015J-1162D01*
G01X538690D01*
G03X539996Y248559I-59J1575D01*
G02X541926Y249721I2015J-1163D01*
G01X542055D01*
G03X543376Y250509I-44J1575D01*
G02X545321Y251672I2015J-1162D01*
G01X545450D01*
G03X546756Y252459I-59J1575D01*
G02X548686Y253621I2015J-1163D01*
G01X548815D01*
G03X550136Y254409I-44J1575D01*
G02X552081Y255572I2015J-1162D01*
G01X552210D01*
G03X553516Y256359I-59J1575D01*
G02X553871Y256826I2015J-1163D01*
G01X556374D01*
X558100Y255100D01*
X559500D01*
X561500Y253100D01*
X563300D01*
X568300Y248100D01*
G01X537600Y243400D02*
X535929Y245071D01*
X535192D01*
G03X534417Y244833I60J-1575D01*
G03X533886Y244284I834J-1338D01*
G02X531956Y243122I-2015J1163D01*
G01X531786D01*
G02X529856Y244284I85J2325D01*
G03X528550Y245071I-1365J-788D01*
G01X528421D01*
G02X525111Y245447I0J14757D01*
G01X554963Y284094D02*
X554470Y283809D01*
X554166Y283284D01*
G02X552236Y282122I-2015J1163D01*
G01X552107D01*
G03X550786Y281334I44J-1575D01*
G02X548841Y280171I-2015J1162D01*
G01X548712D01*
G03X547406Y279384I59J-1575D01*
G02X545442Y278221I-2015J1163D01*
G01X545347D01*
G03X544026Y277433I44J-1575D01*
G02X542096Y276271I-2015J1163D01*
G01X541967D01*
G03X540646Y275483I44J-1575D01*
G02X538716Y274321I-2015J1163D01*
G01X538560D01*
G03X537266Y273534I71J-1574D01*
G02X535321Y272371I-2015J1162D01*
G01X535192D01*
G03X533886Y271584I59J-1575D01*
G02X531956Y270422I-2015J1163D01*
G01X531827D01*
G03X530506Y269634I44J-1575D01*
G02X528561Y268471I-2015J1162D01*
G01X528432D01*
G03X527126Y267684I59J-1575D01*
G02X525196Y266522I-2015J1163D01*
G01X525026D01*
X524202Y266502D01*
G01X533470Y241093D02*
G03X533236Y240759I1781J-1497D01*
G02X531930Y239972I-1365J788D01*
G01X531812D01*
G02X530506Y240759I59J1575D01*
G03X528576Y241921I-2015J-1163D01*
G01X528447D01*
G02X527126Y242709I44J1575D01*
G03X525181Y243872I-2015J-1162D01*
G01X525052D01*
G02X523746Y244659I59J1575D01*
G03X521816Y245821I-2015J-1163D01*
G01X521731D01*
G02X520380Y246586I0J1575D01*
G01X520367Y246609D01*
G03X518352Y249347I-12362J-6987D01*
G01X513857Y260881D02*
X515381D01*
X517122Y262622D01*
X518352D01*
G02X519703Y261857I0J-1575D01*
G01X519716Y261834D01*
G03X521661Y260671I2015J1162D01*
G01X521790D01*
G02X523096Y259884I-59J-1575D01*
G03X525026Y258722I2015J1163D01*
G01X525196D01*
G03X527126Y259884I-85J2325D01*
G02X528432Y260671I1365J-788D01*
G01X528561D01*
G03X530506Y261834I-70J2325D01*
G02X531827Y262622I1365J-787D01*
G01X531956D01*
G03X533886Y263784I-85J2325D01*
G02X535192Y264571I1365J-788D01*
G01X535321D01*
G03X537266Y265734I-70J2325D01*
G02X538587Y266522I1365J-787D01*
G01X538716D01*
G03X540646Y267684I-85J2325D01*
G02X541952Y268471I1365J-788D01*
G01X542081D01*
G03X544026Y269634I-70J2325D01*
G02X545347Y270422I1365J-787D01*
G01X545476D01*
G03X547406Y271584I-85J2325D01*
G02X548712Y272371I1365J-788D01*
G01X548841D01*
G03X550786Y273534I-70J2325D01*
G02X552080Y274321I1365J-787D01*
G01X552236D01*
G03X554166Y275483I-85J2325D01*
G02X555487Y276271I1365J-787D01*
G01X561001D01*
G01X572092Y359781D02*
X572031Y359720D01*
X571923D01*
X566287Y354084D01*
X563730D01*
X563176Y354171D01*
X563175D01*
X563135Y354227D01*
X562246Y354367D01*
G03X561083Y353495I345J-1671D01*
G02X559711Y352322I-2172J1152D01*
G01X558867D01*
G03X557546Y351534I44J-1575D01*
G02X555601Y350371I-2015J1162D01*
G01X555472D01*
G03X554166Y349584I59J-1575D01*
G02X552236Y348422I-2015J1163D01*
G01X552107D01*
G03X550786Y347634I44J-1575D01*
G02X548841Y346471I-2015J1162D01*
G01X548712D01*
G03X547406Y345684I59J-1575D01*
G02X545476Y344522I-2015J1163D01*
G01X545347D01*
G03X544026Y343734I44J-1575D01*
G02X542081Y342571I-2015J1162D01*
G01X541952D01*
G03X540646Y341784I59J-1575D01*
G02X538716Y340622I-2015J1163D01*
G01X538587D01*
G03X537266Y339834I44J-1575D01*
G02X535321Y338671I-2015J1162D01*
G01X535192D01*
G03X533886Y337884I59J-1575D01*
G02X531956Y336722I-2015J1163D01*
G01X531827D01*
G03X530506Y335934I44J-1575D01*
G02X528561Y334771I-2015J1162D01*
G01X528432D01*
G03X527126Y333984I59J-1575D01*
G02X525196Y332822I-2015J1163D01*
G01X525067D01*
G03X523746Y332034I44J-1575D01*
G02X521801Y330871I-2015J1162D01*
G01X521731D01*
G03X520380Y330106I0J-1575D01*
G01X520367Y330083D01*
G02X518450Y328922I-2015J1164D01*
G01X518308D01*
G03X516987Y328134I44J-1575D01*
G02X515042Y326971I-2015J1162D01*
G01X514913D01*
G03X513607Y326184I59J-1575D01*
G02X511643Y325021I-2015J1163D01*
G01X511548D01*
G03X510227Y322659I44J-1575D01*
G02X510252Y320376I-2015J-1164D01*
G01X510227Y320334D01*
X510208Y320300D01*
G03X510227Y318759I1384J-754D01*
G02X510252Y316476I-2015J-1164D01*
G01X510227Y316434D01*
X510208Y316400D01*
G03X510227Y314859I1384J-754D01*
G02X510252Y312576I-2015J-1164D01*
G01X510227Y312534D01*
G03X510128Y311166I1365J-786D01*
G01X510438Y311082D01*
X511592Y311747D01*
G01X571383Y360489D02*
X571322Y360428D01*
Y360322D01*
X565934Y354934D01*
X563797D01*
X563308Y355011D01*
X563252Y354969D01*
X562237Y355130D01*
G03X560419Y353848I355J-2433D01*
G02X559568Y353072I-1508J799D01*
G01X558841D01*
G03X556896Y351909I70J-2325D01*
G02X555575Y351121I-1365J787D01*
G01X555446D01*
G03X553516Y349959I85J-2325D01*
G02X552210Y349172I-1365J788D01*
G01X552081D01*
G03X550136Y348009I70J-2325D01*
G02X548815Y347221I-1365J787D01*
G01X548686D01*
G03X546756Y346059I85J-2325D01*
G02X545450Y345272I-1365J788D01*
G01X545321D01*
G03X543376Y344109I70J-2325D01*
G02X542055Y343321I-1365J787D01*
G01X541926D01*
G03X539996Y342159I85J-2325D01*
G02X538690Y341372I-1365J788D01*
G01X538561D01*
G03X536616Y340209I70J-2325D01*
G02X535295Y339421I-1365J787D01*
G01X535166D01*
G03X533236Y338259I85J-2325D01*
G02X531930Y337472I-1365J788D01*
G01X531801D01*
G03X529856Y336309I70J-2325D01*
G02X528535Y335521I-1365J787D01*
G01X528406D01*
G03X526476Y334359I85J-2325D01*
G02X525170Y333572I-1365J788D01*
G01X525041D01*
G03X523096Y332409I70J-2325D01*
G02X521775Y331621I-1365J787D01*
G01X521633D01*
G03X519716Y330460I98J-2325D01*
G01X519703Y330437D01*
G02X518352Y329672I-1351J810D01*
G01X518282D01*
G03X516337Y328509I70J-2325D01*
G02X515016Y327721I-1365J787D01*
G01X514887D01*
G03X512957Y326559I85J-2325D01*
G02X511651Y325772I-1365J788D01*
G01X511541D01*
G03X509577Y322283I51J-2326D01*
G02Y320709I-1365J-787D01*
G01X509552Y320667D01*
G03X509577Y318384I2040J-1119D01*
G02X509596Y316843I-1365J-787D01*
G01X509577Y316809D01*
X509552Y316767D01*
G03X509577Y314484I2040J-1119D01*
G02X509596Y312943I-1365J-787D01*
G01X509577Y312909D01*
X509552Y312867D01*
G03X509460Y310814I2039J-1120D01*
G01X509366Y310462D01*
X508212Y309797D01*
G01X491312Y323446D02*
G03X487888Y323821I-3424J-15444D01*
G02X486567Y324609I44J1575D01*
G01X486548Y324643D01*
G02X486567Y326184I1384J754D01*
G02X487873Y326971I1365J-788D01*
G01X488002D01*
G03X489947Y328134I-70J2325D01*
G02X491268Y328922I1365J-787D01*
G01X491397D01*
G03X493327Y330084I-85J2325D01*
G02X494633Y330871I1365J-788D01*
G01X494762D01*
G03X496707Y332034I-70J2325D01*
G02X498028Y332822I1365J-787D01*
G01X498157D01*
G03X500087Y333984I-85J2325D01*
G02X501393Y334771I1365J-788D01*
G01X501522D01*
G03X503467Y335934I-70J2325D01*
G02X504788Y336722I1365J-787D01*
G01X504917D01*
G03X506847Y337884I-85J2325D01*
G02X508153Y338671I1365J-788D01*
G01X508282D01*
G03X510227Y339834I-70J2325D01*
G02X511548Y340622I1365J-787D01*
G01X511677D01*
G03X513607Y341784I-85J2325D01*
G02X514913Y342571I1365J-788D01*
G01X515042D01*
G03X516987Y343734I-70J2325D01*
G02X518308Y344522I1365J-787D01*
G01X518450D01*
G03X520367Y345683I-98J2325D01*
G01X520380Y345706D01*
G02X521731Y346471I1351J-810D01*
G01X521801D01*
G03X523746Y347634I-70J2325D01*
G02X525067Y348422I1365J-787D01*
G01X525196D01*
G03X527126Y349584I-85J2325D01*
G02X528432Y350371I1365J-788D01*
G01X528561D01*
G03X530506Y351534I-70J2325D01*
G02X531827Y352322I1365J-787D01*
G01X531956D01*
G03X533886Y353484I-85J2325D01*
G02X535192Y354271I1365J-788D01*
G01X535321D01*
G03X537266Y355434I-70J2325D01*
G02X538587Y356222I1365J-787D01*
G01X538716D01*
G03X540646Y357384I-85J2325D01*
G02X541952Y358171I1365J-788D01*
G01X542081D01*
G03X544026Y359334I-70J2325D01*
G02X545347Y360122I1365J-787D01*
G01X545476D01*
G03X547406Y361284I-85J2325D01*
G02X548712Y362071I1365J-788D01*
G01X548841D01*
G03X550786Y363234I-70J2325D01*
G02X552107Y364022I1365J-787D01*
G01X554400D01*
G01X487932Y321496D02*
X486200Y323700D01*
X485917Y324233D01*
G03X484596Y325021I-1365J-787D01*
G01X484501D01*
G02X482420Y328280I51J2326D01*
G01X482636Y328715D01*
G03X482537Y330084I-1465J582D01*
G02X482512Y332367I2015J1164D01*
G01X482800Y332859D01*
Y336400D01*
X483600Y337200D01*
G01X560100Y372200D02*
X558429D01*
X557941Y371712D01*
G02X557703Y371046I-2410J486D01*
G01X557207Y370109D01*
X554400Y368410D01*
X553593Y367922D01*
X552107D01*
G03X550786Y367134I44J-1575D01*
G02X548841Y365971I-2015J1162D01*
G01X548712D01*
G03X547406Y365184I59J-1575D01*
G02X545476Y364022I-2015J1163D01*
G01X545347D01*
G03X544026Y363234I44J-1575D01*
G02X542081Y362071I-2015J1162D01*
G01X541952D01*
G03X540646Y361284I59J-1575D01*
G02X538716Y360122I-2015J1163D01*
G01X538587D01*
G03X537266Y359334I44J-1575D01*
G02X535321Y358171I-2015J1162D01*
G01X535192D01*
G03X533886Y357384I59J-1575D01*
G02X531956Y356222I-2015J1163D01*
G01X531827D01*
G03X530506Y355434I44J-1575D01*
G02X528561Y354271I-2015J1162D01*
G01X528432D01*
G03X527126Y353484I59J-1575D01*
G02X525196Y352322I-2015J1163D01*
G01X525067D01*
G03X523746Y351534I44J-1575D01*
G02X521801Y350371I-2015J1162D01*
G01X521731D01*
G03X520380Y349606I0J-1575D01*
G01X520367Y349583D01*
G02X518450Y348422I-2015J1164D01*
G01X518308D01*
G03X516987Y347634I44J-1575D01*
G02X515042Y346471I-2015J1162D01*
G01X514913D01*
G03X513607Y345684I59J-1575D01*
G02X511677Y344522I-2015J1163D01*
G01X511548D01*
G03X510227Y343734I44J-1575D01*
G02X508282Y342571I-2015J1162D01*
G01X508153D01*
G03X506847Y341784I59J-1575D01*
G02X504917Y340622I-2015J1163D01*
G01X504788D01*
G03X503467Y339834I44J-1575D01*
G02X501522Y338671I-2015J1162D01*
G01X501393D01*
G03X500087Y337884I59J-1575D01*
G02X498157Y336722I-2015J1163D01*
G01X498028D01*
G03X496707Y335934I44J-1575D01*
G02X494762Y334771I-2015J1162D01*
G01X494633D01*
G03X493327Y333984I59J-1575D01*
G02X491397Y332822I-2015J1163D01*
G01X491268D01*
G03X489947Y332034I44J-1575D01*
G02X488002Y330871I-2015J1162D01*
G01X487873D01*
G03X486356Y329300I59J-1575D01*
G01X484552Y327347D01*
G01X567100Y369400D02*
X557822Y360122D01*
X552107D01*
G03X550786Y359334I44J-1575D01*
G02X548841Y358171I-2015J1162D01*
G01X548712D01*
G03X547406Y357384I59J-1575D01*
G02X545476Y356222I-2015J1163D01*
G01X545347D01*
G03X544026Y355434I44J-1575D01*
G02X542081Y354271I-2015J1162D01*
G01X541952D01*
G03X540646Y353484I59J-1575D01*
G02X538716Y352322I-2015J1163D01*
G01X538587D01*
G03X537266Y351534I44J-1575D01*
G02X535321Y350371I-2015J1162D01*
G01X535192D01*
G03X533886Y349584I59J-1575D01*
G02X531956Y348422I-2015J1163D01*
G01X531827D01*
G03X530506Y347634I44J-1575D01*
G02X528561Y346471I-2015J1162D01*
G01X528432D01*
G03X527126Y345684I59J-1575D01*
G02X525196Y344522I-2015J1163D01*
G01X525067D01*
G03X523746Y343734I44J-1575D01*
G02X521801Y342571I-2015J1162D01*
G01X521731D01*
G03X520380Y341806I0J-1575D01*
G01X520367Y341783D01*
G02X518450Y340622I-2015J1164D01*
G01X518308D01*
G03X516987Y339834I44J-1575D01*
G02X515042Y338671I-2015J1162D01*
G01X514913D01*
G03X513607Y337884I59J-1575D01*
G02X511677Y336722I-2015J1163D01*
G01X511548D01*
G03X510227Y335934I44J-1575D01*
G02X508282Y334771I-2015J1162D01*
G01X508153D01*
G03X506847Y333984I59J-1575D01*
G02X504917Y332822I-2015J1163D01*
G01X504788D01*
G03X503467Y332034I44J-1575D01*
G02X501522Y330871I-2015J1162D01*
G01X501393D01*
G03X500087Y330084I59J-1575D01*
G02X498157Y328922I-2015J1163D01*
G01X498028D01*
G03X496707Y328134I44J-1575D01*
G02X494762Y326971I-2015J1162D01*
G01X494633D01*
G03X493327Y326184I59J-1575D01*
G02X491363Y325021I-2015J1163D01*
G01X491312D01*
G02X487932Y325396I0J15420D01*
G01X495044Y404971D02*
X495883Y405810D01*
Y410141D01*
X496038Y410296D01*
Y410383D01*
G01X909977Y261630D02*
X910731D01*
X912176Y260185D01*
X914157D01*
G02X916102Y259022I-70J-2325D01*
G03X918832I1365J787D01*
G02X920777Y260185I2015J-1162D01*
G01X920917D01*
G02X922862Y259022I-70J-2325D01*
G03X925592I1365J787D01*
G02X927537Y260185I2015J-1162D01*
G01X927666D01*
G03X928972Y260972I-59J1575D01*
G02X930902Y262134I2015J-1163D01*
G01X931031D01*
G03X932352Y262922I-44J1575D01*
G02X934297Y264085I2015J-1162D01*
G01X934426D01*
G03X935732Y264872I-59J1575D01*
G02X937662Y266034I2015J-1163D01*
G01X937791D01*
G03X939112Y266822I-44J1575D01*
G02X941057Y267985I2015J-1162D01*
G01X941197D01*
G02X943142Y266822I-70J-2325D01*
G03X944463Y266034I1365J787D01*
G01X944592D01*
G02X946522Y264872I-85J-2325D01*
G01X946771Y264445D01*
X947909Y261817D01*
X947887Y261760D01*
G01X909694Y259130D02*
X911626D01*
X911931Y259435D01*
X914131D01*
G02X915452Y258647I-44J-1575D01*
G03X917397Y257484I2015J1162D01*
G01X917537D01*
G03X919482Y258647I-70J2325D01*
G02X922212I1365J-787D01*
G03X924157Y257484I2015J1162D01*
G01X924297D01*
G03X926242Y258647I-70J2325D01*
G02X927563Y259435I1365J-787D01*
G01X927692D01*
G03X929622Y260597I-85J2325D01*
G02X930928Y261384I1365J-788D01*
G01X931057D01*
G03X933002Y262547I-70J2325D01*
G02X934323Y263335I1365J-787D01*
G01X934452D01*
G03X936382Y264497I-85J2325D01*
G02X937688Y265284I1365J-788D01*
G01X937817D01*
G03X939762Y266447I-70J2325D01*
G02X942492I1365J-787D01*
G03X944437Y265284I2015J1162D01*
G01X944566D01*
G02X945872Y264497I-59J-1575D01*
G01X946104Y264096D01*
X946161Y263348D01*
X946107Y262469D01*
X946362Y261362D01*
G03X947828Y260185I1525J398D01*
G01X948286D01*
X950451Y261158D01*
G02X951208Y261384I815J-1349D01*
G01X951326D01*
G02X952632Y260597I-59J-1575D01*
G01X952698Y260481D01*
X954647Y257860D01*
G01X908929Y266630D02*
X910813D01*
X911976Y265467D01*
Y265060D01*
X912951Y264085D01*
X914157D01*
G02X916102Y262922I-70J-2325D01*
G03X918832I1365J787D01*
G02X920777Y264085I2015J-1162D01*
G01X920917D01*
G02X922862Y262922I-70J-2325D01*
G03X925592I1365J787D01*
G02X927537Y264085I2015J-1162D01*
G01X927666D01*
G03X928972Y264872I-59J1575D01*
G02X930902Y266034I2015J-1163D01*
G01X931031D01*
G03X932352Y266822I-44J1575D01*
G02X934297Y267985I2015J-1162D01*
G01X934426D01*
G03X935732Y268772I-59J1575D01*
G02X937662Y269934I2015J-1163D01*
G01X937791D01*
G03X939112Y270722I-44J1575D01*
G02X941057Y271885I2015J-1162D01*
G01X941197D01*
G02X943142Y270722I-70J-2325D01*
G03X944463Y269934I1365J787D01*
G01X944592D01*
G02X946522Y268772I-85J-2325D01*
G03X947828Y267985I1365J788D01*
G01X947957D01*
G02X950065Y266480I-69J-2326D01*
G01X951267Y263709D01*
G01X909976Y264130D02*
X911014D01*
X911809Y263335D01*
X914131D01*
G02X915452Y262547I-44J-1575D01*
G03X917397Y261384I2015J1162D01*
G01X917537D01*
G03X919482Y262547I-70J2325D01*
G02X922212I1365J-787D01*
G03X924157Y261384I2015J1162D01*
G01X924297D01*
G03X926242Y262547I-70J2325D01*
G02X927563Y263335I1365J-787D01*
G01X927692D01*
G03X929622Y264497I-85J2325D01*
G02X930928Y265284I1365J-788D01*
G01X931057D01*
G03X933002Y266447I-70J2325D01*
G02X934323Y267235I1365J-787D01*
G01X934452D01*
G03X936382Y268397I-85J2325D01*
G02X937688Y269184I1365J-788D01*
G01X937817D01*
G03X939762Y270347I-70J2325D01*
G02X942492I1365J-787D01*
G03X944437Y269184I2015J1162D01*
G01X944566D01*
G02X945872Y268397I-59J-1575D01*
G03X947802Y267235I2015J1163D01*
G01X947931D01*
G02X949460Y265567I-44J-1575D01*
G01X949544Y264073D01*
X949748Y263189D01*
X949902Y262922D01*
G03X951223Y262134I1365J787D01*
G01X951413D01*
X954647Y261760D01*
G01X908400Y255380D02*
X908555Y255535D01*
X914131D01*
G02X915452Y254747I-44J-1575D01*
G03X917465Y253585I2011J1160D01*
G01X917470D01*
G03X919482Y254747I1J2322D01*
G02X920844Y255534I1362J-785D01*
G01X920850D01*
G02X922212Y254747I0J-1572D01*
G03X924225Y253585I2011J1160D01*
G01X924230D01*
G03X926242Y254747I1J2322D01*
G02X927563Y255535I1365J-787D01*
G01X927679D01*
G03X929622Y256697I-72J2325D01*
G02X930918Y257484I1365J-788D01*
G01X931041D01*
G03X933002Y258647I-54J2325D01*
G02X934310Y259435I1365J-787D01*
G01X934439D01*
G03X936382Y260597I-72J2325D01*
G02X937678Y261384I1365J-788D01*
G01X937801D01*
G03X939762Y262547I-54J2325D01*
G02X941126Y263335I1364J-786D01*
G01X941128D01*
G02X942491Y262547I0J-1574D01*
G03X942848Y262077I2016J1161D01*
G03X942959Y261973I1645J1645D01*
G01X942992Y261932D01*
X944507Y259809D01*
G01X908400Y256440D02*
X908555Y256285D01*
X914141D01*
G02X916102Y255122I-54J-2325D01*
G03X917464Y254335I1362J785D01*
G01X917470D01*
G03X918832Y255122I0J1572D01*
G02X920843Y256284I2011J-1160D01*
G01X920851D01*
G02X922862Y255122I0J-2322D01*
G03X924224Y254335I1362J785D01*
G01X924230D01*
G03X925592Y255122I0J1572D01*
G02X927553Y256285I2015J-1162D01*
G01X927666D01*
G03X928972Y257072I-59J1575D01*
G02X930902Y258234I2015J-1163D01*
G01X931031D01*
G03X932352Y259022I-44J1575D01*
G02X934297Y260185I2015J-1162D01*
G01X934426D01*
G03X935732Y260972I-59J1575D01*
G02X937662Y262134I2015J-1163D01*
G01X937791D01*
G03X939112Y262922I-44J1575D01*
G02X941125Y264085I2013J-1161D01*
G01X941129D01*
G02X943142Y262922I0J-2324D01*
G03X943383Y262604I1366J785D01*
G03X943500Y262497I1121J1108D01*
G01X944092Y261764D01*
G03X944566Y261384I764J467D01*
G02X945872Y260597I-59J-1575D01*
G01X945938Y260481D01*
X947887Y257860D01*
G01X1031800Y351400D02*
X1030286Y349886D01*
X1027914D01*
X1026620Y351180D01*
X1024230D01*
X1022935Y349885D01*
X1022175D01*
G03X1020230Y348722I70J-2325D01*
G02X1017500I-1365J787D01*
G03X1015555Y349885I-2015J-1162D01*
G01X1015415D01*
G03X1013470Y348722I70J-2325D01*
G02X1010740I-1365J787D01*
G03X1008795Y349885I-2015J-1162D01*
G01X1008655D01*
G03X1008218Y349816I51J-1740D01*
G01X1007274D01*
G01X954647Y339760D02*
X953350Y336764D01*
X953282Y336647D01*
G02X951337Y335484I-2015J1162D01*
G01X951208D01*
G03X949902Y334697I59J-1575D01*
G02X947972Y333535I-2015J1163D01*
G01X947843D01*
G03X946522Y332747I44J-1575D01*
G02X944577Y331584I-2015J1162D01*
G01X944448D01*
G03X943142Y330797I59J-1575D01*
G02X941212Y329635I-2015J1163D01*
G01X941042D01*
G02X939112Y330797I85J2325D01*
G03X937806Y331584I-1365J-788D01*
G01X937677D01*
G02X935732Y332747I70J2325D01*
G03X934411Y333535I-1365J-787D01*
G01X934282D01*
G02X932352Y334697I85J2325D01*
G03X931046Y335484I-1365J-788D01*
G01X930917D01*
G02X928972Y336647I70J2325D01*
G03X927651Y337435I-1365J-787D01*
G01X927522D01*
G02X925592Y338597I85J2325D01*
G03X924286Y339384I-1365J-788D01*
G01X924157D01*
G02X922212Y340547I70J2325D01*
G03X920891Y341335I-1365J-787D01*
G01X920762D01*
G02X918832Y342497I85J2325D01*
G03X917526Y343284I-1365J-788D01*
G01X917397D01*
G02X915452Y344447I70J2325D01*
G03X914131Y345235I-1365J-787D01*
G01X912300D01*
X910406Y343341D01*
X903409D01*
X902496Y342428D01*
G01X947887Y335860D02*
X945938Y333238D01*
X945872Y333122D01*
G02X944551Y332334I-1365J787D01*
G01X944422D01*
G03X942492Y331172I85J-2325D01*
G02X941186Y330385I-1365J788D01*
G01X941068D01*
G02X939762Y331172I59J1575D01*
G03X937832Y332334I-2015J-1163D01*
G01X937703D01*
G02X936382Y333122I44J1575D01*
G03X934437Y334285I-2015J-1162D01*
G01X934308D01*
G02X933002Y335072I59J1575D01*
G03X931072Y336234I-2015J-1163D01*
G01X930943D01*
G02X929622Y337022I44J1575D01*
G03X927677Y338185I-2015J-1162D01*
G01X927548D01*
G02X926242Y338972I59J1575D01*
G03X924312Y340134I-2015J-1163D01*
G01X924183D01*
G02X922862Y340922I44J1575D01*
G03X920917Y342085I-2015J-1162D01*
G01X920788D01*
G02X919482Y342872I59J1575D01*
G03X917552Y344034I-2015J-1163D01*
G01X917423D01*
G02X916102Y344822I44J1575D01*
G03X914141Y345985I-2015J-1162D01*
G01X911992D01*
X910096Y344089D01*
X903436D01*
X902597Y344928D01*
G01X954647Y335860D02*
X953350Y332864D01*
X953282Y332747D01*
G02X951337Y331584I-2015J1162D01*
G01X951208D01*
G03X949902Y330797I59J-1575D01*
G02X947972Y329635I-2015J1163D01*
G01X947843D01*
G03X946522Y328847I44J-1575D01*
G02X944577Y327684I-2015J1162D01*
G01X944436D01*
G03X943142Y326897I71J-1574D01*
G02X941212Y325735I-2015J1163D01*
G01X941042D01*
G02X939112Y326897I85J2325D01*
G03X937818Y327684I-1365J-787D01*
G01X937677D01*
G02X935732Y328847I70J2325D01*
G03X934411Y329635I-1365J-787D01*
G01X934282D01*
G02X932352Y330797I85J2325D01*
G03X931046Y331584I-1365J-788D01*
G01X930917D01*
G02X928972Y332747I70J2325D01*
G03X927651Y333535I-1365J-787D01*
G01X927522D01*
G02X925592Y334697I85J2325D01*
G03X924286Y335484I-1365J-788D01*
G01X924157D01*
G02X922212Y336647I70J2325D01*
G03X920891Y337435I-1365J-787D01*
G01X920762D01*
G02X918832Y338597I85J2325D01*
G03X917526Y339384I-1365J-788D01*
G01X917397D01*
G02X915452Y340547I70J2325D01*
G03X914131Y341335I-1365J-787D01*
G01X913050D01*
X912212Y340497D01*
Y339297D01*
X910954Y338039D01*
X906567D01*
X906006Y338600D01*
G01X951267Y333909D02*
X949318Y331288D01*
X949252Y331172D01*
G02X947946Y330385I-1365J788D01*
G01X947817D01*
G03X945872Y329222I70J-2325D01*
G02X944578Y328435I-1365J787D01*
G01X944422D01*
G03X942492Y327273I85J-2325D01*
G02X939762I-1365J787D01*
G03X937832Y328435I-2015J-1163D01*
G01X937676D01*
G02X936382Y329222I71J1574D01*
G03X934437Y330385I-2015J-1162D01*
G01X934308D01*
G02X933002Y331172I59J1575D01*
G03X931072Y332334I-2015J-1163D01*
G01X930943D01*
G02X929622Y333122I44J1575D01*
G03X927677Y334285I-2015J-1162D01*
G01X927548D01*
G02X926242Y335072I59J1575D01*
G03X924312Y336234I-2015J-1163D01*
G01X924183D01*
G02X922862Y337022I44J1575D01*
G03X920917Y338185I-2015J-1162D01*
G01X920788D01*
G02X919482Y338972I59J1575D01*
G03X917552Y340134I-2015J-1163D01*
G01X917423D01*
G02X916102Y340922I44J1575D01*
G03X914157Y342085I-2015J-1162D01*
G01X912739D01*
X911462Y340808D01*
Y339642D01*
X910609Y338789D01*
X908075D01*
X906364Y340500D01*
G01X951267Y341709D02*
X952421Y342375D01*
X952731Y342291D01*
G02X951311Y340134I-1465J-582D01*
G01X951182D01*
G03X949252Y338972I85J-2325D01*
G02X947946Y338185I-1365J788D01*
G01X947817D01*
G03X945872Y337022I70J-2325D01*
G02X944551Y336234I-1365J787D01*
G01X944422D01*
G03X942492Y335072I85J-2325D01*
G02X941186Y334285I-1365J788D01*
G01X941068D01*
G02X939762Y335072I59J1575D01*
G03X937832Y336234I-2015J-1163D01*
G01X937703D01*
G02X936382Y337022I44J1575D01*
G03X934437Y338185I-2015J-1162D01*
G01X934308D01*
G02X933002Y338972I59J1575D01*
G03X931072Y340134I-2015J-1163D01*
G01X930943D01*
G02X929622Y340922I44J1575D01*
G03X927677Y342085I-2015J-1162D01*
G01X927548D01*
G02X926242Y342872I59J1575D01*
G03X924312Y344034I-2015J-1163D01*
G01X924183D01*
G02X922862Y344822I44J1575D01*
G03X920917Y345985I-2015J-1162D01*
G01X920788D01*
G02X919482Y346772I59J1575D01*
G03X917552Y347934I-2015J-1163D01*
G01X917423D01*
G02X916102Y348722I44J1575D01*
G03X914141Y349885I-2015J-1162D01*
G01X912750D01*
X911549Y348684D01*
X907955D01*
X907800Y348839D01*
X907713D01*
G01X954647Y343660D02*
X953493Y342994D01*
X953399Y342642D01*
G02X951337Y339384I-2131J-933D01*
G01X951208D01*
G03X949902Y338597I59J-1575D01*
G02X947972Y337435I-2015J1163D01*
G01X947843D01*
G03X946522Y336647I44J-1575D01*
G02X944577Y335484I-2015J1162D01*
G01X944448D01*
G03X943142Y334697I59J-1575D01*
G02X941212Y333535I-2015J1163D01*
G01X941042D01*
G02X939112Y334697I85J2325D01*
G03X937806Y335484I-1365J-788D01*
G01X937677D01*
G02X935732Y336647I70J2325D01*
G03X934411Y337435I-1365J-787D01*
G01X934282D01*
G02X932352Y338597I85J2325D01*
G03X931046Y339384I-1365J-788D01*
G01X930917D01*
G02X928972Y340547I70J2325D01*
G03X927651Y341335I-1365J-787D01*
G01X927522D01*
G02X925592Y342497I85J2325D01*
G03X924286Y343284I-1365J-788D01*
G01X924157D01*
G02X922212Y344447I70J2325D01*
G03X920891Y345235I-1365J-787D01*
G01X920762D01*
G02X918832Y346397I85J2325D01*
G03X917526Y347184I-1365J-788D01*
G01X917397D01*
G02X915452Y348347I70J2325D01*
G03X914131Y349135I-1365J-787D01*
G01X913061D01*
X911860Y347934D01*
X907955D01*
X907800Y347779D01*
X907713D01*
G01X912436Y212333D02*
X913258Y211511D01*
X914086D01*
X921809Y219234D01*
X924271D01*
G03X925592Y220022I-44J1575D01*
G02X927537Y221185I2015J-1162D01*
G01X927666D01*
G03X928972Y221972I-59J1575D01*
G02X930902Y223134I2015J-1163D01*
G01X931031D01*
G03X932352Y223922I-44J1575D01*
G02X934297Y225085I2015J-1162D01*
G01X934426D01*
G03X935732Y225872I-59J1575D01*
G02X937696Y227035I2015J-1163D01*
G01X937791D01*
G03X939112Y227823I-44J1575D01*
G02X941042Y228985I2015J-1163D01*
G01X941198D01*
G03X942492Y229772I-71J1574D01*
G01X942558Y229888D01*
X944507Y232509D01*
G01X912436Y209833D02*
X913364Y210761D01*
X914394D01*
X922117Y218484D01*
X924297D01*
G03X926242Y219647I-70J2325D01*
G02X927563Y220435I1365J-787D01*
G01X927692D01*
G03X929622Y221597I-85J2325D01*
G02X930928Y222384I1365J-788D01*
G01X931057D01*
G03X933002Y223547I-70J2325D01*
G02X934323Y224335I1365J-787D01*
G01X934452D01*
G03X936382Y225497I-85J2325D01*
G02X937688Y226284I1365J-788D01*
G01X937798D01*
G03X939762Y227447I-51J2326D01*
G02X941056Y228234I1365J-787D01*
G01X941197D01*
G03X943142Y229397I-70J2325D01*
G02X944436Y230184I1365J-787D01*
G01X944651D01*
X947887Y230559D01*
G01X906858Y236942D02*
X907711Y236089D01*
X915647D01*
X918494Y238936D01*
X918832Y239522D01*
G02X920777Y240685I2015J-1162D01*
G01X920917D01*
G02X922862Y239522I-70J-2325D01*
G03X925592I1365J787D01*
G02X927537Y240685I2015J-1162D01*
G01X927666D01*
G03X928972Y241472I-59J1575D01*
G02X930902Y242634I2015J-1163D01*
G01X931031D01*
G03X932352Y243422I-44J1575D01*
G02X934297Y244585I2015J-1162D01*
G01X934426D01*
G03X935732Y245372I-59J1575D01*
G02X937662Y246534I2015J-1163D01*
G01X937791D01*
G03X939112Y247322I-44J1575D01*
G02X941057Y248485I2015J-1162D01*
G01X941776D01*
X943567Y249374D01*
G02X944448Y249684I940J-1265D01*
G01X944566D01*
G02X945872Y248897I-59J-1575D01*
G03X947802Y247735I2015J1163D01*
G01X947931D01*
G02X949252Y246947I-44J-1575D01*
G01X949318Y246831D01*
X951267Y244209D01*
G01X907056Y234442D02*
X907955Y235341D01*
X916041D01*
X918984Y238284D01*
X919482Y239147D01*
G02X922212I1365J-787D01*
G03X924157Y237984I2015J1162D01*
G01X924297D01*
G03X926242Y239147I-70J2325D01*
G02X927563Y239935I1365J-787D01*
G01X927692D01*
G03X929622Y241097I-85J2325D01*
G02X930928Y241884I1365J-788D01*
G01X931057D01*
G03X933002Y243047I-70J2325D01*
G02X934323Y243835I1365J-787D01*
G01X934452D01*
G03X936382Y244997I-85J2325D01*
G02X937688Y245784I1365J-788D01*
G01X937817D01*
G03X939762Y246947I-70J2325D01*
G02X941083Y247735I1365J-787D01*
G01X941776D01*
X943531Y246872D01*
G03X944463Y246534I976J1237D01*
G01X944592D01*
G02X946522Y245372I-85J-2325D01*
G03X947828Y244585I1365J788D01*
G01X947957D01*
G02X949902Y243422I-70J-2325D01*
G03X951223Y242634I1365J787D01*
G01X951413D01*
X954647Y242260D01*
G01X912436Y217333D02*
X913158Y216611D01*
X914914D01*
X921437Y223134D01*
X924271D01*
G03X925592Y223922I-44J1575D01*
G02X927537Y225085I2015J-1162D01*
G01X927666D01*
G03X928972Y225872I-59J1575D01*
G02X930936Y227035I2015J-1163D01*
G01X931031D01*
G03X932352Y227823I-44J1575D01*
G02X934282Y228985I2015J-1163D01*
G01X934438D01*
G03X935732Y229772I-71J1574D01*
G02X937677Y230935I2015J-1162D01*
G01X937818D01*
G03X939112Y231722I-71J1574D01*
G02X941076Y232885I2015J-1163D01*
G01X941186D01*
G03X942492Y233672I-59J1575D01*
G01X942558Y233788D01*
X944507Y236409D01*
G01X912436Y214833D02*
X913464Y215861D01*
X915225D01*
X921748Y222384D01*
G01X916688Y206810D02*
X917687D01*
X918332Y207455D01*
X918700Y208093D01*
X918832Y208322D01*
G02X920762Y209484I2015J-1163D01*
G01X920891D01*
G03X922212Y211846I-44J1575D01*
G02X924142Y215334I2015J1163D01*
G01X924271D01*
G03X925592Y216122I-44J1575D01*
G02X927537Y217285I2015J-1162D01*
G01X927666D01*
G03X928972Y218072I-59J1575D01*
G02X930902Y219234I2015J-1163D01*
G01X931031D01*
G03X932352Y220022I-44J1575D01*
G02X934297Y221185I2015J-1162D01*
G01X934426D01*
G03X935732Y221972I-59J1575D01*
G02X937662Y223134I2015J-1163D01*
G01X937791D01*
G03X939112Y223922I-44J1575D01*
G02X941057Y225085I2015J-1162D01*
G01X941186D01*
G03X942492Y225872I-59J1575D01*
G02X944456Y227035I2015J-1163D01*
G01X944551D01*
G03X945872Y227823I-44J1575D01*
G02X947802Y228985I2015J-1163D01*
G01X947958D01*
G03X949252Y229772I-71J1574D01*
G02X951197Y230935I2015J-1162D01*
G01X951338D01*
G03X952632Y231722I-71J1574D01*
G02X954596Y232885I2015J-1163D01*
G01X954647D01*
G03X955998Y233650I0J1575D01*
G01X956011Y233673D01*
G02X957928Y234834I2015J-1164D01*
G01X958111D01*
G02X958385Y234808I-82J-2325D01*
G01X961406Y234460D01*
G01X918556Y204941D02*
X918756Y205141D01*
Y206241D01*
X919266Y206751D01*
Y207563D01*
X919300Y207623D01*
X919482Y207946D01*
G02X920803Y208734I1365J-787D01*
G01X920932D01*
G03X922862Y212222I-85J2325D01*
G02X924183Y214584I1365J787D01*
G01X924297D01*
G03X926242Y215747I-70J2325D01*
G02X927563Y216535I1365J-787D01*
G01X927692D01*
G03X929622Y217697I-85J2325D01*
G02X930928Y218484I1365J-788D01*
G01X931057D01*
G03X933002Y219647I-70J2325D01*
G02X934323Y220435I1365J-787D01*
G01X934452D01*
G03X936382Y221597I-85J2325D01*
G02X937688Y222384I1365J-788D01*
G01X937817D01*
G03X939762Y223547I-70J2325D01*
G02X941083Y224335I1365J-787D01*
G01X941212D01*
G03X943142Y225497I-85J2325D01*
G02X944448Y226284I1365J-788D01*
G01X944558D01*
G03X946522Y227447I-51J2326D01*
G02X947816Y228234I1365J-787D01*
G01X947957D01*
G03X949902Y229397I-70J2325D01*
G02X951196Y230184I1365J-787D01*
G01X951352D01*
G03X953282Y231346I-85J2325D01*
G02X954603Y232134I1365J-787D01*
G01X954717D01*
G03X956662Y233296I-70J2326D01*
G01X956675Y233319D01*
G02X959107Y233656I1352J-810D01*
G01X960253Y233142D01*
X961176Y232885D01*
X961465D01*
G03X962771Y233672I-59J1575D01*
G01X962837Y233788D01*
X964786Y236409D01*
G01X908617Y243480D02*
X909462Y242635D01*
X910408D01*
X910411Y242632D01*
X910774D01*
X912506Y244364D01*
X912505D01*
Y244366D01*
X912724Y244585D01*
X914585D01*
G02X915959Y243411I-798J-2325D01*
G03X916812Y242634I1508J798D01*
G01X917511D01*
G03X918832Y243422I-44J1575D01*
G02X920777Y244585I2015J-1162D01*
G01X920917D01*
G02X922862Y243422I-70J-2325D01*
G03X925592I1365J787D01*
G02X927537Y244585I2015J-1162D01*
G01X927666D01*
G03X928972Y245372I-59J1575D01*
G02X930902Y246534I2015J-1163D01*
G01X931031D01*
G03X932352Y247322I-44J1575D01*
G02X934297Y248485I2015J-1162D01*
G01X934426D01*
G03X935732Y249272I-59J1575D01*
G02X937662Y250434I2015J-1163D01*
G01X937791D01*
G03X939112Y251222I-44J1575D01*
G02X941057Y252385I2015J-1162D01*
G01X941670D01*
X944466Y252060D01*
X944507Y252009D01*
G01X908695Y240980D02*
X909599Y241884D01*
X911084D01*
X913035Y243835D01*
X914442D01*
G02X915295Y243058I-655J-1575D01*
G03X916669Y241884I2172J1151D01*
G01X917537D01*
G03X919482Y243047I-70J2325D01*
G02X922212I1365J-787D01*
G03X924157Y241884I2015J1162D01*
G01X924297D01*
G03X926242Y243047I-70J2325D01*
G02X927563Y243835I1365J-787D01*
G01X927692D01*
G03X929622Y244997I-85J2325D01*
G02X930928Y245784I1365J-788D01*
G01X931057D01*
G03X933002Y246947I-70J2325D01*
G02X934323Y247735I1365J-787D01*
G01X934452D01*
G03X936382Y248897I-85J2325D01*
G02X937688Y249684I1365J-788D01*
G01X937817D01*
G03X939762Y250847I-70J2325D01*
G02X941083Y251635I1365J-787D01*
G01X941608D01*
X943568Y250744D01*
G03X944463Y250434I939J1265D01*
G01X944653D01*
X947887Y250060D01*
G01X908114Y248485D02*
X914157D01*
G02X916102Y247322I-70J-2325D01*
G03X918832I1365J787D01*
G02X920777Y248485I2015J-1162D01*
G01X920917D01*
G02X922862Y247322I-70J-2325D01*
G03X925592I1365J787D01*
G02X927537Y248485I2015J-1162D01*
G01X927666D01*
G03X928972Y249272I-59J1575D01*
G02X930902Y250434I2015J-1163D01*
G01X931031D01*
G03X932352Y251222I-44J1575D01*
G02X934297Y252385I2015J-1162D01*
G01X934426D01*
G03X935732Y253172I-59J1575D01*
G02X937662Y254334I2015J-1163D01*
G01X937791D01*
G03X939112Y255122I-44J1575D01*
G02X941057Y256285I2015J-1162D01*
G01X941269D01*
X944507Y255909D01*
G01X907380Y245980D02*
X909135Y247735D01*
X914131D01*
G02X915452Y246947I-44J-1575D01*
G03X917397Y245784I2015J1162D01*
G01X917537D01*
G03X919482Y246947I-70J2325D01*
G02X922212I1365J-787D01*
G03X924157Y245784I2015J1162D01*
G01X924297D01*
G03X926242Y246947I-70J2325D01*
G02X927563Y247735I1365J-787D01*
G01X927692D01*
G03X929622Y248897I-85J2325D01*
G02X930928Y249684I1365J-788D01*
G01X931057D01*
G03X933002Y250847I-70J2325D01*
G02X934323Y251635I1365J-787D01*
G01X934452D01*
G03X936382Y252797I-85J2325D01*
G02X937688Y253584I1365J-788D01*
G01X937817D01*
G03X939762Y254747I-70J2325D01*
G02X942492I1365J-787D01*
G03X944437Y253584I2015J1162D01*
G01X944566D01*
G02X945872Y252797I-59J-1575D01*
G03X947802Y251635I2015J1163D01*
G01X948033D01*
X951267Y252009D01*
G01X906736Y231542D02*
X907557Y230721D01*
X915918D01*
X920031Y234834D01*
X924271D01*
G03X925592Y235622I-44J1575D01*
G02X927537Y236785I2015J-1162D01*
G01X927666D01*
G03X928972Y237572I-59J1575D01*
G02X930902Y238734I2015J-1163D01*
G01X931031D01*
G03X932352Y239522I-44J1575D01*
G02X934297Y240685I2015J-1162D01*
G01X934426D01*
G03X935732Y241472I-59J1575D01*
G02X937662Y242634I2015J-1163D01*
G01X937791D01*
G03X939112Y243422I-44J1575D01*
G02X941057Y244585I2015J-1162D01*
G01X941776D01*
X943567Y245474D01*
G02X944448Y245784I940J-1265D01*
G01X944566D01*
G02X945872Y244997I-59J-1575D01*
G01X945938Y244881D01*
X947887Y242260D01*
G01X906736Y229042D02*
X907665Y229971D01*
X916229D01*
X920342Y234084D01*
X924297D01*
G03X926242Y235247I-70J2325D01*
G02X927563Y236035I1365J-787D01*
G01X927692D01*
G03X929622Y237197I-85J2325D01*
G02X930928Y237984I1365J-788D01*
G01X931057D01*
G03X933002Y239147I-70J2325D01*
G02X934323Y239935I1365J-787D01*
G01X934452D01*
G03X936382Y241097I-85J2325D01*
G02X937688Y241884I1365J-788D01*
G01X937817D01*
G03X939762Y243047I-70J2325D01*
G02X941083Y243835I1365J-787D01*
G01X941876D01*
X943417Y243071D01*
G03X944463Y242634I1090J1138D01*
G01X944592D01*
G02X946522Y241472I-85J-2325D01*
G03X947828Y240685I1365J788D01*
G01X948226D01*
X950397Y241624D01*
G02X951208Y241884I869J-1315D01*
G01X951326D01*
G02X952632Y241097I-59J-1575D01*
G01X952698Y240981D01*
X954647Y238360D01*
G01X910622Y251480D02*
X910709D01*
X910864Y251635D01*
X914131D01*
G02X915452Y250847I-44J-1575D01*
G03X917463Y249685I2011J1160D01*
G01X917470D01*
G03X919482Y250847I1J2322D01*
G02X920844Y251634I1362J-785D01*
G01X920850D01*
G02X922212Y250847I0J-1572D01*
G03X924225Y249685I2011J1160D01*
G01X924231D01*
G03X926242Y250847I0J2322D01*
G02X927563Y251635I1365J-787D01*
G01X927692D01*
G03X929622Y252797I-85J2325D01*
G02X930928Y253584I1365J-788D01*
G01X931057D01*
G03X933002Y254747I-70J2325D01*
G02X934323Y255535I1365J-787D01*
G01X934452D01*
G03X936382Y256697I-85J2325D01*
G02X937688Y257484I1365J-788D01*
G01X937801D01*
G03X939762Y258647I-54J2325D01*
G02X941126Y259435I1364J-786D01*
G01X941128D01*
G02X942492Y258647I0J-1574D01*
G03X944453Y257484I2015J1162D01*
G01X944566D01*
G02X945872Y256697I-59J-1575D01*
G03X947802Y255535I2015J1163D01*
G01X947931D01*
G02X949252Y254747I-44J-1575D01*
G03X951197Y253584I2015J1162D01*
G01X951337D01*
G03X953141Y254530I-69J2325D01*
G01X953493Y254625D01*
X954647Y253960D01*
G01X944507Y240309D02*
X941979Y240095D01*
G02X941212Y239935I-852J2165D01*
G01X941083D01*
G03X939762Y239147I44J-1575D01*
G02X937817Y237984I-2015J1162D01*
G01X937688D01*
G03X936382Y237197I59J-1575D01*
G02X934452Y236035I-2015J1163D01*
G01X934323D01*
G03X933002Y235247I44J-1575D01*
G02X931057Y234084I-2015J1162D01*
G01X930928D01*
G03X929622Y233297I59J-1575D01*
G02X927658Y232134I-2015J1163D01*
G01X927563D01*
G03X926242Y231346I44J-1575D01*
G02X924312Y230184I-2015J1163D01*
G01X921004D01*
X915155Y224335D01*
X907655D01*
X907588Y224268D01*
Y224224D01*
X907544Y224180D01*
X907500D01*
G01X907318Y220168D02*
X907362D01*
X907406Y220212D01*
Y220292D01*
X907455Y220341D01*
X915433D01*
X921377Y226285D01*
X924280D01*
X924278Y226284D01*
G03X926242Y227447I-51J2326D01*
G02X927536Y228234I1365J-787D01*
G01X927677D01*
G03X929622Y229397I-70J2325D01*
G02X930916Y230184I1365J-787D01*
G01X931072D01*
G03X933002Y231346I-85J2325D01*
G02X934323Y232134I1365J-787D01*
G01X934418D01*
G03X936382Y233297I-51J2326D01*
G02X937688Y234084I1365J-788D01*
G01X937817D01*
G03X939762Y235247I-70J2325D01*
G02X941083Y236035I1365J-787D01*
G01X941212D01*
G03X943142Y237197I-85J2325D01*
G02X944448Y237984I1365J-788D01*
G01X944566D01*
G02X945872Y237197I-59J-1575D01*
G03X947802Y236035I2015J1163D01*
G01X947931D01*
G02X949252Y235247I-44J-1575D01*
G03X953141Y235030I2015J1162D01*
G01X953493Y235125D01*
X954647Y234460D01*
G01X910622Y252540D02*
X910709D01*
X910864Y252385D01*
X914141D01*
G02X916102Y251222I-54J-2325D01*
G03X917464Y250435I1362J785D01*
G01X917470D01*
G03X918832Y251222I0J1572D01*
G02X920843Y252384I2011J-1160D01*
G01X920851D01*
G02X922862Y251222I0J-2322D01*
G03X924224Y250435I1362J785D01*
G01X924230D01*
G03X925592Y251222I0J1572D01*
G02X927553Y252385I2015J-1162D01*
G01X927666D01*
G03X928972Y253172I-59J1575D01*
G02X930902Y254334I2015J-1163D01*
G01X931031D01*
G03X932352Y255122I-44J1575D01*
G02X934297Y256285I2015J-1162D01*
G01X934426D01*
G03X935732Y257072I-59J1575D01*
G02X937662Y258234I2015J-1163D01*
G01X937791D01*
G03X939112Y259022I-44J1575D01*
G02X941125Y260185I2013J-1161D01*
G01X941129D01*
G02X943142Y259022I0J-2324D01*
G03X944463Y258234I1365J787D01*
G01X944592D01*
G02X946522Y257072I-85J-2325D01*
G03X947828Y256285I1365J788D01*
G01X947957D01*
G02X949902Y255122I-70J-2325D01*
G03X951223Y254334I1365J787D01*
G01X951311D01*
G03X952504Y254934I-45J1575D01*
G01X952421Y255244D01*
X951267Y255909D01*
G01X947887Y238360D02*
X947841Y238367D01*
X946071Y240747D01*
X945872Y241097D01*
G03X944566Y241884I-1365J-788D01*
G01X944250Y241886D01*
G03X943252Y241301I0J-1144D01*
G01X941880Y240875D01*
G02X941704Y240793I-752J1385D01*
G02X941186Y240685I-576J1467D01*
G01X941057D01*
G03X939112Y239522I70J-2325D01*
G02X937791Y238734I-1365J787D01*
G01X937662D01*
G03X935732Y237572I85J-2325D01*
G02X934426Y236785I-1365J788D01*
G01X934297D01*
G03X932352Y235622I70J-2325D01*
G02X931031Y234834I-1365J787D01*
G01X930902D01*
G03X928972Y233672I85J-2325D01*
G02X927666Y232885I-1365J788D01*
G01X927556D01*
G03X925592Y231722I51J-2326D01*
G01Y231721D01*
G02X924285Y230934I-1365J788D01*
G01X920693D01*
X914844Y225085D01*
X907655D01*
X907500Y225240D01*
G01X907318Y221228D02*
X907455Y221091D01*
X915122D01*
X921066Y227035D01*
X924271D01*
G03X925592Y227823I-44J1575D01*
G02X927522Y228985I2015J-1163D01*
G01X927678D01*
G03X928972Y229772I-71J1574D01*
G02X930917Y230935I2015J-1162D01*
G01X931058D01*
G03X932352Y231722I-71J1574D01*
G02X934316Y232885I2015J-1163D01*
G01X934426D01*
G03X935732Y233672I-59J1575D01*
G02X937662Y234834I2015J-1163D01*
G01X937791D01*
G03X939112Y235622I-44J1575D01*
G02X941057Y236785I2015J-1162D01*
G01X941186D01*
G03X942492Y237572I-59J1575D01*
G02X944422Y238734I2015J-1163D01*
G01X944592D01*
G02X946522Y237572I-85J-2325D01*
G03X947828Y236785I1365J788D01*
G01X947957D01*
G02X949902Y235622I-70J-2325D01*
G03X952504Y235434I1365J787D01*
G01X952505Y235433D01*
X952421Y235744D01*
X951267Y236409D01*
G01X910260Y334320D02*
X910295Y334285D01*
X914585D01*
G02X915959Y333111I-798J-2325D01*
G03X916812Y332334I1508J798D01*
G01X917552D01*
G02X919482Y331172I-85J-2325D01*
G03X920788Y330385I1365J788D01*
G01X920917D01*
G02X922862Y329222I-70J-2325D01*
G03X924156Y328435I1365J787D01*
G01X924312D01*
G02X926242Y327273I-85J-2325D01*
G03X927563Y326485I1365J787D01*
G01X927692D01*
G02X929622Y325323I-85J-2325D01*
G03X930943Y324535I1365J787D01*
G01X931038D01*
G02X933002Y323372I-51J-2326D01*
G03X934308Y322585I1365J788D01*
G01X934437D01*
G02X936382Y321422I-70J-2325D01*
G03X937703Y320634I1365J787D01*
G01X937832D01*
G02X939762Y319472I-85J-2325D01*
G03X942492I1365J788D01*
G02X944422Y320634I2015J-1163D01*
G01X944551D01*
G03X945872Y321422I-44J1575D01*
G02X947540Y322560I2015J-1162D01*
G02X947621Y322571I353J-2299D01*
G01X947887Y322837D01*
Y324160D01*
G01X910410Y333420D02*
X910525Y333535D01*
X914442D01*
G02X915295Y332758I-655J-1575D01*
G03X916669Y331584I2172J1151D01*
G01X917526D01*
G02X918832Y330797I-59J-1575D01*
G03X920762Y329635I2015J1163D01*
G01X920891D01*
G02X922212Y328847I-44J-1575D01*
G03X924157Y327684I2015J1162D01*
G01X924298D01*
G02X925592Y326897I-71J-1574D01*
G03X927522Y325735I2015J1163D01*
G01X927651D01*
G02X928972Y324947I-44J-1575D01*
G03X930936Y323784I2015J1163D01*
G01X931046D01*
G02X932352Y322997I-59J-1575D01*
G03X934282Y321835I2015J1163D01*
G01X934411D01*
G02X935732Y321047I-44J-1575D01*
G03X937677Y319884I2015J1162D01*
G01X937806D01*
G02X939112Y319097I-59J-1575D01*
G03X943142I2015J1163D01*
G02X944448Y319884I1365J-788D01*
G01X944577D01*
G03X946522Y321047I-70J2325D01*
G02X947652Y321818I1365J-787D01*
G01X947887Y321583D01*
Y320260D01*
G01X954647Y355360D02*
X953350Y352364D01*
X953282Y352247D01*
G02X951337Y351084I-2015J1162D01*
G01X951208D01*
G03X949902Y350297I59J-1575D01*
G02X947972Y349135I-2015J1163D01*
G01X947843D01*
G03X946522Y348347I44J-1575D01*
G02X944577Y347184I-2015J1162D01*
G01X944437D01*
G02X942492Y348347I70J2325D01*
G03X941171Y349135I-1365J-787D01*
G01X941042D01*
G02X939112Y350297I85J2325D01*
G03X937806Y351084I-1365J-788D01*
G01X937677D01*
G02X935732Y352247I70J2325D01*
G03X934411Y353035I-1365J-787D01*
G01X934282D01*
G02X932352Y354197I85J2325D01*
G03X931046Y354984I-1365J-788D01*
G01X930917D01*
G02X928972Y356147I70J2325D01*
G03X927651Y356935I-1365J-787D01*
G01X927522D01*
G02X925592Y358097I85J2325D01*
G03X924286Y358884I-1365J-788D01*
G01X923191D01*
X922364Y359711D01*
X921286D01*
X917856Y363141D01*
X913456D01*
X908756Y367841D01*
X904470D01*
X904056Y367427D01*
G01X951267Y353409D02*
X949318Y350788D01*
X949252Y350672D01*
G02X947946Y349885I-1365J788D01*
G01X947817D01*
G03X945872Y348722I70J-2325D01*
G02X943142I-1365J787D01*
G03X941197Y349885I-2015J-1162D01*
G01X941068D01*
G02X939762Y350672I59J1575D01*
G03X937832Y351834I-2015J-1163D01*
G01X937703D01*
G02X936382Y352622I44J1575D01*
G03X934437Y353785I-2015J-1162D01*
G01X934308D01*
G02X933002Y354572I59J1575D01*
G03X931072Y355734I-2015J-1163D01*
G01X930943D01*
G02X929622Y356522I44J1575D01*
G03X927677Y357685I-2015J-1162D01*
G01X927548D01*
G02X926242Y358472I59J1575D01*
G03X924312Y359634I-2015J-1163D01*
G01X923504D01*
X922677Y360461D01*
X921597D01*
X918169Y363889D01*
X913766D01*
X909066Y368589D01*
X904508D01*
X903166Y369931D01*
G01X944507Y361209D02*
X942558Y363831D01*
X942492Y363947D01*
G03X941171Y364735I-1365J-787D01*
G01X941042D01*
G02X939112Y365897I85J2325D01*
G03X937806Y366684I-1365J-788D01*
G01X937696D01*
G02X935732Y367847I51J2326D01*
G03X934438Y368634I-1365J-787D01*
G01X934297D01*
G02X932352Y369797I70J2325D01*
G03X931058Y370584I-1365J-787D01*
G01X930902D01*
G02X928972Y371746I85J2325D01*
G03X927651Y372534I-1365J-787D01*
G01X927556D01*
G02X925592Y373697I51J2326D01*
G03X924298Y374484I-1365J-787D01*
G01X924142D01*
G02X922212Y375646I85J2325D01*
G01X920417Y377441D01*
X916656D01*
X914556Y379541D01*
Y387941D01*
X913756Y388741D01*
X906557D01*
X905605Y387789D01*
G01X947887Y347560D02*
X946590Y344564D01*
X946522Y344447D01*
G02X944577Y343284I-2015J1162D01*
G01X944437D01*
G02X942492Y344447I70J2325D01*
G03X941171Y345235I-1365J-787D01*
G01X941042D01*
G02X939112Y346397I85J2325D01*
G03X937806Y347184I-1365J-788D01*
G01X937677D01*
G02X935732Y348347I70J2325D01*
G03X934411Y349135I-1365J-787D01*
G01X934282D01*
G02X932352Y350297I85J2325D01*
G03X931046Y351084I-1365J-788D01*
G01X930917D01*
G02X928972Y352247I70J2325D01*
G03X927651Y353035I-1365J-787D01*
G01X927522D01*
G02X925592Y354197I85J2325D01*
G03X924286Y354984I-1365J-788D01*
G01X924157D01*
G02X922212Y356147I70J2325D01*
G03X921020Y356926I-1365J-787D01*
G03X920671Y356940I-274J-2484D01*
G02X918832Y358097I178J2323D01*
G03X917526Y358884I-1365J-788D01*
G01X916139D01*
X915062Y359961D01*
X912078D01*
X910356Y361683D01*
X900056D01*
X899229Y360856D01*
G01X944507Y345609D02*
X941269Y345985D01*
X941068D01*
G02X939762Y346772I59J1575D01*
G03X937832Y347934I-2015J-1163D01*
G01X937703D01*
G02X936382Y348722I44J1575D01*
G03X934437Y349885I-2015J-1162D01*
G01X934308D01*
G02X933002Y350672I59J1575D01*
G03X931072Y351834I-2015J-1163D01*
G01X930943D01*
G02X929622Y352622I44J1575D01*
G03X927677Y353785I-2015J-1162D01*
G01X927548D01*
G02X926242Y354572I59J1575D01*
G03X924312Y355734I-2015J-1163D01*
G01X924183D01*
G02X922862Y356522I44J1575D01*
G03X921128Y357669I-2016J-1163D01*
G03X920627Y357699I-493J-4042D01*
G02X919482Y358472I215J1554D01*
G03X917552Y359634I-2015J-1163D01*
G01X916447D01*
X915372Y360709D01*
X912388D01*
X910666Y362431D01*
X899755D01*
X898813Y363373D01*
G01X916669Y354984D02*
G02X915295Y356158I798J2325D01*
G03X913787Y356935I-1508J-1075D01*
G01X912568D01*
X912274Y356641D01*
X899970D01*
X899065Y355736D01*
G01X944507Y341709D02*
X942405Y342016D01*
X941810Y342085D01*
X941068D01*
G02X939762Y342872I59J1575D01*
G03X937832Y344034I-2015J-1163D01*
G01X937703D01*
G02X936382Y344822I44J1575D01*
G03X934437Y345985I-2015J-1162D01*
G01X934308D01*
G02X933002Y346772I59J1575D01*
G03X931072Y347934I-2015J-1163D01*
G01X930943D01*
G02X929622Y348722I44J1575D01*
G03X927677Y349885I-2015J-1162D01*
G01X927548D01*
G02X926242Y350672I59J1575D01*
G03X924312Y351834I-2015J-1163D01*
G01X924183D01*
G02X922862Y352622I44J1575D01*
G03X920917Y353785I-2015J-1162D01*
G01X920788D01*
G02X919482Y354572I59J1575D01*
G03X917552Y355734I-2015J-1163D01*
G01X916812D01*
G02X916080Y356316I655J1575D01*
G03X913787Y357685I-2293J-1236D01*
G01X912260D01*
X911964Y357389D01*
X899891D01*
X899044Y358236D01*
G01X902856Y372601D02*
X903648Y373393D01*
X907546D01*
X914946Y365993D01*
X918946D01*
X921934Y363005D01*
X921933D01*
Y363003D01*
X922152Y362784D01*
X924286D01*
G02X925592Y361997I-59J-1575D01*
G03X927522Y360835I2015J1163D01*
G01X927651D01*
G02X928972Y360047I-44J-1575D01*
G03X930917Y358884I2015J1162D01*
G01X931046D01*
G02X932352Y358097I-59J-1575D01*
G03X934282Y356935I2015J1163D01*
G01X934411D01*
G02X935732Y356147I-44J-1575D01*
G03X937677Y354984I2015J1162D01*
G01X937806D01*
G02X939112Y354197I-59J-1575D01*
G03X941042Y353035I2015J1163D01*
G01X941171D01*
G02X942492Y352247I-44J-1575D01*
G03X944437Y351084I2015J1162D01*
G01X944577D01*
G03X946522Y352247I-70J2325D01*
G02X947843Y353035I1365J-787D01*
G01X947972D01*
G03X949902Y354197I-85J2325D01*
G02X951208Y354984I1365J-788D01*
G01X951337D01*
G03X953282Y356147I-70J2325D01*
G01X953350Y356264D01*
X954647Y359260D01*
G01X947887Y355360D02*
X945938Y352738D01*
X945872Y352622D01*
G02X943142I-1365J787D01*
G03X941197Y353785I-2015J-1162D01*
G01X941068D01*
G02X939762Y354572I59J1575D01*
G03X937832Y355734I-2015J-1163D01*
G01X937703D01*
G02X936382Y356522I44J1575D01*
G03X934437Y357685I-2015J-1162D01*
G01X934308D01*
G02X933002Y358472I59J1575D01*
G03X931072Y359634I-2015J-1163D01*
G01X930943D01*
G02X929622Y360422I44J1575D01*
G03X927677Y361585I-2015J-1162D01*
G01X927548D01*
G02X926242Y362372I59J1575D01*
G03X924312Y363534I-2015J-1163D01*
G01X922463D01*
X919256Y366741D01*
X915256D01*
X907856Y374141D01*
X903883D01*
X902856Y375168D01*
G01X944507Y337809D02*
X941538Y337470D01*
G02X941212Y337435I-411J2290D01*
G01X941042D01*
G02X939112Y338597I85J2325D01*
G03X937806Y339384I-1365J-788D01*
G01X937677D01*
G02X935732Y340547I70J2325D01*
G03X934411Y341335I-1365J-787D01*
G01X934282D01*
G02X932352Y342497I85J2325D01*
G03X931046Y343284I-1365J-788D01*
G01X930917D01*
G02X928972Y344447I70J2325D01*
G03X927651Y345235I-1365J-787D01*
G01X927522D01*
G02X925592Y346397I85J2325D01*
G03X924286Y347184I-1365J-788D01*
G01X924157D01*
G02X922212Y348347I70J2325D01*
G03X920891Y349135I-1365J-787D01*
G01X920762D01*
G02X918832Y350297I85J2325D01*
G03X917526Y351084I-1365J-788D01*
G01X917397D01*
G02X915452Y352247I70J2325D01*
G03X914131Y353035I-1365J-787D01*
G01X912395D01*
X911191Y351831D01*
X899568D01*
X899413Y351676D01*
X899326D01*
G01X951267Y361209D02*
X952421Y361875D01*
X952731Y361791D01*
G02X951311Y359634I-1465J-582D01*
G01X951182D01*
G03X949252Y358472I85J-2325D01*
G02X947946Y357685I-1365J788D01*
G01X947833D01*
G03X945872Y356522I54J-2325D01*
G02X944510Y355735I-1362J785D01*
G01X944504D01*
G02X943142Y356522I0J1572D01*
G03X941181Y357685I-2015J-1162D01*
G01X941068D01*
G02X939762Y358472I59J1575D01*
G03X937832Y359634I-2015J-1163D01*
G01X937703D01*
G02X936382Y360422I44J1575D01*
G03X934437Y361585I-2015J-1162D01*
G01X934308D01*
G02X933002Y362372I59J1575D01*
G03X931072Y363534I-2015J-1163D01*
G01X930943D01*
G02X929622Y364322I44J1575D01*
G03X927677Y365485I-2015J-1162D01*
G01X927548D01*
G02X926242Y366272I59J1575D01*
G03X924278Y367435I-2015J-1163D01*
G01X924277Y367434D01*
X922524D01*
X918067Y371891D01*
X914267D01*
X906838Y379320D01*
X903922D01*
X903767Y379475D01*
X903680D01*
G01X944507Y357309D02*
X945661Y357975D01*
X945744Y358285D01*
G03X944566Y358884I-1238J-976D01*
G01X944437D01*
G02X942492Y360047I70J2325D01*
G03X941171Y360835I-1365J-787D01*
G01X941042D01*
G02X939112Y361997I85J2325D01*
G03X937806Y362784I-1365J-788D01*
G01X937677D01*
G02X935732Y363947I70J2325D01*
G03X934411Y364735I-1365J-787D01*
G01X934282D01*
G02X932352Y365897I85J2325D01*
G03X931046Y366684I-1365J-788D01*
G01X930936D01*
G02X928972Y367847I51J2326D01*
G03X927678Y368634I-1365J-787D01*
G01X927537D01*
G02X925592Y369797I70J2325D01*
G03X924308Y370584I-1365J-787D01*
G01X922352D01*
X918795Y374141D01*
X915432D01*
X911126Y378466D01*
Y382193D01*
X910519Y382800D01*
X902975D01*
X902429Y382811D01*
X902272Y382659D01*
X902185Y382660D01*
G01X947887Y339760D02*
X945861Y339383D01*
X943603D01*
X942512Y338714D01*
G02X941776Y338324I-3459J5638D01*
G02X941405Y338209I-649J1436D01*
G02X941186Y338185I-281J1551D01*
G01X941068D01*
G02X939762Y338972I59J1575D01*
G03X937832Y340134I-2015J-1163D01*
G01X937703D01*
G02X936382Y340922I44J1575D01*
G03X934437Y342085I-2015J-1162D01*
G01X934308D01*
G02X933002Y342872I59J1575D01*
G03X931072Y344034I-2015J-1163D01*
G01X930943D01*
G02X929622Y344822I44J1575D01*
G03X927677Y345985I-2015J-1162D01*
G01X927548D01*
G02X926242Y346772I59J1575D01*
G03X924312Y347934I-2015J-1163D01*
G01X924183D01*
G02X922862Y348722I44J1575D01*
G03X920917Y349885I-2015J-1162D01*
G01X920788D01*
G02X919482Y350672I59J1575D01*
G03X917552Y351834I-2015J-1163D01*
G01X917423D01*
G02X916102Y352622I44J1575D01*
G03X914141Y353785I-2015J-1162D01*
G01X912084D01*
X910880Y352581D01*
X899568D01*
X899413Y352736D01*
X899326D01*
G01X954647Y363160D02*
X953493Y362494D01*
X953399Y362142D01*
G02X951337Y358884I-2131J-933D01*
G01X951208D01*
G03X949902Y358097I59J-1575D01*
G02X947972Y356935I-2015J1163D01*
G01X947843D01*
G03X946522Y356147I44J-1575D01*
G02X944511Y354985I-2011J1160D01*
G01X944503D01*
G02X942492Y356147I0J2322D01*
G03X941171Y356935I-1365J-787D01*
G01X941042D01*
G02X939112Y358097I85J2325D01*
G03X937806Y358884I-1365J-788D01*
G01X937677D01*
G02X935732Y360047I70J2325D01*
G03X934411Y360835I-1365J-787D01*
G01X934282D01*
G02X932352Y361997I85J2325D01*
G03X931046Y362784I-1365J-788D01*
G01X930917D01*
G02X928972Y363947I70J2325D01*
G03X927651Y364735I-1365J-787D01*
G01X927522D01*
G02X925592Y365897I85J2325D01*
G03X924286Y366684I-1365J-788D01*
G01X922213D01*
X917756Y371141D01*
X913956D01*
X906527Y378570D01*
X903922D01*
X903767Y378415D01*
X903680D01*
G01X947887Y359260D02*
X945069Y359634D01*
X944463D01*
G02X943142Y360422I44J1575D01*
G03X941197Y361585I-2015J-1162D01*
G01X941068D01*
G02X939762Y362372I59J1575D01*
G03X937832Y363534I-2015J-1163D01*
G01X937703D01*
G02X936382Y364322I44J1575D01*
G03X934437Y365485I-2015J-1162D01*
G01X934308D01*
G02X933002Y366272I59J1575D01*
G03X931038Y367435I-2015J-1163D01*
G01X930943D01*
G02X929622Y368223I44J1575D01*
G03X927692Y369385I-2015J-1163D01*
G01X927536D01*
G02X926242Y370172I71J1574D01*
G03X924298Y371335I-2015J-1162D01*
G01X924297Y371334D01*
X922663D01*
X919106Y374891D01*
X915746D01*
X911876Y378795D01*
Y382504D01*
X910830Y383550D01*
X902989D01*
X902443Y383561D01*
X902292Y383719D01*
X902205Y383720D01*
G01X918434Y383132D02*
X918851Y383856D01*
G03X918832Y385397I-1384J754D01*
G02X918807Y387680I2015J1164D01*
G01X918832Y387722D01*
X918851Y387756D01*
G03X918832Y389297I-1384J754D01*
G02Y391623I2015J1163D01*
G03Y393197I-1365J787D01*
G01X918612Y393578D01*
X917755Y394140D01*
X909955D01*
X909107Y393292D01*
G01X947887Y367060D02*
X944644Y367435D01*
X944463D01*
G02X943142Y368223I44J1575D01*
G03X941212Y369385I-2015J-1163D01*
G01X941056D01*
G02X939762Y370172I71J1574D01*
G03X937817Y371335I-2015J-1162D01*
G01X937676D01*
G02X936382Y372122I71J1574D01*
G03X934418Y373285I-2015J-1163D01*
G01X934308D01*
G02X933002Y374072I59J1575D01*
G03X931072Y375234I-2015J-1163D01*
G01X930943D01*
G02X929622Y376022I44J1575D01*
G03X927677Y377185I-2015J-1162D01*
G01X927548D01*
G02X926242Y377972I59J1575D01*
G03X924312Y379134I-2015J-1163D01*
G01X924183D01*
G02X922862Y379922I44J1575D01*
G03X920917Y381085I-2015J-1162D01*
G01X920190D01*
G02X919155Y382879I657J1575D01*
G01X919507Y383489D01*
G03X919482Y385772I-2040J1119D01*
G02X919463Y387313I1365J787D01*
G01X919482Y387347D01*
X919507Y387389D01*
G03X919482Y389672I-2040J1119D01*
G02X919463Y391213I1365J787D01*
G01X919482Y391247D01*
G03X919507Y393530I-2015J1164D01*
G01X919410Y393692D01*
X919173Y394106D01*
X917979Y394888D01*
X910042D01*
X909107Y395823D01*
G01X944507Y365109D02*
X941269Y365485D01*
X941068D01*
G02X939762Y366272I59J1575D01*
G03X937798Y367435I-2015J-1163D01*
G01X937703D01*
G02X936382Y368223I44J1575D01*
G03X934452Y369385I-2015J-1163D01*
G01X934296D01*
G02X933002Y370172I71J1574D01*
G03X931057Y371335I-2015J-1162D01*
G01X930916D01*
G02X929622Y372122I71J1574D01*
G03X927658Y373285I-2015J-1163D01*
G01X927548D01*
G02X926242Y374072I59J1575D01*
G03X924297Y375235I-2015J-1162D01*
G01X924156D01*
G02X922862Y376022I71J1574D01*
G03X922741Y376175I-580J-335D01*
G01X920727Y378189D01*
X916966D01*
X915304Y379851D01*
Y388251D01*
X914066Y389489D01*
X906085D01*
X905285Y390289D01*
G01X964786Y361209D02*
X961548Y361585D01*
X960105D01*
G02X959391Y361997I0J825D01*
G03X958085Y362784I-1365J-788D01*
G01X957956D01*
G02X956011Y363947I70J2325D01*
G01X955998Y363970D01*
G03X954647Y364735I-1351J-810D01*
G01X954562D01*
G02X952632Y365897I85J2325D01*
G03X951326Y366684I-1365J-788D01*
G01X951216D01*
G02X949252Y367847I51J2326D01*
G03X947958Y368634I-1365J-787D01*
G01X947817D01*
G02X945872Y369797I70J2325D01*
G03X944578Y370584I-1365J-787D01*
G01X944422D01*
G02X942492Y371746I85J2325D01*
G03X941171Y372534I-1365J-787D01*
G01X941076D01*
G02X939112Y373697I51J2326D01*
G03X937806Y374484I-1365J-788D01*
G01X937677D01*
G02X935732Y375647I70J2325D01*
G03X934411Y376435I-1365J-787D01*
G01X934282D01*
G02X932352Y377597I85J2325D01*
G03X931046Y378384I-1365J-788D01*
G01X930917D01*
G02X928972Y379547I70J2325D01*
G03X927651Y380335I-1365J-787D01*
G01X927522D01*
G02X925592Y381497I85J2325D01*
G03X924286Y382284I-1365J-788D01*
G01X924176D01*
G02X922212Y385773I51J2326D01*
G03Y387347I-1365J787D01*
G02Y389673I2015J1163D01*
G03Y391247I-1365J787D01*
G02X922187Y393530I2015J1164D01*
G01X922212Y393572D01*
G03X920891Y395934I-1365J787D01*
G01X920796D01*
G02X918832Y397097I51J2326D01*
G01X917800Y398666D01*
X917793Y398677D01*
X916377Y400093D01*
X915307D01*
G01X918296Y199831D02*
X920151Y201686D01*
X920928D01*
G03X922231Y204013I-81J1574D01*
G01X922212Y204047D01*
G02X924157Y207535I2015J1163D01*
G01X924298D01*
G03X925592Y209897I-71J1574D01*
G02X927537Y213385I2015J1163D01*
G01X927666D01*
G03X928972Y214172I-59J1575D01*
G02X930902Y215334I2015J-1163D01*
G01X931031D01*
G03X932352Y216122I-44J1575D01*
G02X934297Y217285I2015J-1162D01*
G01X934426D01*
G03X935732Y218072I-59J1575D01*
G02X937662Y219234I2015J-1163D01*
G01X937791D01*
G03X939112Y220022I-44J1575D01*
G02X941057Y221185I2015J-1162D01*
G01X941186D01*
G03X942492Y221972I-59J1575D01*
G02X944422Y223134I2015J-1163D01*
G01X944551D01*
G03X945872Y223922I-44J1575D01*
G02X947817Y225085I2015J-1162D01*
G01X947946D01*
G03X949252Y225872I-59J1575D01*
G02X951216Y227035I2015J-1163D01*
G01X951311D01*
G03X952632Y227823I-44J1575D01*
G02X954562Y228985I2015J-1163D01*
G01X954695D01*
G03X956011Y229772I-48J1574D01*
G02X957956Y230935I2015J-1162D01*
G01X959407D01*
X961280Y230717D01*
X961406Y230559D01*
G01X919945Y197331D02*
X922106Y199492D01*
Y200787D01*
X922862Y202097D01*
G03Y204423I-2015J1163D01*
G02X924156Y206784I1365J787D01*
G01X924312D01*
G03X926242Y210272I-85J2325D01*
G02X927563Y212635I1365J788D01*
G01X927692D01*
G03X929622Y213797I-85J2325D01*
G02X930928Y214584I1365J-788D01*
G01X931057D01*
G03X933002Y215747I-70J2325D01*
G02X934323Y216535I1365J-787D01*
G01X934452D01*
G03X936382Y217697I-85J2325D01*
G02X937688Y218484I1365J-788D01*
G01X937817D01*
G03X939762Y219647I-70J2325D01*
G02X941083Y220435I1365J-787D01*
G01X941212D01*
G03X943142Y221597I-85J2325D01*
G02X944448Y222384I1365J-788D01*
G01X944577D01*
G03X946522Y223547I-70J2325D01*
G02X947843Y224335I1365J-787D01*
G01X947972D01*
G03X949902Y225497I-85J2325D01*
G02X951208Y226284I1365J-788D01*
G01X951318D01*
G03X953282Y227447I-51J2326D01*
G02X954576Y228234I1365J-787D01*
G01X954732D01*
G03X956662Y229396I-85J2325D01*
G01X956675Y229419D01*
G02X958026Y230184I1351J-810D01*
G01X958097D01*
G02X958821Y229971I-70J-1574D01*
G02X959202Y229659I-796J-1360D01*
G01X960826Y228985D01*
X961906D01*
X962256Y229203D01*
X962681Y229467D01*
X962980Y230134D01*
X963232Y232248D01*
G02X964727Y234084I1554J261D01*
G01X964928D01*
X968166Y234460D01*
G01X938139Y189470D02*
X939285D01*
X940183Y190368D01*
Y196345D01*
X939112Y198196D01*
G02X939077Y200462I2015J1164D01*
G01X939112Y200522D01*
X939131Y200556D01*
G03X939112Y202097I-1384J754D01*
G02X941042Y205585I2015J1163D01*
G01X941198D01*
G03X942492Y206372I-71J1574D01*
G02X944437Y207535I2015J-1162D01*
G01X944578D01*
G03X945872Y208322I-71J1574D01*
G02X947836Y209485I2015J-1163D01*
G01X947946D01*
G03X949252Y210272I-59J1575D01*
G02X951182Y211434I2015J-1163D01*
G01X951286D01*
G03X952632Y212223I-19J1575D01*
G02X954577Y213386I2015J-1162D01*
G01X954695D01*
G03X956011Y214173I-48J1574D01*
G02X957928Y215334I2015J-1164D01*
G01X958070D01*
G03X959391Y216122I-44J1575D01*
G02X961336Y217285I2015J-1162D01*
G01X961465D01*
G03X962771Y218072I-59J1575D01*
G02X964701Y219234I2015J-1163D01*
G01X964830D01*
G03X966151Y220022I-44J1575D01*
G02X966587Y220568I2015J-1162D01*
G01X968166Y222760D01*
G01X939920Y186920D02*
Y189037D01*
X940933Y190050D01*
Y196547D01*
X939762Y198572D01*
G02X939743Y200113I1365J787D01*
G01X939762Y200147D01*
X939787Y200189D01*
G03X939762Y202472I-2040J1119D01*
G02X941056Y204834I1365J788D01*
G01X941197D01*
G03X943142Y205997I-70J2325D01*
G02X944436Y206784I1365J-787D01*
G01X944592D01*
G03X946522Y207946I-85J2325D01*
G02X947843Y208734I1365J-787D01*
G01X947938D01*
G03X949902Y209897I-51J2326D01*
G02X951208Y210684I1365J-788D01*
G01X951337D01*
G03X953282Y211847I-70J2325D01*
G02X954588Y212635I1365J-786D01*
G01X954745D01*
G03X956662Y213796I-98J2325D01*
G01X956675Y213819D01*
G02X958026Y214584I1351J-810D01*
G01X958096D01*
G03X960041Y215747I-70J2325D01*
G02X961362Y216535I1365J-787D01*
G01X961491D01*
G03X963421Y217697I-85J2325D01*
G02X964727Y218484I1365J-788D01*
G01X964856D01*
G03X966801Y219647I-70J2325D01*
G02X968122Y220435I1365J-787D01*
G01X968251D01*
G03X970295Y221822I-85J2325D01*
G01X971546Y224709D01*
G01X933097Y191440D02*
X934255D01*
X935944Y193129D01*
Y199358D01*
X935942Y199360D01*
G03X935732Y200147I-1575J1D01*
G01X935707Y200189D01*
G02X935732Y202472I2040J1119D01*
G03X935751Y204013I-1365J787D01*
G01X935732Y204047D01*
G02X937677Y207535I2015J1163D01*
G01X937818D01*
G03X939112Y208322I-71J1574D01*
G02X941076Y209485I2015J-1163D01*
G01X941186D01*
G03X942492Y210272I-59J1575D01*
G02X944422Y211434I2015J-1163D01*
G01X944551D01*
G03X945872Y212222I-44J1575D01*
G02X947817Y213385I2015J-1162D01*
G01X947946D01*
G03X949252Y214172I-59J1575D01*
G02X951182Y215334I2015J-1163D01*
G01X951311D01*
G03X952632Y216122I-44J1575D01*
G02X954577Y217285I2015J-1162D01*
G01X954647D01*
G03X955998Y218050I0J1575D01*
G01X956011Y218073D01*
G02X957928Y219234I2015J-1164D01*
G01X958070D01*
G03X959391Y220022I-44J1575D01*
G02X961336Y221185I2015J-1162D01*
G01X961465D01*
G03X962771Y221972I-59J1575D01*
G01X962837Y222088D01*
X964786Y224709D01*
G01X934570Y189437D02*
Y190551D01*
X936693Y192674D01*
Y199360D01*
G03X936382Y200522I-2326J0D01*
G01X936363Y200556D01*
G02X936382Y202097I1384J754D01*
G03Y204423I-2015J1163D01*
G02X937676Y206784I1365J787D01*
G01X937832D01*
G03X939762Y207946I-85J2325D01*
G02X941083Y208734I1365J-787D01*
G01X941178D01*
G03X943142Y209897I-51J2326D01*
G02X944448Y210684I1365J-788D01*
G01X944577D01*
G03X946522Y211847I-70J2325D01*
G02X947843Y212635I1365J-787D01*
G01X947972D01*
G03X949902Y213797I-85J2325D01*
G02X951208Y214584I1365J-788D01*
G01X951337D01*
G03X953282Y215747I-70J2325D01*
G02X954603Y216535I1365J-787D01*
G01X954745D01*
G03X956662Y217696I-98J2325D01*
G01X956675Y217719D01*
G02X958026Y218484I1351J-810D01*
G01X958096D01*
G03X960041Y219647I-70J2325D01*
G02X961362Y220435I1365J-787D01*
G01X961491D01*
G03X963421Y221597I-85J2325D01*
G02X964727Y222384I1365J-788D01*
G01X964856D01*
G03X966801Y223547I-70J2325D01*
G02X968122Y224335I1365J-787D01*
G01X968251D01*
G03X970181Y225497I-85J2325D01*
G01X970247Y225611D01*
X971546Y228610D01*
G01X963497Y203400D02*
X965015D01*
X972316Y210701D01*
Y212325D01*
X973474Y213483D01*
Y216439D01*
X975961Y218926D01*
Y221399D01*
X976291Y221972D01*
G03X976310Y223513I-1365J787D01*
G01X976291Y223547D01*
X976266Y223589D01*
G02X976291Y225872I2040J1119D01*
G03X976310Y227413I-1365J787D01*
G01X976291Y227447D01*
G02X976266Y229730I2015J1164D01*
G01X976291Y229772D01*
G03Y231346I-1365J787D01*
G02Y233672I2015J1163D01*
G03X976310Y235213I-1365J787D01*
G01X976291Y235247D01*
X976266Y235289D01*
G02X976291Y237572I2040J1119D01*
G03X976310Y239113I-1365J787D01*
G01X976291Y239147D01*
X976266Y239189D01*
G02X976291Y241472I2040J1119D01*
G03X976310Y243013I-1365J787D01*
G01X976291Y243047D01*
X976266Y243089D01*
G02X976291Y245372I2040J1119D01*
G03X976310Y246913I-1365J787D01*
G01X976291Y246947D01*
X976266Y246989D01*
G02X976291Y249272I2040J1119D01*
G03Y250847I-1364J787D01*
G02Y253173I2015J1163D01*
G01X976307Y253201D01*
G02X978140Y255733I13166J-7602D01*
G01X978306Y255909D01*
G01X965732Y201765D02*
Y203059D01*
X973066Y210393D01*
Y212013D01*
X974224Y213171D01*
Y216128D01*
X976711Y218615D01*
Y221199D01*
X976941Y221597D01*
G03X976966Y223880I-2015J1164D01*
G01X976941Y223922D01*
X976922Y223956D01*
G02X976941Y225497I1384J754D01*
G03Y227823I-2015J1163D01*
G02Y229397I1365J787D01*
G01X976966Y229439D01*
G03X976941Y231722I-2040J1119D01*
G01X976922Y231756D01*
G02X976941Y233297I1384J754D01*
G03X976966Y235580I-2015J1164D01*
G01X976941Y235622D01*
X976922Y235656D01*
G02X976941Y237197I1384J754D01*
G03X976966Y239480I-2015J1164D01*
G01X976941Y239522D01*
X976922Y239556D01*
G02X976941Y241097I1384J754D01*
G03X976966Y243380I-2015J1164D01*
G01X976941Y243422D01*
X976922Y243456D01*
G02X976941Y244997I1384J754D01*
G03X976966Y247280I-2015J1164D01*
G01X976941Y247322D01*
X976922Y247356D01*
G02X976941Y248897I1384J754D01*
G03Y251223I-2017J1163D01*
G02Y252797I1365J787D01*
G02X978880Y254443I3267J-1884D01*
G03X979556Y256869I-574J1467D01*
G03X977702Y258355I-3490J-2454D01*
G02X976941Y260597I604J1455D01*
G03X976964Y260643I-395J226D01*
G01X978293Y263704D01*
X978306Y263709D01*
G01X954120Y204600D02*
X955511D01*
X960396Y209485D01*
X961406D01*
G03X962771Y210272I2J1574D01*
G02X964701Y211434I2015J-1163D01*
G01X965965D01*
X967447Y212916D01*
Y214293D01*
X972550Y219396D01*
X972911Y220021D01*
G03Y221597I-1365J788D01*
G02X972886Y223880I2015J1164D01*
G01X972911Y223922D01*
X972930Y223956D01*
G03X972911Y225497I-1384J754D01*
G02Y227823I2015J1163D01*
G03Y229397I-1365J787D01*
G01X972886Y229439D01*
G02X972911Y231722I2040J1119D01*
G01X972930Y231756D01*
G03X972911Y233297I-1384J754D01*
G02X972886Y235580I2015J1164D01*
G01X972911Y235622D01*
X972930Y235656D01*
G03X972911Y237197I-1384J754D01*
G02X972886Y239480I2015J1164D01*
G01X972911Y239522D01*
X972930Y239556D01*
G03X972911Y241097I-1384J754D01*
G02X972886Y243380I2015J1164D01*
G01X972911Y243422D01*
X972930Y243456D01*
G03X972911Y244997I-1384J754D01*
G02X972886Y247280I2015J1164D01*
G01X972911Y247322D01*
X972930Y247356D01*
G03X972911Y248897I-1384J754D01*
G02X972886Y251180I2015J1164D01*
G01X972911Y251222D01*
X972930Y251256D01*
G03X972911Y252797I-1384J754D01*
G02X972886Y255080I2015J1164D01*
G01X972911Y255122D01*
X972977Y255238D01*
X974926Y257860D01*
G01X956000Y202936D02*
Y204015D01*
X960720Y208735D01*
X961406D01*
G03X963421Y209897I2J2324D01*
G02X964727Y210684I1365J-788D01*
G01X966279D01*
X968197Y212602D01*
Y213979D01*
X973147Y218929D01*
X973561Y219646D01*
G03Y221972I-2015J1163D01*
G02X973542Y223513I1365J787D01*
G01X973561Y223547D01*
X973586Y223589D01*
G03X973561Y225872I-2040J1119D01*
G02X973542Y227413I1365J787D01*
G01X973561Y227447D01*
G03X973586Y229730I-2015J1164D01*
G01X973561Y229772D01*
G02Y231346I1365J787D01*
G03Y233672I-2015J1163D01*
G02X973542Y235213I1365J787D01*
G01X973561Y235247D01*
X973586Y235289D01*
G03X973561Y237572I-2040J1119D01*
G02X973542Y239113I1365J787D01*
G01X973561Y239147D01*
X973586Y239189D01*
G03X973561Y241472I-2040J1119D01*
G02X973542Y243013I1365J787D01*
G01X973561Y243047D01*
X973586Y243089D01*
G03X973561Y245372I-2040J1119D01*
G02X973542Y246913I1365J787D01*
G01X973561Y246947D01*
X973586Y246989D01*
G03X973561Y249272I-2040J1119D01*
G02X973542Y250813I1365J787D01*
G01X973561Y250847D01*
X973586Y250889D01*
G03X973561Y253172I-2040J1119D01*
G02X974360Y255431I1365J788D01*
G01X976034Y256626D01*
X976291Y257072D01*
G03X976310Y258613I-1365J787D01*
G01X976223Y258764D01*
X974926Y261760D01*
G01X977976Y195431D02*
X978846Y196301D01*
Y196821D01*
X978231Y197436D01*
Y202346D01*
X983060Y207175D01*
Y212663D01*
X986311Y215914D01*
X986431Y216122D01*
G03X986450Y217663I-1365J787D01*
G01X986431Y217697D01*
X986406Y217739D01*
G02X986431Y220022I2040J1119D01*
G01X986450Y220056D01*
G03X986431Y221597I-1384J754D01*
G02X986406Y223880I2015J1164D01*
G01X986431Y223922D01*
X986450Y223956D01*
G03X986431Y225497I-1384J754D01*
G02Y227823I2015J1163D01*
G03Y229397I-1365J787D01*
G01X986406Y229439D01*
G02X986431Y231722I2040J1119D01*
G01X986450Y231756D01*
G03X986431Y233297I-1384J754D01*
G02X986406Y235580I2015J1164D01*
G01X986431Y235622D01*
X986450Y235656D01*
G03X986431Y237197I-1384J754D01*
G02X986406Y239480I2015J1164D01*
G01X986431Y239522D01*
X986450Y239556D01*
G03X986431Y241097I-1384J754D01*
G02X986406Y243380I2015J1164D01*
G01X986431Y243422D01*
X986450Y243456D01*
G03X986431Y244997I-1384J754D01*
G02X986406Y247280I2015J1164D01*
G01X986431Y247322D01*
X986450Y247356D01*
G03X986431Y248897I-1384J754D01*
G02Y251223I2017J1163D01*
G03Y252797I-1365J787D01*
G02X986300Y253061I2014J1164D01*
G01X985066Y255909D01*
G01X980326Y195421D02*
X979594Y196153D01*
Y197134D01*
X978981Y197747D01*
Y202034D01*
X983810Y206863D01*
Y212351D01*
X986911Y215452D01*
X987081Y215747D01*
G03X987106Y218030I-2015J1164D01*
G01X987081Y218072D01*
X987062Y218106D01*
G02X987081Y219647I1384J754D01*
G01X987106Y219689D01*
G03X987081Y221972I-2040J1119D01*
G02X987062Y223513I1365J787D01*
G01X987081Y223547D01*
X987106Y223589D01*
G03X987081Y225872I-2040J1119D01*
G02X987062Y227413I1365J787D01*
G01X987081Y227447D01*
G03X987106Y229730I-2015J1164D01*
G01X987081Y229772D01*
G02Y231346I1365J787D01*
G03Y233672I-2015J1163D01*
G02X987062Y235213I1365J787D01*
G01X987081Y235247D01*
X987106Y235289D01*
G03X987081Y237572I-2040J1119D01*
G02X987062Y239113I1365J787D01*
G01X987081Y239147D01*
X987106Y239189D01*
G03X987081Y241472I-2040J1119D01*
G02X987062Y243013I1365J787D01*
G01X987081Y243047D01*
X987106Y243089D01*
G03X987081Y245372I-2040J1119D01*
G02X987062Y246913I1365J787D01*
G01X987081Y246947D01*
X987106Y246989D01*
G03X987081Y249272I-2040J1119D01*
G02Y250847I1364J787D01*
G03Y253173I-2015J1163D01*
G02Y254747I1365J787D01*
G03Y257073I-2015J1163D01*
G02X986618Y259540I3278J1892D01*
G03X986431Y260597I-1552J270D01*
G01X985066Y263709D01*
G01X924749Y197181D02*
X924792Y197257D01*
X924733Y197469D01*
X926267Y200192D01*
G03X926242Y202472I-2040J1118D01*
G02X927536Y204834I1365J788D01*
G01X927677D01*
G03X929622Y208322I-70J2325D01*
G01X929603Y208356D01*
G02X930928Y210684I1384J753D01*
G01X931057D01*
G03X933002Y211847I-70J2325D01*
G02X934323Y212635I1365J-787D01*
G01X934452D01*
G03X936382Y213797I-85J2325D01*
G02X937688Y214584I1365J-788D01*
G01X937817D01*
G03X939762Y215747I-70J2325D01*
G02X941083Y216535I1365J-787D01*
G01X941212D01*
G03X943142Y217697I-85J2325D01*
G02X944448Y218484I1365J-788D01*
G01X944577D01*
G03X946522Y219647I-70J2325D01*
G02X947843Y220435I1365J-787D01*
G01X947972D01*
G03X949902Y221597I-85J2325D01*
G02X951208Y222384I1365J-788D01*
G01X951337D01*
G03X953282Y223547I-70J2325D01*
G02X954603Y224335I1365J-787D01*
G01X954745D01*
G03X956662Y225496I-98J2325D01*
G01X956675Y225519D01*
G02X958026Y226284I1351J-810D01*
G01X958077D01*
G03X958524Y226337I-49J2326D01*
G01X961406Y226660D01*
G01X969300Y198488D02*
X969362Y198550D01*
Y198770D01*
X972079Y201487D01*
X972776Y202696D01*
Y204770D01*
X977606Y209600D01*
Y215491D01*
X978493Y216378D01*
X980346Y219689D01*
G03X980321Y221972I-2040J1119D01*
G02X980302Y223513I1365J787D01*
G01X980321Y223547D01*
X980346Y223589D01*
G03X980321Y225872I-2040J1119D01*
G02X980302Y227413I1365J787D01*
G01X980321Y227447D01*
G03X980346Y229730I-2015J1164D01*
G01X980321Y229772D01*
G02Y231346I1365J787D01*
G03Y233672I-2015J1163D01*
G02X980302Y235213I1365J787D01*
G01X980321Y235247D01*
X980346Y235289D01*
G03X980321Y237572I-2040J1119D01*
G02X980302Y239113I1365J787D01*
G01X980321Y239147D01*
X980346Y239189D01*
G03X980321Y241472I-2040J1119D01*
G02X980302Y243013I1365J787D01*
G01X980321Y243047D01*
X980346Y243089D01*
G03X980321Y245372I-2040J1119D01*
G02X980302Y246913I1365J787D01*
G01X980321Y246947D01*
X980346Y246989D01*
G03X980321Y249272I-2040J1119D01*
G02X980302Y250813I1365J787D01*
G01X980305Y250818D01*
X980307Y250822D01*
X980309Y250825D01*
X980312Y250830D01*
X980318Y250842D01*
X980346Y250889D01*
G03X980835Y251887I-10368J5699D01*
G01X981725Y253943D01*
X981686Y253960D01*
G01X930741Y197119D02*
X930803Y197181D01*
Y197399D01*
X932308Y198904D01*
X933027Y200189D01*
G03X933002Y202472I-2040J1119D01*
G02X932983Y204013I1365J787D01*
G01X933002Y204047D01*
G03X933027Y206330I-2015J1164D01*
G01X933002Y206372D01*
G02X934323Y208734I1365J787D01*
G01X934418D01*
G03X936382Y209897I-51J2326D01*
G02X937688Y210684I1365J-788D01*
G01X937817D01*
G03X939762Y211847I-70J2325D01*
G02X941083Y212635I1365J-787D01*
G01X941212D01*
G03X943142Y213797I-85J2325D01*
G02X944448Y214584I1365J-788D01*
G01X944577D01*
G03X946522Y215747I-70J2325D01*
G02X947843Y216535I1365J-787D01*
G01X947972D01*
G03X949902Y217697I-85J2325D01*
G02X951208Y218484I1365J-788D01*
G01X951337D01*
G03X953282Y219647I-70J2325D01*
G02X954603Y220435I1365J-787D01*
G01X954745D01*
G03X956662Y221596I-98J2325D01*
G01X956675Y221619D01*
G02X958026Y222384I1351J-810D01*
G01X958096D01*
G03X960041Y223547I-70J2325D01*
G02X961362Y224335I1365J-787D01*
G01X961491D01*
G03X963421Y225497I-85J2325D01*
G02X964727Y226284I1365J-788D01*
G01X964837D01*
G03X966801Y227447I-51J2326D01*
G02X968095Y228234I1365J-787D01*
G01X968236D01*
G03X970298Y231492I-69J2325D01*
G01X970392Y231844D01*
X971546Y232509D01*
G01X975468Y196281D02*
X975530Y196343D01*
Y196563D01*
X976133Y197166D01*
Y203447D01*
X980784Y208098D01*
Y213028D01*
X981826Y214070D01*
Y215710D01*
X983547Y217431D01*
X983701Y217697D01*
G03X983726Y219980I-2015J1164D01*
G01X983701Y220022D01*
X983682Y220056D01*
G02X983701Y221597I1384J754D01*
G03X983726Y223880I-2015J1164D01*
G01X983701Y223922D01*
X983682Y223956D01*
G02X983701Y225497I1384J754D01*
G03Y227823I-2015J1163D01*
G02Y229397I1365J787D01*
G01X983726Y229439D01*
G03X983701Y231722I-2040J1119D01*
G01X983682Y231756D01*
G02X983701Y233297I1384J754D01*
G03X983726Y235580I-2015J1164D01*
G01X983701Y235622D01*
X983682Y235656D01*
G02X983701Y237197I1384J754D01*
G03X983726Y239480I-2015J1164D01*
G01X983701Y239522D01*
X983682Y239556D01*
G02X983701Y241097I1384J754D01*
G03X983726Y243380I-2015J1164D01*
G01X983701Y243422D01*
X983682Y243456D01*
G02X983701Y244997I1384J754D01*
G03X983726Y247280I-2015J1164D01*
G01X983701Y247322D01*
X983682Y247356D01*
G02X983701Y248897I1384J754D01*
G03X983726Y251180I-2015J1164D01*
G01X983701Y251222D01*
X983682Y251256D01*
G02X983701Y252797I1384J754D01*
G03X983726Y255080I-2015J1164D01*
G01X983701Y255122D01*
X983682Y255156D01*
G02X983701Y256697I1384J754D01*
G03X983726Y258980I-2015J1164D01*
G01X983701Y259022D01*
X983682Y259056D01*
G02X983701Y260597I1384J754D01*
G03X981943Y264072I-2015J1163D01*
G01X981686Y264329D01*
Y265660D01*
G01X923826Y197703D02*
X923869Y197779D01*
X924079Y197837D01*
X925611Y200556D01*
G03X925592Y202097I-1384J754D01*
G02X927520Y205584I2014J1163D01*
G01X927664D01*
G03X928972Y207947I-57J1575D01*
G01X928969Y207951D01*
X928946Y207993D01*
G02X930915Y211434I2041J1116D01*
G01X931044D01*
G03X932352Y212222I-57J1575D01*
G02X934313Y213385I2015J-1162D01*
G01X934436D01*
G03X935732Y214172I-69J1575D01*
G02X937675Y215334I2015J-1163D01*
G01X937804D01*
G03X939112Y216122I-57J1575D01*
G02X941073Y217285I2015J-1162D01*
G01X941196D01*
G03X942492Y218072I-69J1575D01*
G02X944435Y219234I2015J-1163D01*
G01X944564D01*
G03X945872Y220022I-57J1575D01*
G02X947833Y221185I2015J-1162D01*
G01X947956D01*
G03X949252Y221972I-69J1575D01*
G02X951195Y223134I2015J-1163D01*
G01X951324D01*
G03X952632Y223922I-57J1575D01*
G02X954593Y225085I2015J-1162D01*
G01X954727D01*
G03X956010Y225869I-81J1575D01*
G01X956026Y225896D01*
G02X958026Y227034I2000J-1188D01*
G01X958068D01*
G03X959235Y227600I-43J1575D01*
G02X959906Y227991I1077J-1077D01*
G01X960409Y228130D01*
X961086Y228236D01*
X961968D01*
X964786Y228610D01*
G01X968550Y199238D02*
X968612Y199300D01*
X968830D01*
X971478Y201948D01*
X972026Y202897D01*
Y205081D01*
X976856Y209911D01*
Y215802D01*
X977889Y216835D01*
X979689Y220053D01*
G03X979672Y221596I-1383J756D01*
G01X979671Y221597D01*
G02X979646Y223880I2015J1164D01*
G01X979671Y223922D01*
X979690Y223956D01*
G03X979671Y225497I-1384J754D01*
G02Y227823I2015J1163D01*
G03Y229397I-1365J787D01*
G01X979646Y229439D01*
G02X979671Y231722I2040J1119D01*
G01X979690Y231756D01*
G03X979671Y233297I-1384J754D01*
G02X979646Y235580I2015J1164D01*
G01X979671Y235622D01*
X979690Y235656D01*
G03X979671Y237197I-1384J754D01*
G02X979646Y239480I2015J1164D01*
G01X979671Y239522D01*
X979690Y239556D01*
G03X979671Y241097I-1384J754D01*
G02X979646Y243380I2015J1164D01*
G01X979671Y243422D01*
X979690Y243456D01*
G03X979671Y244997I-1384J754D01*
G02X979646Y247280I2015J1164D01*
G01X979671Y247322D01*
X979690Y247356D01*
G03X979671Y248897I-1384J754D01*
G02X979646Y251180I2015J1164D01*
G01X979667Y251217D01*
X979671Y251223D01*
G03X980160Y253568I-3319J1916D01*
G02X980321Y254747I1526J392D01*
G03X981679Y257845I-13361J7703D01*
G01X981686Y257852D01*
Y257860D01*
G01X929992Y197869D02*
X930054Y197931D01*
X930274D01*
X931704Y199361D01*
X932370Y200553D01*
G03X932352Y202097I-1383J756D01*
G02Y204423I2015J1163D01*
G03Y205997I-1365J787D01*
G01X932327Y206039D01*
G02X934316Y209485I2040J1120D01*
G01X934426D01*
G03X935732Y210272I-59J1575D01*
G02X937662Y211434I2015J-1163D01*
G01X937791D01*
G03X939112Y212222I-44J1575D01*
G02X941057Y213385I2015J-1162D01*
G01X941186D01*
G03X942492Y214172I-59J1575D01*
G02X944422Y215334I2015J-1163D01*
G01X944551D01*
G03X945872Y216122I-44J1575D01*
G02X947817Y217285I2015J-1162D01*
G01X947946D01*
G03X949252Y218072I-59J1575D01*
G02X951182Y219234I2015J-1163D01*
G01X951311D01*
G03X952632Y220022I-44J1575D01*
G02X954577Y221185I2015J-1162D01*
G01X954647D01*
G03X955998Y221950I0J1575D01*
G01X956011Y221973D01*
G02X957928Y223134I2015J-1164D01*
G01X958070D01*
G03X959391Y223922I-44J1575D01*
G02X961336Y225085I2015J-1162D01*
G01X961465D01*
G03X962771Y225872I-59J1575D01*
G02X964735Y227035I2015J-1163D01*
G01X964830D01*
G03X966151Y227823I-44J1575D01*
G02X968081Y228985I2015J-1163D01*
G01X968237D01*
G03X969630Y231140I-71J1574D01*
G01X969320Y231224D01*
X968166Y230559D01*
G01X974718Y197031D02*
Y197030D01*
X974779Y197091D01*
X974997D01*
X975383Y197477D01*
Y203758D01*
X980034Y208409D01*
Y213339D01*
X981076Y214381D01*
Y216021D01*
X982947Y217892D01*
X983051Y218072D01*
G03X983070Y219613I-1365J787D01*
G01X983051Y219647D01*
X983026Y219689D01*
G02X983051Y221972I2040J1119D01*
G03X983070Y223513I-1365J787D01*
G01X983051Y223547D01*
X983026Y223589D01*
G02X983051Y225872I2040J1119D01*
G03X983070Y227413I-1365J787D01*
G01X983051Y227447D01*
G02X983026Y229730I2015J1164D01*
G01X983051Y229772D01*
G03Y231346I-1365J787D01*
G02Y233672I2015J1163D01*
G03X983070Y235213I-1365J787D01*
G01X983051Y235247D01*
X983026Y235289D01*
G02X983051Y237572I2040J1119D01*
G03X983070Y239113I-1365J787D01*
G01X983051Y239147D01*
X983026Y239189D01*
G02X983051Y241472I2040J1119D01*
G03X983070Y243013I-1365J787D01*
G01X983051Y243047D01*
X983026Y243089D01*
G02X983051Y245372I2040J1119D01*
G03X983070Y246913I-1365J787D01*
G01X983051Y246947D01*
X983026Y246989D01*
G02X983051Y249272I2040J1119D01*
G03X983070Y250813I-1365J787D01*
G01X983051Y250847D01*
X983026Y250889D01*
G02X983051Y253172I2040J1119D01*
G03X983070Y254713I-1365J787D01*
G01X983051Y254747D01*
X983026Y254789D01*
G02X983051Y257072I2040J1119D01*
G03X983070Y258613I-1365J787D01*
G01X983051Y258647D01*
X983026Y258689D01*
G02X983051Y260972I2040J1119D01*
G03X981914Y263319I-1365J788D01*
G01X981686Y263091D01*
Y261760D01*
G01X960559Y365720D02*
X958960Y366683D01*
X958026D01*
G02X956024Y367822I-1J2328D01*
G01X956010Y367847D01*
X956011D01*
G03X954695Y368634I-1364J-787D01*
G01X954577D01*
G02X952632Y369797I70J2325D01*
G03X951338Y370584I-1365J-787D01*
G01X951182D01*
G02X949252Y371746I85J2325D01*
G03X947931Y372534I-1365J-787D01*
G01X947836D01*
G02X945872Y373697I51J2326D01*
G03X944566Y374484I-1365J-788D01*
G01X944437D01*
G02X942492Y375647I70J2325D01*
G03X941171Y376435I-1365J-787D01*
G01X941042D01*
G02X939112Y377597I85J2325D01*
G03X937806Y378384I-1365J-788D01*
G01X937677D01*
G02X935732Y379547I70J2325D01*
G03X934411Y380335I-1365J-787D01*
G01X934282D01*
G02X932352Y381497I85J2325D01*
G03X931046Y382284I-1365J-788D01*
G01X930917D01*
G02X928972Y383447I70J2325D01*
G03X927651Y384235I-1365J-787D01*
G01X927522D01*
G02X925592Y387723I85J2325D01*
G03Y389297I-1365J787D01*
G02Y391623I2015J1163D01*
G03Y393197I-1365J787D01*
G01X925567Y393239D01*
G02X925592Y395522I2040J1119D01*
G01X925611Y395556D01*
G03X924286Y397884I-1384J753D01*
G01X924157D01*
G02X922212Y399047I70J2325D01*
G01X921600Y400109D01*
Y402897D01*
X919900Y404597D01*
X918712D01*
G01X961406Y367060D02*
X959219Y367427D01*
X959132Y367435D01*
X958026D01*
G02X956675Y368200I0J1575D01*
G01X956662Y368223D01*
G03X954732Y369385I-2015J-1163D01*
G01X954576D01*
G02X953282Y370172I71J1574D01*
G03X951337Y371335I-2015J-1162D01*
G01X951196D01*
G02X949902Y372122I71J1574D01*
G03X947938Y373285I-2015J-1163D01*
G01X947828D01*
G02X946522Y374072I59J1575D01*
G03X944592Y375234I-2015J-1163D01*
G01X944463D01*
G02X943142Y376022I44J1575D01*
G03X941197Y377185I-2015J-1162D01*
G01X941068D01*
G02X939762Y377972I59J1575D01*
G03X937832Y379134I-2015J-1163D01*
G01X937703D01*
G02X936382Y379922I44J1575D01*
G03X934437Y381085I-2015J-1162D01*
G01X934308D01*
G02X933002Y381872I59J1575D01*
G03X931072Y383034I-2015J-1163D01*
G01X930943D01*
G02X929622Y383822I44J1575D01*
G03X927677Y384985I-2015J-1162D01*
G01X927563D01*
G02X926242Y387347I44J1575D01*
G03Y389673I-2015J1163D01*
G02Y391247I1365J787D01*
G03X926267Y393530I-2015J1164D01*
G01X926242Y393572D01*
G02Y395146I1365J787D01*
G03X924312Y398634I-2015J1163D01*
G01X924183D01*
G02X922862Y399422I44J1575D01*
G01X922348Y400314D01*
Y403207D01*
X920480Y405075D01*
Y406365D01*
G01X971546Y372909D02*
X968302Y373285D01*
X968107D01*
G02X966801Y374072I59J1575D01*
G01X966151Y375198D01*
G02Y376022I714J412D01*
G01X966170Y376056D01*
G03X964845Y378384I-1384J753D01*
G01X964716D01*
G02X962771Y379547I70J2325D01*
G03X961450Y380335I-1365J-787D01*
G01X961321D01*
G02X959391Y381497I85J2325D01*
G03X958085Y382284I-1365J-788D01*
G01X957956D01*
G02X956011Y383447I70J2325D01*
G01X955998Y383470D01*
G03X954647Y384235I-1351J-810D01*
G01X954562D01*
G02X952632Y385397I85J2325D01*
G03X951326Y386184I-1365J-788D01*
G01X951197D01*
G02X949252Y387347I70J2325D01*
G03X947931Y388135I-1365J-787D01*
G01X947802D01*
G02X945872Y391623I85J2325D01*
G03Y393197I-1365J787D01*
G01X945847Y393239D01*
G02X945872Y395522I2040J1119D01*
G01X945891Y395556D01*
G03X945872Y397097I-1384J754D01*
G02X945847Y399380I2015J1164D01*
G01X946261Y400118D01*
Y407036D01*
X938401Y414896D01*
X936511D01*
G01X968166Y374860D02*
X966867Y377859D01*
X966801Y377972D01*
G03X964871Y379134I-2015J-1163D01*
G01X964742D01*
G02X963421Y379922I44J1575D01*
G03X961476Y381085I-2015J-1162D01*
G01X961347D01*
G02X960041Y381872I59J1575D01*
G03X958111Y383034I-2015J-1163D01*
G01X958026D01*
G02X956675Y383799I0J1575D01*
G01X956662Y383822D01*
G03X954717Y384985I-2015J-1162D01*
G01X954588D01*
G02X953282Y385772I59J1575D01*
G03X951352Y386934I-2015J-1163D01*
G01X951223D01*
G02X949902Y387722I44J1575D01*
G03X947957Y388885I-2015J-1162D01*
G01X947828D01*
G02X946503Y391213I59J1575D01*
G01X946522Y391247D01*
G03X946547Y393530I-2015J1164D01*
G01X946522Y393572D01*
G02Y395146I1365J787D01*
G03Y397472I-2015J1163D01*
G02X946503Y399013I1365J787D01*
G01X947009Y399922D01*
Y407346D01*
X938279Y416076D01*
Y416664D01*
G01X961406Y363160D02*
X958200Y363531D01*
X958172Y363534D01*
X958026D01*
G02X956675Y364299I0J1575D01*
G01X956662Y364322D01*
G03X954717Y365485I-2015J-1162D01*
G01X954588D01*
G02X953282Y366272I59J1575D01*
G03X951318Y367435I-2015J-1163D01*
G01X951223D01*
G02X949902Y368223I44J1575D01*
G03X947972Y369385I-2015J-1163D01*
G01X947816D01*
G02X946522Y370172I71J1574D01*
G03X944577Y371335I-2015J-1162D01*
G01X944436D01*
G02X943142Y372122I71J1574D01*
G03X941178Y373285I-2015J-1163D01*
G01X941068D01*
G02X939762Y374072I59J1575D01*
G03X937832Y375234I-2015J-1163D01*
G01X937703D01*
G02X936382Y376022I44J1575D01*
G03X934437Y377185I-2015J-1162D01*
G01X934308D01*
G02X933002Y377972I59J1575D01*
G03X931072Y379134I-2015J-1163D01*
G01X930943D01*
G02X929622Y379922I44J1575D01*
G03X927677Y381085I-2015J-1162D01*
G01X927548D01*
G02X926242Y381872I59J1575D01*
G03X924278Y383035I-2015J-1163D01*
G01X924183D01*
G02X922862Y385397I44J1575D01*
G03Y387723I-2015J1163D01*
G02Y389297I1365J787D01*
G03Y391623I-2015J1163D01*
G02Y393197I1365J787D01*
G01X922887Y393239D01*
G03X920898Y396685I-2040J1120D01*
G01X920788D01*
G02X919482Y397472I59J1575D01*
G01X919457Y397508D01*
X918696Y398666D01*
X918376Y399152D01*
X917084Y400444D01*
Y401870D01*
G01X971546Y369010D02*
X968310Y369385D01*
X968095D01*
G02X966801Y370172I71J1574D01*
G03X964856Y371335I-2015J-1162D01*
G01X964715D01*
G02X963421Y372122I71J1574D01*
G01X962771Y373249D01*
G02Y374072I713J412D01*
G03X961450Y376435I-1365J788D01*
G01X961321D01*
G02X959391Y377597I85J2325D01*
G03X958085Y378384I-1365J-788D01*
G01X957956D01*
G02X956011Y379547I70J2325D01*
G01X955998Y379570D01*
G03X954647Y380335I-1351J-810D01*
G01X954562D01*
G02X952632Y381497I85J2325D01*
G03X951326Y382284I-1365J-788D01*
G01X951197D01*
G02X949252Y383447I70J2325D01*
G03X947931Y384235I-1365J-787D01*
G01X947802D01*
G02X945872Y385397I85J2325D01*
G03X944566Y386184I-1365J-788D01*
G01X944437D01*
G02X942492Y387347I70J2325D01*
G03X941171Y388135I-1365J-787D01*
G01X941042D01*
G02X939112Y391623I85J2325D01*
G03Y393197I-1365J787D01*
G01X939087Y393239D01*
G02X939112Y395522I2040J1119D01*
G01X939131Y395556D01*
G03X939112Y397097I-1384J754D01*
G02X939087Y399380I2015J1164D01*
G01X939112Y399422D01*
X939360Y399799D01*
Y405584D01*
X934153Y410791D01*
X932706D01*
G01X964786Y372909D02*
X963489Y375905D01*
X963421Y376022D01*
G03X961476Y377185I-2015J-1162D01*
G01X961347D01*
G02X960041Y377972I59J1575D01*
G03X958111Y379134I-2015J-1163D01*
G01X958026D01*
G02X956675Y379899I0J1575D01*
G01X956662Y379922D01*
G03X954717Y381085I-2015J-1162D01*
G01X954588D01*
G02X953282Y381872I59J1575D01*
G03X951352Y383034I-2015J-1163D01*
G01X951223D01*
G02X949902Y383822I44J1575D01*
G03X947957Y384985I-2015J-1162D01*
G01X947828D01*
G02X946522Y385772I59J1575D01*
G03X944592Y386934I-2015J-1163D01*
G01X944463D01*
G02X943142Y387722I44J1575D01*
G03X941197Y388885I-2015J-1162D01*
G01X941068D01*
G02X939743Y391213I59J1575D01*
G01X939762Y391247D01*
G03X939787Y393530I-2015J1164D01*
G01X939762Y393572D01*
G02Y395146I1365J787D01*
G03Y397472I-2015J1163D01*
G02X939743Y399013I1365J787D01*
G01X939766Y399054D01*
X940108Y399574D01*
Y405894D01*
X934724Y411278D01*
Y412309D01*
G01X978306Y337809D02*
X976357Y340431D01*
X976291Y340547D01*
X976266Y340589D01*
G02X976291Y342872I2040J1119D01*
G03X976310Y344413I-1365J787D01*
G01X976291Y344447D01*
X976266Y344489D01*
G02X976291Y346772I2040J1119D01*
G03X976310Y348313I-1365J787D01*
G01X976291Y348347D01*
X976266Y348389D01*
G02X976291Y350672I2040J1119D01*
G03X976310Y352213I-1365J787D01*
G01X976291Y352247D01*
X976266Y352289D01*
G02X976291Y354572I2040J1119D01*
G03X976310Y356113I-1365J787D01*
G01X976291Y356147D01*
X976266Y356189D01*
G02X976291Y358472I2040J1119D01*
G03X974970Y360835I-1365J788D01*
G01X974841D01*
G02X972886Y364280I85J2325D01*
G01X972911Y364322D01*
X972930Y364356D01*
G03X972911Y365897I-1384J754D01*
G02Y368223I2015J1163D01*
G03Y369797I-1365J787D01*
G01X972886Y369839D01*
G02X972911Y372122I2040J1119D01*
G01X972930Y372156D01*
G03X971605Y374484I-1384J753D01*
G01X971476D01*
G02X969531Y377972I70J2325D01*
G03X968210Y380335I-1365J788D01*
G01X968081D01*
G02X966151Y381497I85J2325D01*
G03X964845Y382284I-1365J-788D01*
G01X964716D01*
G02X962771Y383447I70J2325D01*
G03X961450Y384235I-1365J-787D01*
G01X961321D01*
G02X959366Y387680I85J2325D01*
G01X959781Y388417D01*
Y390016D01*
X956856Y392941D01*
Y396041D01*
X954856Y398041D01*
Y403009D01*
X953983Y403882D01*
G01X968166Y367060D02*
X969320Y366394D01*
X969403Y366084D01*
G02X968225Y365485I-1238J976D01*
G01X968107D01*
G02X966801Y366272I59J1575D01*
G03X964837Y367435I-2015J-1163D01*
G01X964742D01*
G02X963421Y368223I44J1575D01*
G03X961491Y369385I-2015J-1163D01*
G01X961335D01*
G02X960041Y370172I71J1574D01*
G03X958096Y371335I-2015J-1162D01*
G01X957978D01*
G02X956662Y372122I48J1574D01*
G03X954698Y373285I-2015J-1163D01*
G01X954588D01*
G02X953282Y374072I59J1575D01*
G03X951352Y375234I-2015J-1163D01*
G01X951223D01*
G02X949902Y376022I44J1575D01*
G03X947957Y377185I-2015J-1162D01*
G01X947828D01*
G02X946522Y377972I59J1575D01*
G03X944592Y379134I-2015J-1163D01*
G01X944463D01*
G02X943142Y379922I44J1575D01*
G03X941197Y381085I-2015J-1162D01*
G01X941068D01*
G02X939762Y381872I59J1575D01*
G03X937832Y383034I-2015J-1163D01*
G01X937703D01*
G02X936382Y383822I44J1575D01*
G03X934437Y384985I-2015J-1162D01*
G01X934308D01*
G02X933002Y385772I59J1575D01*
G03X931072Y386934I-2015J-1163D01*
G01X930943D01*
G02X929622Y389297I44J1575D01*
G03Y391623I-2015J1163D01*
G02Y393197I1365J787D01*
G01X929647Y393239D01*
G03X929622Y395522I-2040J1119D01*
G01X929603Y395556D01*
G02X929622Y397097I1384J754D01*
G03X929647Y399380I-2015J1164D01*
G01X929376Y399848D01*
Y403165D01*
X923286Y409255D01*
Y409474D01*
X923224Y409536D01*
G01X961406Y370959D02*
X960243Y372218D01*
X959391Y373697D01*
G03X958095Y374484I-1365J-788D01*
G01X957956D01*
G02X956011Y375647I70J2325D01*
G01X955998Y375670D01*
G03X954647Y376435I-1351J-810D01*
G01X954562D01*
G02X952632Y377597I85J2325D01*
G03X951326Y378384I-1365J-788D01*
G01X951197D01*
G02X949252Y379547I70J2325D01*
G03X947931Y380335I-1365J-787D01*
G01X947802D01*
G02X945872Y381497I85J2325D01*
G03X944566Y382284I-1365J-788D01*
G01X944437D01*
G02X942492Y383447I70J2325D01*
G03X941171Y384235I-1365J-787D01*
G01X941042D01*
G02X939112Y385397I85J2325D01*
G03X937806Y386184I-1365J-788D01*
G01X937677D01*
G02X935732Y387347I70J2325D01*
G03X934411Y388135I-1365J-787D01*
G01X934282D01*
G02X932352Y391623I85J2325D01*
G03Y393197I-1365J787D01*
G01X932327Y393239D01*
G02X932352Y395522I2040J1119D01*
G01X932371Y395556D01*
G03X932352Y397097I-1384J754D01*
G01X932351Y397098D01*
G02X932327Y399380I2016J1162D01*
G01X932576Y399834D01*
Y404492D01*
X924644Y412424D01*
X924423D01*
X924361Y412486D01*
G01X971546Y365109D02*
X970392Y365775D01*
X970040Y365680D01*
G02X968251Y364735I-1873J1380D01*
G01X968081D01*
G02X966151Y365897I85J2325D01*
G03X964845Y366684I-1365J-788D01*
G01X964735D01*
G02X962771Y367847I51J2326D01*
G03X961477Y368634I-1365J-787D01*
G01X961336D01*
G02X959391Y369797I70J2325D01*
G03X958097Y370584I-1365J-787D01*
G01X957941D01*
G02X956011Y371746I85J2325D01*
G01X955998Y371769D01*
G03X954647Y372534I-1351J-810D01*
G01X954596D01*
G02X952632Y373697I51J2326D01*
G03X951326Y374484I-1365J-788D01*
G01X951197D01*
G02X949252Y375647I70J2325D01*
G03X947931Y376435I-1365J-787D01*
G01X947802D01*
G02X945872Y377597I85J2325D01*
G03X944566Y378384I-1365J-788D01*
G01X944437D01*
G02X942492Y379547I70J2325D01*
G03X941171Y380335I-1365J-787D01*
G01X941042D01*
G02X939112Y381497I85J2325D01*
G03X937806Y382284I-1365J-788D01*
G01X937677D01*
G02X935732Y383447I70J2325D01*
G03X934411Y384235I-1365J-787D01*
G01X934282D01*
G02X932352Y385397I85J2325D01*
G03X931046Y386184I-1365J-788D01*
G01X930917D01*
G02X928972Y389672I70J2325D01*
G03X928991Y391213I-1365J787D01*
G01X928972Y391247D01*
G02X928947Y393530I2015J1164D01*
G01X928972Y393572D01*
G03Y395146I-1365J787D01*
G02Y397472I2015J1163D01*
G01X928973Y397473D01*
G03X928992Y399012I-1366J786D01*
G01X928626Y399647D01*
Y402854D01*
X922756Y408724D01*
X922536D01*
X922474Y408786D01*
G01X964786Y369010D02*
G02X962771Y371749I11250J10387D01*
G03X961978Y372430I-1365J-787D01*
G01X961626Y372580D01*
X960799Y372758D01*
X960041Y374072D01*
G03X958111Y375234I-2015J-1163D01*
G01X958026D01*
G02X956675Y375999I0J1575D01*
G01X956662Y376022D01*
G03X954717Y377185I-2015J-1162D01*
G01X954588D01*
G02X953282Y377972I59J1575D01*
G03X951352Y379134I-2015J-1163D01*
G01X951223D01*
G02X949902Y379922I44J1575D01*
G03X947957Y381085I-2015J-1162D01*
G01X947828D01*
G02X946522Y381872I59J1575D01*
G03X944592Y383034I-2015J-1163D01*
G01X944463D01*
G02X943142Y383822I44J1575D01*
G03X941197Y384985I-2015J-1162D01*
G01X941068D01*
G02X939762Y385772I59J1575D01*
G03X937832Y386934I-2015J-1163D01*
G01X937703D01*
G02X936382Y387722I44J1575D01*
G03X934437Y388885I-2015J-1162D01*
G01X934308D01*
G02X932983Y391213I59J1575D01*
G01X933002Y391247D01*
G03X933027Y393530I-2015J1164D01*
G01X933002Y393572D01*
G02Y395146I1365J787D01*
G03Y397472I-2015J1163D01*
G01X933001Y397473D01*
G02X932982Y399012I1366J786D01*
G01X933326Y399607D01*
Y404803D01*
X925173Y412956D01*
Y413175D01*
X925111Y413237D01*
G01X981686Y335860D02*
X980321Y338974D01*
G02X980249Y340407I1365J787D01*
G03X980188Y341602I-1197J538D01*
G01X979671Y342498D01*
G02Y344824I2015J1163D01*
G03Y346398I-1365J787D01*
G02Y348724I2015J1163D01*
G03Y350298I-1365J787D01*
G02Y352624I2015J1163D01*
G03Y354198I-1365J787D01*
G02Y356524I2015J1163D01*
G03Y358098I-1365J787D01*
G02Y360424I2015J1163D01*
G03X978308Y362784I-1363J786D01*
G01X978306D01*
G02X976291Y366274I0J2327D01*
G03Y367847I-1363J787D01*
G02X976266Y370130I2015J1164D01*
G01X976291Y370172D01*
G03Y371746I-1365J787D01*
G02Y374072I2015J1163D01*
G03X974970Y376435I-1365J788D01*
G01X974841D01*
G02X972886Y379880I85J2325D01*
G01X972911Y379922D01*
X972930Y379956D01*
G03X971605Y382284I-1384J753D01*
G01X971546D01*
G02X969531Y383447I0J2327D01*
G03X968210Y384235I-1365J-787D01*
G01X968081D01*
G02X966151Y385397I85J2325D01*
G03X964845Y386184I-1365J-788D01*
G01X964716D01*
G02X962459Y388489I70J2326D01*
G01Y392138D01*
X960056Y394541D01*
Y403653D01*
X959283Y404426D01*
G01X981686Y343660D02*
X980479Y346443D01*
G03X980321Y346774I-2172J-834D01*
G02Y348348I1365J787D01*
G03Y350674I-2015J1163D01*
G02Y352248I1365J787D01*
G03Y354574I-2015J1163D01*
G02Y356148I1365J787D01*
G03Y358474I-2015J1163D01*
G02Y360048I1365J787D01*
G03X978308Y363534I-2013J1162D01*
G01X978307D01*
G02X976941Y365898I0J1577D01*
G03Y368223I-2016J1162D01*
G02Y369797I1365J787D01*
G01X976966Y369839D01*
G03X976941Y372122I-2040J1119D01*
G01X976922Y372156D01*
G02X976941Y373697I1384J754D01*
G03X974996Y377185I-2015J1163D01*
G01X974867D01*
G02X973542Y379513I59J1575D01*
G01X973561Y379547D01*
X973586Y379589D01*
G03X971631Y383034I-2040J1120D01*
G01X971546D01*
G02X970181Y383822I0J1576D01*
G03X968236Y384985I-2015J-1162D01*
G01X968107D01*
G02X966801Y385772I59J1575D01*
G03X964871Y386934I-2015J-1163D01*
G01X964729D01*
G02X963209Y388493I57J1576D01*
G01Y392446D01*
X960804Y394851D01*
Y403447D01*
X961783Y404426D01*
G01X978306Y341709D02*
X977009Y344705D01*
X976922Y344856D01*
G02X976941Y346397I1384J754D01*
G03X976966Y348680I-2015J1164D01*
G01X976941Y348722D01*
X976922Y348756D01*
G02X976941Y350297I1384J754D01*
G03X976966Y352580I-2015J1164D01*
G01X976941Y352622D01*
X976922Y352656D01*
G02X976941Y354197I1384J754D01*
G03X976966Y356480I-2015J1164D01*
G01X976941Y356522D01*
X976922Y356556D01*
G02X976941Y358097I1384J754D01*
G03X974996Y361585I-2015J1163D01*
G01X974867D01*
G02X973542Y363913I59J1575D01*
G01X973561Y363947D01*
X973586Y363989D01*
G03X973561Y366272I-2040J1119D01*
G02X973542Y367813I1365J787D01*
G01X973561Y367847D01*
G03X973586Y370130I-2015J1164D01*
G01X973561Y370172D01*
G02Y371746I1365J787D01*
G03X971631Y375234I-2015J1163D01*
G01X971502D01*
G02X970181Y377597I44J1575D01*
G03X968236Y381085I-2015J1163D01*
G01X968107D01*
G02X966801Y381872I59J1575D01*
G03X964871Y383034I-2015J-1163D01*
G01X964742D01*
G02X963421Y383822I44J1575D01*
G03X961476Y384985I-2015J-1162D01*
G01X961347D01*
G02X960022Y387313I59J1575D01*
G01X960529Y388220D01*
Y390326D01*
X957604Y393251D01*
Y396351D01*
X955604Y398351D01*
Y403003D01*
X956483Y403882D01*
G01X988446Y335860D02*
X987147Y338859D01*
X987081Y338972D01*
G02X987062Y340513I1365J787D01*
G01X987081Y340547D01*
X987106Y340589D01*
G03X987081Y342872I-2040J1119D01*
G02X987062Y344413I1365J787D01*
G01X987729Y345571D01*
G02X988446Y345985I717J-414D01*
G01X988505D01*
G03X989830Y348313I-59J1575D01*
G01X989811Y348347D01*
X989786Y348389D01*
G02X989811Y350672I2040J1119D01*
G03X989830Y352213I-1365J787D01*
G01X989811Y352247D01*
X989786Y352289D01*
G02X989811Y354572I2040J1119D01*
G03X989830Y356113I-1365J787D01*
G01X989811Y356147D01*
X989786Y356189D01*
G02X989811Y358472I2040J1119D01*
G03X989830Y360013I-1365J787D01*
G01X989811Y360047D01*
X989786Y360089D01*
G02X989811Y362372I2040J1119D01*
G03X989830Y363913I-1365J787D01*
G01X989811Y363947D01*
X989786Y363989D01*
G02X989811Y366272I2040J1119D01*
G03X988517Y368634I-1365J788D01*
G01X988376D01*
G02X986431Y372122I70J2325D01*
G01X986450Y372156D01*
G03X986431Y373697I-1384J754D01*
G02X986406Y375980I2015J1164D01*
G01X986431Y376022D01*
X986450Y376056D01*
G03X986431Y377597I-1384J754D01*
G02X986406Y379880I2015J1164D01*
G01X986431Y379922D01*
X986450Y379956D01*
G03X985125Y382284I-1384J753D01*
G01X984775D01*
X984773Y382286D01*
X984491D01*
X984490Y382287D01*
X984103D01*
X982744Y383646D01*
Y387995D01*
X975708Y395031D01*
Y401289D01*
X973856Y403141D01*
Y405299D01*
X972983Y406172D01*
G01X985066Y337809D02*
Y336478D01*
X984838Y336250D01*
G02X983701Y338597I228J1559D01*
G03X983726Y340880I-2015J1164D01*
G01X983701Y340922D01*
X983682Y340956D01*
G02X983701Y342497I1384J754D01*
G03X983726Y344780I-2015J1164D01*
G01X983701Y344822D01*
X983682Y344856D01*
G02X983701Y346397I1384J754D01*
G03X983726Y348680I-2015J1164D01*
G01X983701Y348722D01*
X983682Y348756D01*
G02X983701Y350297I1384J754D01*
G03X983726Y352580I-2015J1164D01*
G01X983701Y352622D01*
X983682Y352656D01*
G02X983701Y354197I1384J754D01*
G03X983726Y356480I-2015J1164D01*
G01X983701Y356522D01*
X983682Y356556D01*
G02X983701Y358097I1384J754D01*
G03X983726Y360380I-2015J1164D01*
G01X983701Y360422D01*
X983682Y360456D01*
G02X983701Y361997I1384J754D01*
G03X981756Y365485I-2015J1163D01*
G01X981627D01*
G02X980302Y367813I59J1575D01*
G01X980321Y367847D01*
G03X980346Y370130I-2015J1164D01*
G01X980321Y370172D01*
G02Y371746I1365J787D01*
G03Y374072I-2015J1163D01*
G02X980302Y375613I1365J787D01*
G01X980321Y375647D01*
X980346Y375689D01*
G03X980321Y377972I-2040J1119D01*
G01X980320Y377973D01*
X979300Y379738D01*
X971546Y387492D01*
Y390413D01*
X969174Y392785D01*
X967420D01*
X967028Y393177D01*
X966576Y393959D01*
X965658Y395625D01*
Y406045D01*
X965813Y406200D01*
Y406287D01*
G01X985066Y345609D02*
G02X986431Y348724I14784J-4622D01*
G01X986435Y348731D01*
X986437Y348734D01*
X986450Y348756D01*
G03X986431Y350297I-1384J754D01*
G02X986406Y352580I2015J1164D01*
G01X986431Y352622D01*
X986450Y352656D01*
G03X986431Y354197I-1384J754D01*
G02X986406Y356480I2015J1164D01*
G01X986431Y356522D01*
X986450Y356556D01*
G03X986431Y358097I-1384J754D01*
G02X986406Y360380I2015J1164D01*
G01X986431Y360422D01*
X986450Y360456D01*
G03X986431Y361997I-1384J754D01*
G02X986406Y364280I2015J1164D01*
G01X986431Y364322D01*
X986450Y364356D01*
G03X985125Y366684I-1384J753D01*
G01X985015D01*
G02X983026Y370130I51J2326D01*
G01X983051Y370172D01*
G03Y371746I-1365J787D01*
G02Y374072I2015J1163D01*
G03X983070Y375613I-1365J787D01*
G01X983051Y375647D01*
X983026Y375689D01*
G02X983051Y377972I2040J1119D01*
G03X983070Y379513I-1365J787D01*
G01X982802Y379979D01*
X978806Y383975D01*
Y386530D01*
X968006Y397330D01*
Y403352D01*
X969138Y404484D01*
Y407918D01*
X968983Y408073D01*
Y408160D01*
G01X985066Y333909D02*
Y335240D01*
X984809Y335497D01*
G02X983051Y338972I257J2312D01*
G03X983070Y340513I-1365J787D01*
G01X983051Y340547D01*
X983026Y340589D01*
G02X983051Y342872I2040J1119D01*
G03X983070Y344413I-1365J787D01*
G01X983051Y344447D01*
X983026Y344489D01*
G02X983051Y346772I2040J1119D01*
G03X983070Y348313I-1365J787D01*
G01X983051Y348347D01*
X983026Y348389D01*
G02X983051Y350672I2040J1119D01*
G03X983070Y352213I-1365J787D01*
G01X983051Y352247D01*
X983026Y352289D01*
G02X983051Y354572I2040J1119D01*
G03X983070Y356113I-1365J787D01*
G01X983051Y356147D01*
X983026Y356189D01*
G02X983051Y358472I2040J1119D01*
G03X983070Y360013I-1365J787D01*
G01X983051Y360047D01*
X983026Y360089D01*
G02X983051Y362372I2040J1119D01*
G03X981730Y364735I-1365J788D01*
G01X981601D01*
G02X979671Y368223I85J2325D01*
G03Y369797I-1365J787D01*
G01X979646Y369839D01*
G02X979671Y372122I2040J1119D01*
G01X979690Y372156D01*
G03X979671Y373697I-1384J754D01*
G02X979646Y375980I2015J1164D01*
G01X979671Y376022D01*
X979690Y376056D01*
G03X979671Y377597I-1384J754D01*
G01X978700Y379277D01*
X970796Y387181D01*
Y390102D01*
X968863Y392035D01*
X967106D01*
X966432Y392709D01*
X966428Y392716D01*
X965923Y393590D01*
X964908Y395432D01*
Y406045D01*
X964753Y406200D01*
Y406287D01*
G01X985066Y341709D02*
G02X986431Y344824I14855J-4653D01*
G03X986628Y345815I-1365J786D01*
G02X987081Y348348I4215J553D01*
G01X987106Y348389D01*
G03X987081Y350672I-2040J1119D01*
G02X987062Y352213I1365J787D01*
G01X987081Y352247D01*
X987106Y352289D01*
G03X987081Y354572I-2040J1119D01*
G02X987062Y356113I1365J787D01*
G01X987081Y356147D01*
X987106Y356189D01*
G03X987081Y358472I-2040J1119D01*
G02X987062Y360013I1365J787D01*
G01X987081Y360047D01*
X987106Y360089D01*
G03X987081Y362372I-2040J1119D01*
G02X987062Y363913I1365J787D01*
G01X987081Y363947D01*
X987106Y363989D01*
G03X985117Y367435I-2040J1120D01*
G01X985022D01*
G02X983701Y369797I44J1575D01*
G01X983726Y369839D01*
G03X983701Y372122I-2040J1119D01*
G01X983682Y372156D01*
G02X983701Y373697I1384J754D01*
G03X983726Y375980I-2015J1164D01*
G01X983701Y376022D01*
X983682Y376056D01*
G02X983701Y377597I1384J754D01*
G03X983725Y379880I-2015J1163D01*
G01X983721Y379886D01*
X983403Y380439D01*
X979556Y384286D01*
Y386841D01*
X968756Y397641D01*
Y403041D01*
X969888Y404173D01*
Y407918D01*
X970043Y408073D01*
Y408160D01*
G01X982826Y194591D02*
X983656Y195421D01*
Y196041D01*
X981546Y198151D01*
Y200011D01*
X986086Y204551D01*
Y212006D01*
X987465Y213385D01*
X988505D01*
G03X989830Y215713I-59J1575D01*
G01X989811Y215747D01*
X989786Y215789D01*
G02X989811Y218072I2040J1119D01*
G03X989830Y219613I-1365J787D01*
G01X989811Y219647D01*
X989786Y219689D01*
G02X989811Y221972I2040J1119D01*
G03X989830Y223513I-1365J787D01*
G01X989811Y223547D01*
X989786Y223589D01*
G02X989811Y225872I2040J1119D01*
G03X989830Y227413I-1365J787D01*
G01X989811Y227447D01*
G02X989786Y229730I2015J1164D01*
G01X989811Y229772D01*
G03Y231346I-1365J787D01*
G02Y233672I2015J1163D01*
G03X989830Y235213I-1365J787D01*
G01X989811Y235247D01*
X989786Y235289D01*
G02X989811Y237572I2040J1119D01*
G03X989830Y239113I-1365J787D01*
G01X989811Y239147D01*
X989786Y239189D01*
G02X989811Y241472I2040J1119D01*
G03X989830Y243013I-1365J787D01*
G01X989811Y243047D01*
X989786Y243089D01*
G02X989811Y245372I2040J1119D01*
G03X989830Y246913I-1365J787D01*
G01X989811Y246947D01*
X989786Y246989D01*
G02X989811Y249272I2040J1119D01*
G03X989830Y250813I-1365J787D01*
G01X989811Y250847D01*
X989786Y250889D01*
G02X989811Y253172I2040J1119D01*
G03X989830Y254713I-1365J787D01*
G01X989743Y254864D01*
X988446Y257860D01*
G01X985326Y194591D02*
X984406Y195511D01*
Y196351D01*
X982296Y198461D01*
Y199701D01*
X986836Y204241D01*
Y211684D01*
X987787Y212635D01*
X988531D01*
G03X990486Y216080I-85J2325D01*
G01X990461Y216122D01*
X990442Y216156D01*
G02X990461Y217697I1384J754D01*
G03X990486Y219980I-2015J1164D01*
G01X990461Y220022D01*
X990442Y220056D01*
G02X990461Y221597I1384J754D01*
G03X990486Y223880I-2015J1164D01*
G01X990461Y223922D01*
X990442Y223956D01*
G02X990461Y225497I1384J754D01*
G03Y227823I-2015J1163D01*
G02Y229397I1365J787D01*
G01X990486Y229439D01*
G03X990461Y231722I-2040J1119D01*
G01X990442Y231756D01*
G02X990461Y233297I1384J754D01*
G03X990486Y235580I-2015J1164D01*
G01X990461Y235622D01*
X990442Y235656D01*
G02X990461Y237197I1384J754D01*
G03X990486Y239480I-2015J1164D01*
G01X990461Y239522D01*
X990442Y239556D01*
G02X990461Y241097I1384J754D01*
G03X990486Y243380I-2015J1164D01*
G01X990461Y243422D01*
X990442Y243456D01*
G02X990461Y244997I1384J754D01*
G03X990486Y247280I-2015J1164D01*
G01X990461Y247322D01*
X990442Y247356D01*
G02X990461Y248897I1384J754D01*
G03X990486Y251180I-2015J1164D01*
G01X990461Y251222D01*
X990442Y251256D01*
G02X990461Y252797I1384J754D01*
G03X990486Y255080I-2015J1164D01*
G01X990461Y255122D01*
X990442Y255156D01*
G02X990461Y256697I1384J754D01*
G03X990486Y258980I-2015J1164D01*
G01X990461Y259022D01*
X990395Y259138D01*
X988446Y261760D01*
G01X951267Y232509D02*
X948023Y232885D01*
X947828D01*
G02X946861Y233263I58J1575D01*
G01X945823Y233812D01*
X945013Y234084D01*
X944448D01*
G03X943142Y233297I59J-1575D01*
G02X941178Y232134I-2015J1163D01*
G01X941083D01*
G03X939762Y231346I44J-1575D01*
G02X937832Y230184I-2015J1163D01*
G01X937676D01*
G03X936382Y229397I71J-1574D01*
G02X934437Y228234I-2015J1162D01*
G01X934296D01*
G03X933002Y227447I71J-1574D01*
G02X931038Y226284I-2015J1163D01*
G01X930928D01*
G03X929622Y225497I59J-1575D01*
G02X927692Y224335I-2015J1163D01*
G01X927563D01*
G03X926242Y223547I44J-1575D01*
G02X924297Y222384I-2015J1162D01*
G01X921748D01*
G01X916669Y354984D02*
X917526D01*
G02X918832Y354197I-59J-1575D01*
G03X920762Y353035I2015J1163D01*
G01X920891D01*
G02X922212Y352247I-44J-1575D01*
G03X924157Y351084I2015J1162D01*
G01X924286D01*
G02X925592Y350297I-59J-1575D01*
G03X927522Y349135I2015J1163D01*
G01X927651D01*
G02X928972Y348347I-44J-1575D01*
G03X930917Y347184I2015J1162D01*
G01X931046D01*
G02X932352Y346397I-59J-1575D01*
G03X934282Y345235I2015J1163D01*
G01X934411D01*
G02X935732Y344447I-44J-1575D01*
G03X937677Y343284I2015J1162D01*
G01X937806D01*
G02X939112Y342497I-59J-1575D01*
G03X941042Y341335I2015J1163D01*
G01X941726D01*
X943566Y340446D01*
G03X944504Y340135I939J1261D01*
G01X944510D01*
G03X945872Y340922I0J1572D01*
G02X946587Y341335I715J-412D01*
G01X951267Y365109D02*
X948033Y364735D01*
X947802D01*
G02X945872Y365897I85J2325D01*
G03X944566Y366684I-1365J-788D01*
G01X944456D01*
G02X942492Y367847I51J2326D01*
G03X941198Y368634I-1365J-787D01*
G01X941057D01*
G02X939112Y369797I70J2325D01*
G03X937818Y370584I-1365J-787D01*
G01X937662D01*
G02X935732Y371746I85J2325D01*
G03X934411Y372534I-1365J-787D01*
G01X934316D01*
G02X932352Y373697I51J2326D01*
G03X931046Y374484I-1365J-788D01*
G01X930917D01*
G02X928972Y375647I70J2325D01*
G03X927651Y376435I-1365J-787D01*
G01X927522D01*
G02X925592Y377597I85J2325D01*
G03X924286Y378384I-1365J-788D01*
G01X924157D01*
G02X922212Y379547I70J2325D01*
G03X920891Y380335I-1365J-787D01*
G01X920047D01*
G02X918434Y383132I800J2325D01*
G01X968166Y363160D02*
X964932Y363534D01*
X964742D01*
G02X963421Y364322I44J1575D01*
G03X961476Y365485I-2015J-1162D01*
G01X961347D01*
G02X960559Y365720I63J1648D01*
G01X946587Y341335D02*
X947972D01*
G03X949902Y342497I-85J2325D01*
G01X949968Y342610D01*
X951267Y345609D01*
G01X991826Y337809D02*
X990529Y340805D01*
X990442Y340956D01*
G02X990461Y342497I1384J754D01*
G01X991109Y343620D01*
G02X991826Y344034I717J-414D01*
G01X991870D01*
G03X993191Y346397I-44J1575D01*
G02X993166Y348680I2015J1164D01*
G01X993191Y348722D01*
X993210Y348756D01*
G03X993191Y350297I-1384J754D01*
G02X993166Y352580I2015J1164D01*
G01X993191Y352622D01*
X993210Y352656D01*
G03X993191Y354197I-1384J754D01*
G02X993166Y356480I2015J1164D01*
G01X993191Y356522D01*
X993210Y356556D01*
G03X993191Y358097I-1384J754D01*
G02X993166Y360380I2015J1164D01*
G01X993191Y360422D01*
X993210Y360456D01*
G03X993191Y361997I-1384J754D01*
G02X993166Y364280I2015J1164D01*
G01X993191Y364322D01*
X993210Y364356D01*
G03X993191Y365897I-1384J754D01*
G02Y368223I2015J1163D01*
G03X991897Y370584I-1365J787D01*
G01X991741D01*
G02X989811Y374072I85J2325D01*
G03X989830Y375613I-1365J787D01*
G01X989811Y375647D01*
X989786Y375689D01*
G02X989811Y377972I2040J1119D01*
G03X989830Y379513I-1365J787D01*
G01X989811Y379547D01*
X989786Y379589D01*
G02X989811Y381872I2040J1119D01*
G03X989830Y383413I-1365J787D01*
G01X987340Y387733D01*
X979156Y395917D01*
Y404899D01*
X978356Y405699D01*
G01X991826Y341709D02*
X993775Y344331D01*
X993841Y344447D01*
X993866Y344489D01*
G03X993841Y346772I-2040J1119D01*
G02X993822Y348313I1365J787D01*
G01X993841Y348347D01*
X993866Y348389D01*
G03X993841Y350672I-2040J1119D01*
G02X993822Y352213I1365J787D01*
G01X993841Y352247D01*
X993866Y352289D01*
G03X993841Y354572I-2040J1119D01*
G02X993822Y356113I1365J787D01*
G01X993841Y356147D01*
X993866Y356189D01*
G03X993841Y358472I-2040J1119D01*
G02X993822Y360013I1365J787D01*
G01X993841Y360047D01*
X993866Y360089D01*
G03X993841Y362372I-2040J1119D01*
G02X993822Y363913I1365J787D01*
G01X993841Y363947D01*
X993866Y363989D01*
G03X993841Y366272I-2040J1119D01*
G02X993822Y367813I1365J787D01*
G01X993841Y367847D01*
G03X991896Y371335I-2015J1163D01*
G01X991755D01*
G02X990461Y373697I71J1574D01*
G03X990486Y375980I-2015J1164D01*
G01X990461Y376022D01*
X990442Y376056D01*
G02X990461Y377597I1384J754D01*
G03X990486Y379880I-2015J1164D01*
G01X990461Y379922D01*
X990442Y379956D01*
G02X990461Y381497I1384J754D01*
G03X990486Y383780I-2015J1164D01*
G01X987939Y388192D01*
X979904Y396227D01*
Y404899D01*
X980856Y405851D01*
G01X976456Y395341D02*
Y401641D01*
X974656Y403441D01*
Y405345D01*
X975483Y406172D01*
G01X991826Y384609D02*
X993123Y387605D01*
X993210Y387756D01*
G03X991845Y390085I-1384J753D01*
G01X991461D01*
X988817Y392729D01*
G01X1015485Y242260D02*
X1016785Y239260D01*
X1016850Y239148D01*
G02Y237574I-1365J-787D01*
G03Y235248I2015J-1163D01*
G02Y233674I-1365J-787D01*
G03Y231348I2015J-1163D01*
G02Y229774I-1365J-787D01*
G03Y227448I2015J-1163D01*
G02Y225874I-1365J-787D01*
G03Y223548I2015J-1163D01*
G02Y221974I-1365J-787D01*
G03Y219648I2015J-1163D01*
G02Y218074I-1365J-787D01*
G03Y215748I2015J-1163D01*
G02Y214174I-1365J-787D01*
G03X1016538Y213000I2015J-1164D01*
G01Y211662D01*
X1017100Y211100D01*
Y200699D01*
X1017726Y200073D01*
Y198724D01*
G01X995206Y242260D02*
X997155Y239638D01*
X997221Y239522D01*
G03X997794Y238947I1365J787D01*
G01X1005541Y234393D01*
X1006017Y234089D01*
X1006891Y233215D01*
X1007149Y231830D01*
Y214979D01*
G03X1007360Y214172I1576J-19D01*
G02X1007385Y211889I-2015J-1164D01*
G01X1007360Y211847D01*
X1007341Y211813D01*
G03X1007360Y210272I1384J-754D01*
G01X1008676Y208128D01*
Y204830D01*
X1009426Y201581D01*
Y199064D01*
G01X1001965Y246160D02*
X1005960D01*
X1007600Y247800D01*
X1009400D01*
X1010529Y246671D01*
Y244200D01*
G03X1012061Y242634I1576J9D01*
G01X1012411D01*
X1013910Y241135D01*
Y238405D01*
G03X1014120Y237574I1575J-44D01*
G02Y235248I-2015J-1163D01*
G03Y233674I1365J-787D01*
G02Y231348I-2015J-1163D01*
G03Y229774I1365J-787D01*
G02Y227448I-2015J-1163D01*
G03Y225874I1365J-787D01*
G02Y223548I-2015J-1163D01*
G03Y221974I1365J-787D01*
G02Y219648I-2015J-1163D01*
G03Y218074I1365J-787D01*
G02Y215748I-2015J-1163D01*
G03Y214174I1365J-787D01*
G01X1014500Y213554D01*
Y204703D01*
X1013900Y203668D01*
Y202200D01*
X1015687Y200413D01*
Y198554D01*
G01X995206Y246160D02*
X997155Y243538D01*
X997221Y243422D01*
G03X997788Y242850I1365J786D01*
G01X1008145Y236851D01*
X1008946Y236419D01*
X1010045Y235485D01*
X1010435Y234480D01*
Y204830D01*
X1011426Y200033D01*
Y198627D01*
G01X1008725Y246160D02*
X1010022Y243164D01*
X1010109Y243013D01*
G02X1010090Y241472I-1384J-754D01*
G03X1012035Y237984I2015J-1163D01*
G01X1012147D01*
X1012149Y237986D01*
G02X1013470Y235624I-44J-1575D01*
G03Y233298I2015J-1163D01*
G02Y231724I-1365J-787D01*
G03Y229398I2015J-1163D01*
G02Y227824I-1365J-787D01*
G03Y225498I2015J-1163D01*
G02Y223924I-1365J-787D01*
G03Y221598I2015J-1163D01*
G02Y220024I-1365J-787D01*
G03Y217698I2015J-1163D01*
G02Y216124I-1365J-787D01*
G03Y213798I2015J-1163D01*
G02X1013681Y212995I-1365J-788D01*
G01Y204788D01*
X1013100Y203785D01*
Y201200D01*
X1013476Y200824D01*
Y198651D01*
G01X990596Y200519D02*
Y201300D01*
X991826Y205210D01*
G01X995206Y207159D02*
X996826Y205539D01*
Y202627D01*
X994596Y200397D01*
Y199498D01*
G01X992596Y199608D02*
Y200796D01*
X993588Y201788D01*
Y207347D01*
X991826Y209109D01*
G01X996596Y199062D02*
Y200206D01*
X998586Y202196D01*
Y205210D01*
G01X1023726Y197381D02*
Y198081D01*
X1022104Y199704D01*
X1019610Y202197D01*
Y211291D01*
X1018865Y213009D01*
G01X999796Y199305D02*
Y200096D01*
X1000200Y200500D01*
Y208964D01*
G03X999950Y209896I-1864J0D01*
G02X999915Y212162I2015J1164D01*
G01X999950Y212222D01*
G03Y213796I-1364J787D01*
G02X999915Y216062I2015J1164D01*
G01X1000014Y216235D01*
X1001965Y218860D01*
G01X1025726Y196930D02*
Y197980D01*
X1020625Y203081D01*
Y213280D01*
X1018865Y216909D01*
G01X1001965Y222760D02*
X1003915Y220137D01*
X1003980Y220024D01*
G02Y217698I-2015J-1163D01*
G03X1003700Y216653I1811J-1045D01*
G01Y214542D01*
X1003330Y214172D01*
G03X1003305Y211889I2015J-1164D01*
G01X1003330Y211847D01*
X1003349Y211813D01*
G02X1003330Y210272I-1384J-754D01*
G01X1003239Y210114D01*
G03X1002700Y208100I3494J-2014D01*
G01Y202382D01*
X1003796Y201286D01*
Y200166D01*
G01X1001796Y199802D02*
Y200980D01*
X1001400Y201376D01*
Y207289D01*
G03X1000601Y210273I-5970J0D01*
G02Y211847I1364J787D01*
G01X1000636Y211907D01*
G03X1000601Y214173I-2050J1102D01*
G02X1001423Y216439I1364J787D01*
G01X1001756Y216561D01*
G03X1002600Y217100I-800J2183D01*
G03X1003279Y217985I-3014J3015D01*
G01X1003330Y218074D01*
G03X1002537Y220329I-1365J787D01*
G01X1000732Y221397D01*
X998586Y224709D01*
G01X1005796Y200081D02*
Y201404D01*
X1003700Y203500D01*
Y208863D01*
G02X1003980Y209897I2051J0D01*
G01X1004046Y210010D01*
X1005345Y213009D01*
G01X1018865Y240309D02*
X1017565Y237310D01*
X1017500Y237198D01*
G03Y235624I1365J-787D01*
G02Y233298I-2015J-1163D01*
G03Y231724I1365J-787D01*
G02Y229398I-2015J-1163D01*
G03Y227824I1365J-787D01*
G02Y225498I-2015J-1163D01*
G03Y223924I1365J-787D01*
G02Y221598I-2015J-1163D01*
G03Y220024I1365J-787D01*
G02Y217698I-2015J-1163D01*
G03Y216124I1365J-787D01*
G02Y213798I-2015J-1163D01*
G03X1017290Y212974I1365J-787D01*
G01Y212211D01*
X1018000Y211501D01*
Y201700D01*
X1019726Y199974D01*
Y198554D01*
G01X1022245Y207159D02*
Y203438D01*
X1024042Y201642D01*
X1029526Y196157D01*
Y192634D01*
X1028926Y192034D01*
Y191223D01*
G01X1022245Y211060D02*
Y211061D01*
X1023545Y208060D01*
X1023610Y207948D01*
G02X1023872Y206969I-1698J-979D01*
G01Y203818D01*
X1030926Y196764D01*
Y190630D01*
G01X1042056Y191624D02*
Y192936D01*
X1040900Y194092D01*
Y197000D01*
X1037400Y200500D01*
Y215700D01*
X1036191Y216909D01*
X1032385D01*
G01X1040056Y191575D02*
Y196444D01*
X1036200Y200300D01*
Y204498D01*
X1034100Y206598D01*
Y213600D01*
X1033000Y214700D01*
X1032237D01*
X1029824Y217113D01*
X1029005Y218860D01*
G01X1025625Y240309D02*
X1027300Y238634D01*
Y212400D01*
X1030579Y209121D01*
Y206309D01*
X1034200Y202688D01*
Y198720D01*
X1036126Y196794D01*
Y195037D01*
G01X1034126Y194697D02*
Y196538D01*
X1030574Y200090D01*
Y202825D01*
X1027900Y205500D01*
X1027500Y205899D01*
X1027300Y206099D01*
Y209660D01*
X1025960Y211000D01*
X1025408D01*
X1023926Y212482D01*
Y238698D01*
X1022245Y242260D01*
G01X1215172Y304405D02*
X1211841Y307736D01*
X1200041D01*
X1198577Y306272D01*
X1194929D01*
G03X1192984Y305109I70J-2325D01*
G02X1190254I-1365J787D01*
G03X1186224I-2015J-1162D01*
G02X1183494I-1365J787D01*
G03X1179464I-2015J-1162D01*
G02X1176734I-1365J787D01*
G03X1172704I-2015J-1162D01*
G02X1169988Y305086I-1365J787D01*
G01X1169975Y305109D01*
G03X1165945I-2015J-1162D01*
G02X1163215I-1365J787D01*
G03X1159185I-2015J-1162D01*
G02X1156455I-1365J787D01*
G03X1154510Y306272I-2015J-1162D01*
G01X1154381D01*
G02X1153075Y307059I59J1575D01*
G03X1149045I-2015J-1163D01*
G02X1146315I-1365J788D01*
G03X1144301Y308222I-2014J-1162D01*
G01X1144299D01*
G02X1142935Y309010I0J1575D01*
G03X1140923Y310172I-2012J-1161D01*
G01X1140917D01*
G03X1138905Y309010I0J-2323D01*
G02X1137541Y308222I-1364J787D01*
G01X1137539D01*
G03X1135525Y307059I0J-2325D01*
G02X1134219Y306272I-1365J788D01*
G01X1134101D01*
G02X1132795Y307059I59J1575D01*
G03X1130831Y308222I-2015J-1163D01*
G01X1130736D01*
G02X1129415Y309010I44J1575D01*
G03X1127656Y310160I-2015J-1162D01*
G01X1027980Y345950D02*
X1026070Y347860D01*
X1024360D01*
X1023085Y349135D01*
X1022201D01*
G03X1020880Y348347I44J-1575D01*
G02X1018935Y347184I-2015J1162D01*
G01X1018806D01*
G03X1017500Y346397I59J-1575D01*
G02X1015570Y345235I-2015J1163D01*
G01X1015400D01*
G02X1013470Y346397I85J2325D01*
G03X1012164Y347184I-1365J-788D01*
G01X1012046D01*
G03X1010740Y346397I59J-1575D01*
G02X1008810Y345235I-2015J1163D01*
G01X1008579D01*
X1005345Y345609D01*
G01X1022245Y390460D02*
X1023026Y391241D01*
Y393226D01*
X1031200Y401400D01*
Y408614D01*
X1032762Y410176D01*
Y411204D01*
G01X995206Y386560D02*
X993907Y389559D01*
X993841Y389672D01*
G02X993669Y390807I1365J787D01*
G01Y392831D01*
X992000Y394500D01*
X990800D01*
X989900Y395400D01*
Y397400D01*
X991961Y399461D01*
Y401161D01*
G01X1022245Y386560D02*
X1024026Y388341D01*
Y393126D01*
X1032000Y401100D01*
Y407240D01*
X1034762Y410002D01*
Y411284D01*
G01X998586Y388509D02*
Y389259D01*
X997528Y390317D01*
G03X997221Y391623I-2322J143D01*
G02X997012Y392403I1352J780D01*
G01Y393654D01*
X997962Y394604D01*
Y396007D01*
G01X991826Y380709D02*
X993123Y383705D01*
X993191Y383822D01*
G02X995136Y384985I2015J-1162D01*
G01X995265D01*
G03X996590Y387313I-59J1575D01*
G01X996571Y387347D01*
X996546Y387389D01*
G02X996571Y389672I2040J1119D01*
G03X996590Y391213I-1365J787D01*
G01X996571Y391247D01*
G02X996097Y392251I7091J3962D01*
G01X995962Y393037D01*
Y395968D01*
G01X1018865Y384609D02*
X1020162Y387605D01*
X1020249Y387756D01*
G03X1020230Y389297I-1384J754D01*
G02Y391623I2015J1163D01*
G03X1020500Y392700I-1753J1012D01*
G01Y393000D01*
X1029500Y402000D01*
Y404662D01*
X1027562Y406600D01*
Y410841D01*
G01X998586Y372909D02*
X998683Y373006D01*
G03X999763Y375613I-2607J2607D01*
G02X999915Y375962I2202J-752D01*
G01X999950Y376022D01*
G03Y377596I-1364J787D01*
G02X999915Y379862I2015J1164D01*
G01X999950Y379922D01*
G03Y381496I-1364J787D01*
G02X999915Y383762I2015J1164D01*
G01X999950Y383822D01*
G03Y385396I-1364J787D01*
G02X999915Y387662I2015J1164D01*
G01X999950Y387722D01*
G03X1000226Y389580I-2184J1274D01*
G01Y394781D01*
X1002526Y397081D01*
Y405606D01*
X1003162Y406242D01*
Y407821D01*
G01X1018865Y380709D02*
X1020300Y382144D01*
Y383300D01*
X1020927Y383927D01*
Y385597D01*
G03X1020880Y385772I-351J0D01*
G02X1020861Y387313I1365J787D01*
G01X1020880Y387347D01*
X1020905Y387389D01*
G03X1020880Y389672I-2040J1119D01*
G02X1020861Y391213I1365J787D01*
G02X1021500Y392000I2444J-1332D01*
G01Y392800D01*
X1030300Y401600D01*
Y406200D01*
X1029562Y406938D01*
Y410706D01*
G01X1007162Y407727D02*
Y406362D01*
X1004926Y404126D01*
Y396080D01*
X1002561Y393715D01*
Y388683D01*
X1003349Y387313D01*
G02X1003330Y385772I-1384J-754D01*
G03X1003305Y383489I2015J-1164D01*
G01X1003330Y383447D01*
X1003349Y383413D01*
G02X1003330Y381872I-1384J-754D01*
G03X1001965Y378760I13451J-7755D01*
G01Y374860D02*
X1000664Y377866D01*
X1000601Y377973D01*
G02Y379547I1364J787D01*
G01X1000636Y379607D01*
G03X1000601Y381873I-2050J1102D01*
G02Y383447I1364J787D01*
G01X1000636Y383507D01*
G03X1000601Y385773I-2050J1102D01*
G02Y387347I1364J787D01*
G03X1001376Y388694I-551038J317938D01*
G01Y394179D01*
X1003776Y396579D01*
Y404276D01*
X1005162Y405662D01*
Y407821D01*
G01X1005345Y384609D02*
X1004053Y387594D01*
X1004048Y387605D01*
X1003726Y388162D01*
Y393080D01*
X1005976Y395330D01*
Y403476D01*
X1009162Y406662D01*
Y407781D01*
G01X998586Y357309D02*
X999884Y360308D01*
X999950Y360422D01*
G03Y361996I-1364J787D01*
G02X999915Y364262I2015J1164D01*
G01X999950Y364322D01*
G03Y365896I-1364J787D01*
G02X1001880Y369385I2015J1164D01*
G01X1002036D01*
G03X1003330Y370172I-71J1574D01*
G02X1005275Y371335I2015J-1162D01*
G01X1005416D01*
G03X1006710Y373697I-71J1574D01*
G02X1006685Y375980I2015J1164D01*
G01X1006710Y376022D01*
X1006729Y376056D01*
G03X1006710Y377597I-1384J754D01*
G02X1006685Y379880I2015J1164D01*
G01X1006710Y379922D01*
X1006729Y379956D01*
G03X1007026Y381121I-2138J1165D01*
G01Y388530D01*
X1007826Y389330D01*
Y400326D01*
X1009000Y401500D01*
G01X1015485Y355360D02*
X1016713Y358194D01*
G02X1016850Y358472I2151J-887D01*
G03Y360046I-1365J787D01*
G02Y362372I2015J1163D01*
G03Y363946I-1365J787D01*
G02Y366272I2015J1163D01*
G03Y367846I-1365J787D01*
G02Y370172I2015J1163D01*
G03Y371746I-1365J787D01*
G02Y374072I2015J1163D01*
G03Y375646I-1365J787D01*
G02Y377972I2015J1163D01*
G03Y379546I-1365J787D01*
G02Y381872I2015J1163D01*
G03Y383446I-1365J787D01*
G02X1016100Y386248I4861J2802D01*
G01Y394300D01*
X1016650Y394850D01*
G01X988446Y343660D02*
X990395Y346281D01*
X990461Y346397D01*
G03X990486Y348680I-2015J1164D01*
G01X990461Y348722D01*
X990442Y348756D01*
G02X990461Y350297I1384J754D01*
G03X990486Y352580I-2015J1164D01*
G01X990461Y352622D01*
X990442Y352656D01*
G02X990461Y354197I1384J754D01*
G03X990486Y356480I-2015J1164D01*
G01X990461Y356522D01*
X990442Y356556D01*
G02X990461Y358097I1384J754D01*
G03X990486Y360380I-2015J1164D01*
G01X990461Y360422D01*
X990442Y360456D01*
G02X990461Y361997I1384J754D01*
G03X990486Y364280I-2015J1164D01*
G01X990461Y364322D01*
X990442Y364356D01*
G02X990461Y365897I1384J754D01*
G03X988531Y369385I-2015J1163D01*
G01X988375D01*
G02X987081Y371746I71J1574D01*
G03Y374072I-2015J1163D01*
G02X987062Y375613I1365J787D01*
G01X987081Y375647D01*
X987106Y375689D01*
G03X987081Y377972I-2040J1119D01*
G02X987062Y379513I1365J787D01*
G01X987081Y379547D01*
X987106Y379589D01*
G03X985151Y383034I-2040J1120D01*
G01X984801D01*
X984800Y383035D01*
X984413D01*
X983492Y383956D01*
Y388305D01*
X976456Y395341D01*
G01X1018865Y357309D02*
X1018500Y358135D01*
X1017725Y359888D01*
G03X1017500Y360422I-2240J-629D01*
G02Y361996I1365J787D01*
G03Y364322I-2015J1163D01*
G02Y365896I1365J787D01*
G03Y368222I-2015J1163D01*
G02Y369796I1365J787D01*
G03Y372122I-2015J1163D01*
G02Y373696I1365J787D01*
G03Y376022I-2015J1163D01*
G02Y377596I1365J787D01*
G03Y379922I-2015J1163D01*
G02Y381496I1365J787D01*
G03Y383822I-2015J1163D01*
G02X1017200Y384942I1940J1120D01*
G01Y386300D01*
X1017222Y386322D01*
Y393021D01*
X1018300Y394099D01*
X1018800D01*
X1019301Y394600D01*
G01X1010575Y400225D02*
X1009336Y398986D01*
Y389015D01*
X1009326Y389005D01*
G03X1009610Y388205I2486J432D01*
G01X1010109Y387313D01*
G02X1010090Y385772I-1384J-754D01*
G03X1010065Y383489I2015J-1164D01*
G01X1010090Y383447D01*
X1010109Y383413D01*
G02X1010090Y381872I-1384J-754D01*
G03X1010065Y379589I2015J-1164D01*
G01X1010090Y379547D01*
X1010109Y379513D01*
G02X1010090Y377972I-1384J-754D01*
G03X1010065Y375689I2015J-1164D01*
G01X1010090Y375647D01*
X1010109Y375613D01*
G02X1010090Y374072I-1384J-754D01*
G03Y371746I2015J-1163D01*
G02X1008796Y369385I-1365J-787D01*
G01X1008640D01*
G03X1006710Y368223I85J-2325D01*
G02X1005389Y367435I-1365J787D01*
G01X1005294D01*
G03X1003330Y366272I51J-2326D01*
G01X1003264Y366159D01*
X1001965Y363160D01*
G01X1025625Y357309D02*
X1027435Y360389D01*
Y362503D01*
X1027431Y362507D01*
Y378766D01*
G02X1027621Y379513I1562J0D01*
G01X1027640Y379547D01*
X1027665Y379589D01*
G03X1027640Y381872I-2040J1119D01*
G02X1027621Y383413I1365J787D01*
G01X1027640Y383447D01*
X1027665Y383489D01*
G03X1027640Y385772I-2040J1119D01*
G02X1027621Y387313I1365J787D01*
G01X1027640Y387347D01*
X1027665Y387389D01*
G03X1027640Y389672I-2040J1119D01*
G02X1027621Y391213I1365J787D01*
G01X1027640Y391247D01*
X1028163Y392123D01*
X1028686Y392486D01*
X1029200Y393000D01*
X1030800D01*
X1032084Y394284D01*
G01X1022245Y355360D02*
X1023455Y358149D01*
G02X1023610Y358472I2169J-842D01*
G03X1023629Y360013I-1365J787D01*
G01X1023610Y360047D01*
X1023585Y360089D01*
G02X1023610Y362372I2040J1119D01*
G03Y363946I-1365J787D01*
G02Y366272I2015J1163D01*
G03Y367846I-1365J787D01*
G02Y370172I2015J1163D01*
G03Y371746I-1365J787D01*
G02Y374072I2015J1163D01*
G03Y375646I-1365J787D01*
G02X1025540Y379134I2015J1163D01*
G01X1025669D01*
G03X1026990Y381496I-44J1575D01*
G02Y383822I2015J1163D01*
G03Y385396I-1365J787D01*
G02Y387722I2015J1163D01*
G03Y389296I-1365J787D01*
G02Y391622I2015J1163D01*
G01X1028349Y393972D01*
X1029138Y394761D01*
G01X1012105Y357309D02*
X1013909Y360340D01*
Y367050D01*
G02X1014101Y367813I1576J9D01*
G01X1014120Y367847D01*
G03X1014145Y370130I-2015J1164D01*
G01X1014120Y370172D01*
G02Y371746I1365J787D01*
G03Y374072I-2015J1163D01*
G02X1014101Y375613I1365J787D01*
G01X1014120Y375647D01*
X1014145Y375689D01*
G03X1014120Y377972I-2040J1119D01*
G02X1014101Y379513I1365J787D01*
G01X1014120Y379547D01*
X1014145Y379589D01*
G03X1014120Y381872I-2040J1119D01*
G02X1014101Y383413I1365J787D01*
G01X1014926Y384853D01*
Y395976D01*
X1015275Y396325D01*
G01X1013754Y397654D02*
X1013200Y397100D01*
Y394200D01*
X1013704Y393696D01*
Y384239D01*
X1013470Y383822D01*
X1013445Y383780D01*
G03X1013470Y381497I2040J-1119D01*
G02X1013489Y379956I-1365J-787D01*
G01X1013470Y379922D01*
X1013445Y379880D01*
G03X1013470Y377597I2040J-1119D01*
G02X1013489Y376056I-1365J-787D01*
G01X1013470Y376022D01*
X1013445Y375980D01*
G03X1013470Y373697I2040J-1119D01*
G02X1013489Y372156I-1365J-787D01*
G01X1013470Y372122D01*
G03X1013445Y369839I2015J-1164D01*
G01X1013470Y369797D01*
G02X1012149Y367435I-1365J-787D01*
G01X1011968D01*
X1008725Y367060D01*
G01Y351460D02*
X1008716D01*
X1007151Y353025D01*
Y367067D01*
G02X1007341Y367813I1561J0D01*
G01X1007360Y367847D01*
G02X1008654Y368634I1365J-787D01*
G01X1008795D01*
G03X1010740Y372122I-70J2325D01*
G01X1010721Y372156D01*
G02X1010740Y373697I1384J754D01*
G03X1010765Y375980I-2015J1164D01*
G01X1010740Y376022D01*
X1010721Y376056D01*
G02X1010740Y377597I1384J754D01*
G03X1010765Y379880I-2015J1164D01*
G01X1010740Y379922D01*
X1010721Y379956D01*
G02X1010740Y381497I1384J754D01*
G03X1010765Y383780I-2015J1164D01*
G01X1010740Y383822D01*
X1010721Y383856D01*
G02X1010740Y385397I1384J754D01*
G03X1010766Y387676I-2015J1163D01*
G01X1010346Y388426D01*
Y389893D01*
X1010353Y389900D01*
Y397153D01*
X1011900Y398700D01*
G01X1049284Y207159D02*
X1051800Y204643D01*
Y198400D01*
X1057806Y192394D01*
Y191151D01*
G01X1042524Y211060D02*
X1041700Y210236D01*
Y208200D01*
X1040950Y207450D01*
Y200966D01*
X1043437Y198479D01*
X1047256Y191865D01*
Y190969D01*
G01X1045256Y191381D02*
Y193480D01*
X1042568Y198132D01*
X1040100Y200600D01*
Y207700D01*
X1040726Y208326D01*
Y209630D01*
X1039145Y213009D01*
G01X1045904D02*
X1047576Y209280D01*
Y207031D01*
X1048142Y205789D01*
X1050271Y204692D01*
X1051000Y203685D01*
Y197300D01*
X1055806Y192494D01*
Y190981D01*
G01X1052506Y191500D02*
Y193042D01*
X1049536Y196012D01*
X1047669Y202973D01*
X1044539Y208324D01*
G02Y209898I1365J787D01*
G03Y212224I-2015J1163D01*
G02Y213798I1365J787D01*
G01X1044604Y213910D01*
X1045904Y216909D01*
G01X1050506Y191694D02*
Y192929D01*
X1048806Y194629D01*
X1046800Y202457D01*
X1043578Y207780D01*
Y209180D01*
G02X1043889Y210274I2326J-70D01*
G03Y211848I-1365J787D01*
G02Y214174I2015J1163D01*
G03Y215748I-1365J787D01*
G01X1043824Y215860D01*
X1042524Y218860D01*
G01X1074565Y188577D02*
X1075266Y189278D01*
Y192229D01*
X1075878Y192841D01*
Y202351D01*
X1073185Y205044D01*
Y208021D01*
X1073417Y208253D01*
Y215172D01*
X1073778Y215533D01*
Y216196D01*
G03X1073567Y216984I-1575J1D01*
G02X1073542Y219267I2015J1164D01*
G01X1073567Y219309D01*
X1073586Y219343D01*
G03X1073567Y220884I-1384J754D01*
G02X1073542Y223167I2015J1164D01*
G01X1073567Y223209D01*
X1073586Y223243D01*
G03X1073567Y224784I-1384J754D01*
G02X1073542Y227067I2015J1164D01*
G01X1073567Y227109D01*
X1073586Y227143D01*
G03X1073566Y228683I-1385J752D01*
G02Y231009I2015J1163D01*
G01X1073582Y231037D01*
G02X1075415Y233569I13166J-7602D01*
G01X1075582Y233746D01*
G01X1077065Y188577D02*
X1076016Y189626D01*
Y191918D01*
X1076628Y192530D01*
Y202663D01*
X1076629Y202664D01*
X1073936Y205357D01*
Y205359D01*
X1073934Y205361D01*
Y207712D01*
X1074167Y207945D01*
Y214861D01*
X1074528Y215222D01*
Y216198D01*
G03X1074217Y217359I-2323J0D01*
G02X1074198Y218900I1365J787D01*
G01X1074217Y218934D01*
X1074242Y218976D01*
G03X1074217Y221259I-2040J1119D01*
G02X1074198Y222800I1365J787D01*
G01X1074217Y222834D01*
X1074242Y222876D01*
G03X1074217Y225159I-2040J1119D01*
G02X1074198Y226700I1365J787D01*
G01X1074217Y226734D01*
X1074242Y226776D01*
G03X1074216Y229059I-2046J1118D01*
G02Y230633I1365J787D01*
G02X1076155Y232279I3267J-1884D01*
G03X1076831Y234705I-574J1467D01*
G03X1074977Y236191I-3490J-2454D01*
G02X1074216Y238433I604J1455D01*
G01X1075582Y241547D01*
G01X1072202Y235696D02*
X1071061Y234471D01*
G03X1071013Y234406I256J-239D01*
G01X1070186Y232959D01*
G03Y230633I2015J-1163D01*
G02Y229059I-1364J-787D01*
G03X1070162Y226776I2015J-1163D01*
G01X1070187Y226734D01*
X1070206Y226700D01*
G02X1070187Y225159I-1384J-754D01*
G03X1070162Y222876I2015J-1164D01*
G01X1070187Y222834D01*
X1070206Y222800D01*
G02X1070187Y221259I-1384J-754D01*
G03X1070162Y218976I2015J-1164D01*
G01X1070187Y218934D01*
X1070206Y218900D01*
G02X1070187Y217359I-1384J-754D01*
G03X1070162Y215076I2015J-1164D01*
G01X1070187Y215034D01*
X1070397Y214649D01*
Y211302D01*
X1070166Y211071D01*
Y203801D01*
X1072858Y201109D01*
Y194093D01*
X1070606Y191841D01*
Y190618D01*
X1069565Y189577D01*
G01X1072202Y239596D02*
X1073501Y236597D01*
X1073567Y236484D01*
G02X1072649Y234185I-1365J-788D01*
G01X1071000Y232866D01*
X1070837Y232583D01*
G03Y231009I1364J-787D01*
G02Y228683I-2015J-1163D01*
G03X1070818Y227143I1363J-787D01*
G01X1070837Y227109D01*
X1070862Y227067D01*
G02X1070837Y224784I-2040J-1119D01*
G03X1070818Y223243I1365J-787D01*
G01X1070837Y223209D01*
X1070862Y223167D01*
G02X1070837Y220884I-2040J-1119D01*
G03X1070818Y219343I1365J-787D01*
G01X1070837Y219309D01*
X1070862Y219267D01*
G02X1070837Y216984I-2040J-1119D01*
G03X1070818Y215443I1365J-787D01*
G01X1071147Y214870D01*
Y210994D01*
X1070915Y210762D01*
Y204112D01*
X1073608Y201419D01*
Y193782D01*
X1071356Y191530D01*
Y190286D01*
X1072065Y189577D01*
G01X1087379Y185879D02*
X1088186Y186686D01*
Y189557D01*
X1086166Y191577D01*
Y204876D01*
X1083396Y207646D01*
Y212303D01*
G02X1083706Y213459I2312J0D01*
G03X1083725Y215000I-1365J787D01*
G01X1083706Y215034D01*
X1083681Y215076D01*
G02X1083706Y217359I2040J1119D01*
G03X1083725Y218900I-1365J787D01*
G01X1083706Y218934D01*
X1083681Y218976D01*
G02X1083706Y221259I2040J1119D01*
G03X1083725Y222800I-1365J787D01*
G01X1083706Y222834D01*
X1083681Y222876D01*
G02X1083706Y225159I2040J1119D01*
G03X1083725Y226700I-1365J787D01*
G01X1083706Y226734D01*
X1083681Y226776D01*
G02X1083706Y229059I2043J1119D01*
G03Y230633I-1365J787D01*
G01Y230634D01*
G02X1083589Y232730I2015J1164D01*
G01X1083495Y233081D01*
X1082341Y233746D01*
G01X1089879Y186121D02*
X1088936Y187064D01*
Y189868D01*
X1086914Y191890D01*
Y205186D01*
X1084146Y207954D01*
Y212300D01*
G02X1084356Y213084I1569J0D01*
G03X1084381Y215367I-2015J1164D01*
G01X1084356Y215409D01*
X1084337Y215443D01*
G02X1084356Y216984I1384J754D01*
G03X1084381Y219267I-2015J1164D01*
G01X1084356Y219309D01*
X1084339Y219339D01*
X1084337Y219343D01*
G02X1084356Y220884I1384J754D01*
G03X1084381Y223167I-2015J1164D01*
G01X1084356Y223209D01*
X1084337Y223243D01*
G02X1084356Y224784I1384J754D01*
G03X1084381Y227067I-2015J1164D01*
G01X1084356Y227109D01*
X1084337Y227143D01*
G02X1084356Y228683I1382J753D01*
G03Y231009I-2015J1163D01*
G02Y232583I1365J787D01*
G03Y234909I-2015J1163D01*
G02X1083893Y237376I3278J1892D01*
G03X1083706Y238433I-1552J270D01*
G01X1082341Y241547D01*
G01X1080905Y186013D02*
Y186100D01*
X1080750Y186255D01*
Y188208D01*
X1079649Y189309D01*
Y203916D01*
X1078105Y205460D01*
Y207942D01*
X1077311Y208736D01*
Y216488D01*
X1077597Y216984D01*
G03X1077622Y219267I-2015J1164D01*
G01X1077597Y219309D01*
X1077578Y219343D01*
G02X1077597Y220884I1384J754D01*
G03X1077622Y223167I-2015J1164D01*
G01X1077597Y223209D01*
X1077578Y223243D01*
G02X1077597Y224784I1384J754D01*
G03X1077622Y227067I-2015J1164D01*
G01X1077597Y227109D01*
X1077578Y227143D01*
G02X1077597Y228684I1384J754D01*
G03X1078955Y231782I-13361J7703D01*
G01X1078962Y231789D01*
Y231797D01*
G01X1084605Y186413D02*
Y186500D01*
X1084450Y186655D01*
Y189840D01*
X1082668Y191622D01*
Y205693D01*
X1081507Y206854D01*
Y208635D01*
X1080947Y209603D01*
G02X1080939Y209621I1434J648D01*
G02X1080976Y211131I1402J721D01*
G03X1081011Y213399I-2015J1165D01*
G01X1080976Y213459D01*
G02X1080945Y214978I1365J788D01*
G01X1081012Y215094D01*
G03X1080977Y217360I-2050J1102D01*
G02Y218934I1364J787D01*
G01X1081012Y218994D01*
G03X1080977Y221260I-2050J1102D01*
G02Y222834I1364J787D01*
G01X1081012Y222894D01*
G03X1080977Y225160I-2050J1102D01*
G02Y226734I1364J787D01*
G01X1081012Y226794D01*
G03X1080977Y229060I-2050J1102D01*
G02Y230634I1364J787D01*
G03X1081002Y232917I-2015J1164D01*
G01X1080977Y232959D01*
G02Y234533I1364J787D01*
G01X1081002Y234575D01*
G03X1080977Y236860I-2040J1120D01*
G02Y238434I1364J787D01*
G01X1081012Y238494D01*
G03X1079218Y241909I-2050J1102D01*
G01X1078962Y242165D01*
Y243496D01*
G01Y235696D02*
Y235688D01*
X1078955Y235681D01*
G02X1077597Y232583I-14719J4605D01*
G03X1077436Y231404I1365J-787D01*
G02X1076947Y229059I-3808J-429D01*
G03X1076922Y226776I2015J-1164D01*
G01X1076947Y226734D01*
X1076966Y226700D01*
G02X1076947Y225159I-1384J-754D01*
G03X1076922Y222876I2015J-1164D01*
G01X1076947Y222834D01*
X1076966Y222800D01*
G02X1076947Y221259I-1384J-754D01*
G03X1076922Y218976I2015J-1164D01*
G01X1076970Y218896D01*
G02X1076947Y217360I-1388J-747D01*
G01Y217359D01*
X1076561Y216689D01*
Y208425D01*
X1077355Y207631D01*
Y205149D01*
X1078899Y203605D01*
Y188998D01*
X1080000Y187897D01*
Y186255D01*
X1079845Y186100D01*
Y186013D01*
G01X1083545Y186413D02*
Y186500D01*
X1083700Y186655D01*
Y189529D01*
X1081918Y191311D01*
Y205382D01*
X1080757Y206543D01*
Y208433D01*
X1080291Y209239D01*
G02X1080326Y211507I2050J1103D01*
G03X1080345Y213050I-1365J788D01*
G01X1080326Y213084D01*
G02X1080301Y215367I2015J1164D01*
G01X1080326Y215409D01*
G03Y216983I-1364J787D01*
G02X1080291Y219249I2015J1164D01*
G01X1080326Y219309D01*
G03Y220883I-1364J787D01*
G02X1080291Y223149I2015J1164D01*
G01X1080326Y223209D01*
G03Y224783I-1364J787D01*
G02X1080291Y227049I2015J1164D01*
G01X1080326Y227109D01*
G03Y228683I-1364J787D01*
G02X1080301Y230968I2015J1165D01*
G01X1080326Y231010D01*
G03Y232584I-1364J787D01*
G01X1080301Y232626D01*
G02X1080326Y234909I2040J1119D01*
G03Y236483I-1364J787D01*
G02X1080291Y238749I2015J1164D01*
G01X1080326Y238809D01*
G03X1079189Y241154I-1364J787D01*
G01X1078962Y240927D01*
Y239596D01*
G01X1085721Y235696D02*
X1087019Y232699D01*
X1087086Y232584D01*
G02Y231010I-1365J-787D01*
G03Y228684I2015J-1163D01*
G02X1087105Y227143I-1365J-787D01*
G01X1087086Y227109D01*
X1087061Y227067D01*
G03X1087086Y224784I2040J-1119D01*
G02X1087105Y223243I-1365J-787D01*
G01X1087086Y223209D01*
X1087061Y223167D01*
G03X1087086Y220884I2040J-1119D01*
G02X1087105Y219343I-1365J-787D01*
G01X1087086Y219309D01*
X1087061Y219267D01*
G03X1087086Y216984I2040J-1119D01*
G02X1087105Y215443I-1365J-787D01*
G01X1087086Y215409D01*
X1087061Y215367D01*
G03X1087086Y213084I2040J-1119D01*
G02X1087105Y211543I-1365J-787D01*
G01X1087086Y211509D01*
G03X1086774Y210346I2015J-1164D01*
G01X1092379Y188577D02*
X1093136Y189334D01*
Y190378D01*
X1089016Y194498D01*
Y206295D01*
X1086774Y208537D01*
Y210346D01*
G01X1094879Y188577D02*
X1093886Y189570D01*
Y190690D01*
X1089766Y194810D01*
Y206608D01*
X1087525Y208849D01*
Y210346D01*
G02X1087717Y211099I1576J-1D01*
G01X1087736Y211133D01*
G03Y213459I-2015J1163D01*
G02X1087717Y215000I1365J787D01*
G01X1087736Y215034D01*
X1087761Y215076D01*
G03X1087736Y217359I-2040J1119D01*
G02X1087717Y218900I1365J787D01*
G01X1087736Y218934D01*
X1087761Y218976D01*
G03X1087736Y221259I-2040J1119D01*
G02X1087717Y222800I1365J787D01*
G01X1087736Y222834D01*
X1087761Y222876D01*
G03X1087736Y225159I-2040J1119D01*
G02X1087717Y226700I1365J787D01*
G01X1087736Y226734D01*
X1087761Y226776D01*
G03X1087736Y229059I-2040J1119D01*
G02X1087717Y230600I1365J787D01*
G01X1087736Y230634D01*
G03X1087761Y232917I-2015J1164D01*
G01X1087736Y232959D01*
G02Y234533I1365J787D01*
G03Y236859I-2015J1163D01*
G01X1087670Y236975D01*
X1085721Y239596D01*
G01X1045904Y384609D02*
X1051909D01*
X1054600Y387300D01*
Y393901D01*
X1061000Y400301D01*
Y401633D01*
G01X1042524Y386560D02*
X1040900Y388184D01*
Y391200D01*
X1043200Y393500D01*
G01X1039145Y384609D02*
Y386255D01*
X1037500Y387900D01*
Y389100D01*
X1042200Y393800D01*
G01X1049284Y390460D02*
X1051000Y392176D01*
Y393900D01*
X1051400Y394300D01*
X1053300D01*
X1059000Y400000D01*
Y401553D01*
G01X1045904Y380709D02*
X1044604Y383709D01*
X1044539Y383821D01*
G02Y385395I1365J787D01*
G01X1044761Y385780D01*
G02X1046700Y386900I1939J-1118D01*
G03X1047700Y387900I0J1000D01*
G01Y391600D01*
G01X1042524Y378760D02*
X1043824Y381759D01*
X1043889Y381871D01*
G03Y383445I-1365J787D01*
G02Y385771I2015J1163D01*
G03X1044099Y386595I-1365J787D01*
G01Y389295D01*
X1045700Y390896D01*
Y392507D01*
G01X1052664Y361209D02*
X1055200D01*
X1057700Y363709D01*
Y393600D01*
X1060650Y396550D01*
X1063250D01*
X1066201Y399501D01*
Y401566D01*
G01X1076702Y364396D02*
X1074753Y367018D01*
X1074687Y367134D01*
G03X1073366Y367922I-1365J-787D01*
G01X1073322D01*
G02X1071190Y369314I-4J2322D01*
G02X1071307Y371410I2132J932D01*
G03Y372984I-1365J787D01*
G01X1071282Y373026D01*
G02X1071307Y375309I2040J1119D01*
G01X1071326Y375343D01*
G03X1071307Y376884I-1384J754D01*
G02X1071282Y379167I2015J1164D01*
G01X1071307Y379209D01*
X1071326Y379243D01*
G03X1071307Y380784I-1384J754D01*
G02X1071282Y383067I2015J1164D01*
G01X1071307Y383109D01*
X1071326Y383143D01*
G03X1071307Y384684I-1384J754D01*
G02X1071282Y386967I2015J1164D01*
G01X1071307Y387009D01*
X1071326Y387043D01*
G03X1071307Y388584I-1384J754D01*
G02X1071282Y390867I2015J1164D01*
G01X1071307Y390909D01*
X1071326Y390943D01*
G03X1071307Y392484I-1384J754D01*
G02X1073309Y395974I2015J1163D01*
G01X1073323Y395973D01*
X1073351D01*
G03X1074898Y397548I-28J1575D01*
G01Y408883D01*
X1076856Y410841D01*
Y412357D01*
X1075980Y413233D01*
G01X1073322Y370247D02*
X1072168Y369582D01*
X1071858Y369666D01*
G02X1071957Y371034I1464J582D01*
G03X1071982Y373317I-2015J1164D01*
G01X1071957Y373359D01*
G02Y374933I1365J787D01*
G03Y377259I-2015J1163D01*
G02X1071938Y378800I1365J787D01*
G01X1071957Y378834D01*
X1071982Y378876D01*
G03X1071957Y381159I-2040J1119D01*
G02X1071938Y382700I1365J787D01*
G01X1071957Y382734D01*
X1071982Y382776D01*
G03X1071957Y385059I-2040J1119D01*
G02X1071938Y386600I1365J787D01*
G01X1071957Y386634D01*
X1071982Y386676D01*
G03X1071957Y388959I-2040J1119D01*
G02X1071938Y390500I1365J787D01*
G01X1071957Y390534D01*
X1071982Y390576D01*
G03X1071957Y392859I-2040J1119D01*
G02X1073278Y395222I1365J788D01*
G01X1073322D01*
X1073392Y395221D01*
G03X1075651Y397548I-69J2327D01*
G01Y408572D01*
X1077604Y410525D01*
Y412357D01*
X1078480Y413233D01*
G01X1086841Y366347D02*
Y367678D01*
X1086585Y367934D01*
G02X1084801Y371368I256J2313D01*
G01X1084826Y371410D01*
G03Y372984I-1364J787D01*
G01X1084801Y373026D01*
G02X1084826Y375309I2040J1119D01*
G03Y376883I-1364J787D01*
G02X1084791Y379149I2015J1164D01*
G01X1084826Y379209D01*
G03Y380783I-1364J787D01*
G02X1084791Y383049I2015J1164D01*
G01X1084826Y383109D01*
G03Y384683I-1364J787D01*
G02X1086771Y388172I2015J1163D01*
G01X1086900D01*
G03X1088206Y388959I-59J1575D01*
G02X1090136Y390121I2015J-1163D01*
G01X1090265D01*
G03X1091586Y390909I-44J1575D01*
G02X1093503Y392071I2015J-1162D01*
G01X1093672D01*
G03X1094966Y394432I-71J1574D01*
G02X1094941Y396715I2015J1164D01*
G01X1094966Y396757D01*
G03Y398331I-1365J787D01*
G02Y400657I2015J1163D01*
G03X1094993Y402183I-1365J787D01*
G01X1094924Y402304D01*
G02X1094966Y404558I2057J1089D01*
G01X1095281Y405102D01*
Y406200D01*
X1094489Y406992D01*
G01X1086841Y370247D02*
Y368916D01*
X1086614Y368689D01*
G02X1085477Y371034I227J1558D01*
G03X1085502Y373317I-2017J1164D01*
G01X1085477Y373359D01*
G02Y374933I1364J787D01*
G01X1085502Y374975D01*
G03X1085477Y377260I-2040J1120D01*
G02Y378834I1364J787D01*
G01X1085512Y378894D01*
G03X1085477Y381160I-2050J1102D01*
G02Y382734I1364J787D01*
G01X1085512Y382794D01*
G03X1085477Y385060I-2050J1102D01*
G02X1086841Y387422I1364J787D01*
G01X1086926D01*
G03X1088856Y388584I-85J2325D01*
G02X1090162Y389371I1365J-788D01*
G01X1090291D01*
G03X1092236Y390534I-70J2325D01*
G02X1093530Y391321I1365J-787D01*
G01X1093699D01*
G03X1095616Y394808I-98J2324D01*
G02Y396382I1365J787D01*
G01X1095641Y396424D01*
G03X1095616Y398707I-2040J1119D01*
G01X1095597Y398741D01*
G02X1095616Y400282I1384J754D01*
G03X1095641Y402565I-2015J1164D01*
G01X1095582Y402666D01*
G02X1095616Y404182I1399J727D01*
G01X1096338Y405431D01*
X1096623Y405716D01*
X1097856D01*
X1098631Y406491D01*
G01X1073322Y358547D02*
Y359878D01*
X1073066Y360134D01*
G02X1071307Y363610I256J2313D01*
G03X1069986Y365972I-1365J787D01*
G01X1069857D01*
G02X1067927Y369460I85J2325D01*
G03Y371034I-1365J787D01*
G02X1067902Y373317I2015J1164D01*
G01X1067927Y373359D01*
G03Y374933I-1365J787D01*
G02Y377259I2015J1163D01*
G03X1067946Y378800I-1365J787D01*
G01X1067927Y378834D01*
X1067902Y378876D01*
G02X1067927Y381159I2040J1119D01*
G03X1067946Y382700I-1365J787D01*
G01X1067927Y382734D01*
X1067902Y382776D01*
G02X1067927Y385059I2040J1119D01*
G03X1067946Y386600I-1365J787D01*
G01X1067927Y386634D01*
X1067902Y386676D01*
G02X1067927Y388959I2040J1119D01*
G03X1067946Y390500I-1365J787D01*
G01X1067927Y390534D01*
X1067902Y390576D01*
G02X1067927Y392859I2040J1119D01*
G03X1068138Y393647I-1363J787D01*
G01Y395657D01*
X1070980Y398499D01*
Y411038D01*
G01X1073322Y366347D02*
G03X1070027Y366722I-3295J-14289D01*
G01X1069898D01*
G02X1068577Y369084I44J1575D01*
G03Y371410I-2015J1163D01*
G02Y372984I1365J787D01*
G01X1068602Y373026D01*
G03X1068577Y375309I-2040J1119D01*
G01X1068558Y375343D01*
G02X1068577Y376884I1384J754D01*
G03X1068602Y379167I-2015J1164D01*
G01X1068577Y379209D01*
X1068558Y379243D01*
G02X1068577Y380784I1384J754D01*
G03X1068602Y383067I-2015J1164D01*
G01X1068577Y383109D01*
X1068558Y383143D01*
G02X1068577Y384684I1384J754D01*
G03X1068602Y386967I-2015J1164D01*
G01X1068577Y387009D01*
X1068558Y387043D01*
G02X1068577Y388584I1384J754D01*
G03X1068602Y390867I-2015J1164D01*
G01X1068577Y390909D01*
X1068558Y390943D01*
G02X1068577Y392484I1384J754D01*
G03X1068889Y393647I-2015J1164D01*
G01Y395347D01*
X1071747Y398205D01*
Y408914D01*
X1073480Y410647D01*
G01X1083462Y364396D02*
X1081513Y367018D01*
X1081447Y367134D01*
X1081422Y367176D01*
G02X1081447Y369459I2040J1119D01*
G03X1081466Y371000I-1365J787D01*
G01X1081447Y371034D01*
G02X1081422Y373317I2015J1164D01*
G01X1081447Y373359D01*
G03Y374933I-1365J787D01*
G02Y377259I2015J1163D01*
G03X1081466Y378800I-1365J787D01*
G01X1081447Y378834D01*
X1081422Y378876D01*
G02X1081447Y381159I2040J1119D01*
G03X1081466Y382700I-1365J787D01*
G01X1081447Y382734D01*
X1081422Y382776D01*
G02X1081447Y385059I2040J1119D01*
G03X1081466Y386600I-1365J787D01*
G01X1081447Y386634D01*
X1081422Y386676D01*
G02X1083377Y390121I2040J1120D01*
G01X1083462D01*
G03X1084813Y390886I0J1575D01*
G01X1084826Y390909D01*
G02X1086771Y392072I2015J-1162D01*
G01X1086900D01*
G03X1088206Y392859I-59J1575D01*
G02X1090136Y394021I2015J-1163D01*
G01X1090292D01*
G03X1091586Y396382I-71J1574D01*
G01X1091561Y396424D01*
G02X1091586Y398707I2040J1119D01*
G03X1091605Y400248I-1365J787D01*
G01X1091586Y400282D01*
G02Y402608I2015J1163D01*
G01X1091605Y402642D01*
G03X1091586Y404108I-1314J716D01*
G01X1090929Y405241D01*
X1089529Y406641D01*
G01X1083462Y372197D02*
X1082131D01*
X1081904Y372424D01*
G02X1082009Y372802I1558J-229D01*
G02X1082097Y372984I1093J-416D01*
G01X1082122Y373026D01*
G03X1082097Y375309I-2040J1119D01*
G02X1082078Y375343I1184J684D01*
G02X1082097Y376884I1384J754D01*
G03X1082122Y379167I-2015J1164D01*
G01X1082097Y379209D01*
X1082078Y379243D01*
G02X1082097Y380784I1384J754D01*
G03X1082122Y383067I-2015J1164D01*
G01X1082097Y383109D01*
X1082078Y383143D01*
G02X1082097Y384684I1384J754D01*
G03X1082122Y386967I-2015J1164D01*
G01X1082097Y387009D01*
X1082078Y387043D01*
G02X1083403Y389371I1384J753D01*
G01X1083532D01*
G03X1085477Y390534I-70J2325D01*
G01X1085490Y390557D01*
G02X1086841Y391322I1351J-810D01*
G01X1086926D01*
G03X1088856Y392484I-85J2325D01*
G02X1090140Y393270I1365J-788D01*
G01X1090306D01*
G03X1092261Y396715I-85J2325D01*
G01X1092236Y396757D01*
X1092217Y396791D01*
G02X1092236Y398332I1384J754D01*
G03Y400658I-2015J1163D01*
G02Y402232I1365J787D01*
G01X1092261Y402274D01*
G03X1092236Y404559I-2040J1120D01*
G01X1092000Y404966D01*
X1091989Y404977D01*
Y406641D01*
G01X1093601Y354647D02*
X1091652Y357268D01*
X1091586Y357384D01*
G02X1091561Y359667I2015J1164D01*
G01X1091586Y359709D01*
X1091605Y359743D01*
G03X1091586Y361284I-1384J754D01*
G02X1091561Y363567I2015J1164D01*
G01X1091586Y363609D01*
X1091605Y363643D01*
G03X1091586Y365184I-1384J754D01*
G02X1091561Y367467I2015J1164D01*
G01X1091586Y367509D01*
X1091605Y367543D01*
G03X1091586Y369084I-1384J754D01*
G02Y371410I2015J1163D01*
G03Y372984I-1365J787D01*
G01X1091561Y373026D01*
G02X1091586Y375309I2040J1119D01*
G01X1091605Y375343D01*
G03X1091586Y376884I-1384J754D01*
G02X1091561Y379167I2015J1164D01*
G01X1091586Y379209D01*
X1091605Y379243D01*
G03X1091586Y380784I-1384J754D01*
G02X1093531Y384272I2015J1163D01*
G01X1093660D01*
G03X1094966Y385059I-59J1575D01*
G02X1096896Y386221I2015J-1163D01*
G01X1097025D01*
G03X1098346Y387009I-44J1575D01*
G02X1100291Y388172I2015J-1162D01*
G01X1100420D01*
G03X1101726Y388959I-59J1575D01*
G02X1103656Y390121I2015J-1163D01*
G01X1103785D01*
G03X1105106Y390909I-44J1575D01*
G02X1107051Y392072I2015J-1162D01*
G01X1107180D01*
G03X1108513Y394385I-59J1575D01*
G01X1108451Y394493D01*
G02X1108486Y396759I2050J1102D01*
G03X1108513Y398285I-1365J787D01*
G01X1108451Y398393D01*
G02X1108486Y400659I2050J1102D01*
G03X1108513Y402185I-1365J787D01*
G01X1108451Y402293D01*
G02X1108486Y404559I2050J1102D01*
G03X1108513Y406085I-1365J787D01*
G01X1108451Y406193D01*
G02X1108486Y408459I2050J1102D01*
G03X1108513Y409985I-1365J787D01*
G01X1108451Y410093D01*
G02X1108486Y412359I2050J1102D01*
G03X1108513Y413885I-1365J787D01*
G01X1108451Y413993D01*
G02X1108486Y416259I2050J1102D01*
G03X1107992Y418360I-1365J788D01*
G01X1107006Y419480D01*
X1106081Y420405D01*
G01X1093601Y362447D02*
X1092302Y365446D01*
X1092236Y365559D01*
G02X1092217Y367100I1365J787D01*
G01X1092236Y367134D01*
X1092261Y367176D01*
G03X1092236Y369459I-2040J1119D01*
G02X1092217Y371000I1365J787D01*
G01X1092236Y371034D01*
G03X1092261Y373317I-2015J1164D01*
G01X1092236Y373359D01*
G02Y374933I1365J787D01*
G03Y377259I-2015J1163D01*
G02X1092217Y378800I1365J787D01*
G01X1092236Y378834D01*
X1092261Y378876D01*
G03X1092236Y381159I-2040J1119D01*
G02X1093557Y383522I1365J788D01*
G01X1093686D01*
G03X1095616Y384684I-85J2325D01*
G02X1096922Y385471I1365J-788D01*
G01X1097051D01*
G03X1098996Y386634I-70J2325D01*
G02X1100317Y387422I1365J-787D01*
G01X1100446D01*
G03X1102376Y388584I-85J2325D01*
G02X1103682Y389371I1365J-788D01*
G01X1103811D01*
G03X1105756Y390534I-70J2325D01*
G02X1107077Y391322I1365J-787D01*
G01X1107206D01*
G03X1109161Y394767I-85J2325D01*
G01X1109136Y394809D01*
X1109109Y394857D01*
G02X1109136Y396383I1392J739D01*
G03X1109171Y398649I-2015J1164D01*
G01X1109161Y398666D01*
X1109109Y398757D01*
G02X1109136Y400283I1392J739D01*
G03X1109171Y402549I-2015J1164D01*
G01X1109109Y402657D01*
G02X1109136Y404183I1392J739D01*
G03X1109171Y406449I-2015J1164D01*
G01X1109109Y406557D01*
G02X1109136Y408083I1392J739D01*
G03X1109171Y410349I-2015J1164D01*
G01X1109109Y410457D01*
G02X1109136Y411983I1392J739D01*
G03X1109171Y414249I-2015J1164D01*
G01X1109136Y414309D01*
X1109109Y414357D01*
G02X1109136Y415883I1392J739D01*
G03X1109171Y418149I-2015J1164D01*
G01X1109136Y418209D01*
G03X1108869Y418582I-2015J-1160D01*
G01X1108581Y419509D01*
Y420405D01*
G01X1090221Y356596D02*
X1088272Y359218D01*
X1088206Y359334D01*
X1088181Y359376D01*
G02X1088206Y361659I2040J1119D01*
G03X1088225Y363200I-1365J787D01*
G01X1088206Y363234D01*
X1088181Y363276D01*
G02X1088206Y365559I2040J1119D01*
G03X1088225Y367100I-1365J787D01*
G01X1088206Y367134D01*
X1088181Y367176D01*
G02X1088206Y369459I2040J1119D01*
G03X1088225Y371000I-1365J787D01*
G01X1088206Y371034D01*
G02X1088181Y373317I2015J1164D01*
G01X1088206Y373359D01*
G03Y374933I-1365J787D01*
G02Y377259I2015J1163D01*
G03X1088225Y378800I-1365J787D01*
G01X1088206Y378834D01*
X1088181Y378876D01*
G02X1088206Y381159I2040J1119D01*
G03X1088225Y382700I-1365J787D01*
G01X1088206Y382734D01*
X1088181Y382776D01*
G02X1090136Y386221I2040J1120D01*
G01X1090265D01*
G03X1091586Y387009I-44J1575D01*
G02X1093531Y388172I2015J-1162D01*
G01X1093660D01*
G03X1094966Y388959I-59J1575D01*
G02X1096896Y390121I2015J-1163D01*
G01X1097025D01*
G03X1098346Y390909I-44J1575D01*
G02X1100291Y392072I2015J-1162D01*
G01X1100420D01*
G03X1101726Y392859I-59J1575D01*
G02X1103656Y394021I2015J-1163D01*
G01X1103785D01*
G03X1105106Y396384I-44J1575D01*
G02X1105081Y398667I2015J1164D01*
G01X1105106Y398709D01*
X1105125Y398743D01*
G03X1105106Y400284I-1384J754D01*
G02X1105081Y402567I2015J1164D01*
G01X1105106Y402609D01*
X1105125Y402643D01*
G03X1105106Y404184I-1384J754D01*
G02X1105081Y406467I2015J1164D01*
G01X1105106Y406509D01*
X1105125Y406543D01*
G03X1105106Y408084I-1384J754D01*
G02X1105081Y410367I2015J1164D01*
G01X1105106Y410409D01*
X1105125Y410443D01*
G03X1105106Y411984I-1384J754D01*
G02X1104794Y413147I2015J1164D01*
G01Y414103D01*
X1102137Y416760D01*
Y418885D01*
X1101081Y419941D01*
G01X1090221Y360496D02*
X1088924Y363492D01*
X1088837Y363643D01*
G02X1088856Y365184I1384J754D01*
G03X1088881Y367467I-2015J1164D01*
G01X1088856Y367509D01*
X1088837Y367543D01*
G02X1088856Y369084I1384J754D01*
G03Y371410I-2015J1163D01*
G02Y372984I1365J787D01*
G01X1088881Y373026D01*
G03X1088856Y375309I-2040J1119D01*
G01X1088837Y375343D01*
G02X1088856Y376884I1384J754D01*
G03X1088881Y379167I-2015J1164D01*
G01X1088856Y379209D01*
X1088837Y379243D01*
G02X1088856Y380784I1384J754D01*
G03X1088881Y383067I-2015J1164D01*
G01X1088856Y383109D01*
X1088837Y383143D01*
G02X1090162Y385471I1384J753D01*
G01X1090291D01*
G03X1092236Y386634I-70J2325D01*
G02X1093557Y387422I1365J-787D01*
G01X1093686D01*
G03X1095616Y388584I-85J2325D01*
G02X1096922Y389371I1365J-788D01*
G01X1097051D01*
G03X1098996Y390534I-70J2325D01*
G02X1100317Y391322I1365J-787D01*
G01X1100446D01*
G03X1102376Y392484I-85J2325D01*
G02X1103682Y393271I1365J-788D01*
G01X1103811D01*
G03X1105756Y396759I-70J2325D01*
G02X1105737Y398300I1365J787D01*
G01X1105756Y398334D01*
X1105781Y398376D01*
G03X1105756Y400659I-2040J1119D01*
G02X1105737Y402200I1365J787D01*
G01X1105756Y402234D01*
X1105781Y402276D01*
G03X1105756Y404559I-2040J1119D01*
G02X1105737Y406100I1365J787D01*
G01X1105756Y406134D01*
X1105781Y406176D01*
G03X1105756Y408459I-2040J1119D01*
G02X1105737Y410000I1365J787D01*
G01X1105756Y410034D01*
X1105781Y410076D01*
G03X1105756Y412359I-2040J1119D01*
G02X1105545Y413147I1365J788D01*
G01Y414415D01*
X1102887Y417073D01*
Y419247D01*
X1103800Y420160D01*
G01X1080082Y366347D02*
Y365016D01*
X1079854Y364788D01*
G02X1078698Y367100I228J1559D01*
G01X1078717Y367134D01*
X1078742Y367176D01*
G03X1076753Y370622I-2040J1120D01*
G01X1076658D01*
G02X1075337Y372984I44J1575D01*
G01X1075362Y373026D01*
G03X1075337Y375309I-2040J1119D01*
G01X1075318Y375343D01*
G02X1075337Y376884I1384J754D01*
G03X1075362Y379167I-2015J1164D01*
G01X1075337Y379209D01*
X1075318Y379243D01*
G02X1075337Y380784I1384J754D01*
G03X1075362Y383067I-2015J1164D01*
G01X1075337Y383109D01*
X1075318Y383143D01*
G02X1075337Y384684I1384J754D01*
G03X1075362Y386967I-2015J1164D01*
G01X1075337Y387009D01*
X1075318Y387043D01*
G02X1075337Y388584I1384J754D01*
G03X1075362Y390867I-2015J1164D01*
G01X1075337Y390909D01*
X1075318Y390943D01*
G02X1076683Y393272I1384J753D01*
G01X1076753D01*
G03X1078717Y394435I-51J2326D01*
G01X1079361Y395549D01*
X1082030Y398219D01*
Y412332D01*
X1082185Y412487D01*
Y412574D01*
G01X1080082Y370247D02*
G03X1079355Y371772I-1963J0D01*
G01X1078666Y372300D01*
G02X1078067Y375309I1416J1846D01*
G01X1078086Y375343D01*
G03X1078067Y376884I-1384J754D01*
G02X1078042Y379167I2015J1164D01*
G01X1078067Y379209D01*
X1078086Y379243D01*
G03X1078067Y380784I-1384J754D01*
G02X1078042Y383067I2015J1164D01*
G01X1078067Y383109D01*
X1078086Y383143D01*
G03X1078067Y384684I-1384J754D01*
G02X1078042Y386967I2015J1164D01*
G01X1078067Y387009D01*
X1078086Y387043D01*
G03X1078067Y388584I-1384J754D01*
G02X1080012Y392072I2015J1163D01*
G01X1080141D01*
G03X1081447Y392859I-59J1575D01*
G01X1082139Y394058D01*
X1085030Y396949D01*
Y412332D01*
X1084875Y412487D01*
Y412574D01*
G01X1080082Y362447D02*
Y363778D01*
X1079826Y364034D01*
G02X1078042Y367467I256J2313D01*
G01X1078067Y367509D01*
X1078086Y367543D01*
G03X1076761Y369871I-1384J753D01*
G01X1076651D01*
G02X1074662Y373317I51J2326D01*
G01X1074687Y373359D01*
G03Y374933I-1365J787D01*
G02Y377259I2015J1163D01*
G03X1074706Y378800I-1365J787D01*
G01X1074687Y378834D01*
X1074662Y378876D01*
G02X1074687Y381159I2040J1119D01*
G03X1074706Y382700I-1365J787D01*
G01X1074687Y382734D01*
X1074662Y382776D01*
G02X1074687Y385059I2040J1119D01*
G03X1074706Y386600I-1365J787D01*
G01X1074687Y386634D01*
X1074662Y386676D01*
G02X1074687Y388959I2040J1119D01*
G03X1074706Y390500I-1365J787D01*
G01X1074687Y390534D01*
X1074662Y390576D01*
G02X1076651Y394022I2040J1120D01*
G01X1076721D01*
G03X1078067Y394810I-19J1576D01*
G01X1078759Y396009D01*
X1081280Y398530D01*
Y412332D01*
X1081125Y412487D01*
Y412574D01*
G01X1096981Y352696D02*
Y354027D01*
X1096724Y354284D01*
G02X1094966Y357759I257J2312D01*
G03X1094985Y359300I-1365J787D01*
G01X1094966Y359334D01*
X1094941Y359376D01*
G02X1094966Y361659I2040J1119D01*
G03X1094985Y363200I-1365J787D01*
G01X1094966Y363234D01*
X1094941Y363276D01*
G02X1094966Y365559I2040J1119D01*
G03X1094985Y367100I-1365J787D01*
G01X1094966Y367134D01*
X1094941Y367176D01*
G02X1094966Y369459I2040J1119D01*
G03X1094985Y371000I-1365J787D01*
G01X1094966Y371034D01*
G02X1094941Y373317I2015J1164D01*
G01X1094966Y373359D01*
G03Y374933I-1365J787D01*
G02Y377259I2015J1163D01*
G03X1094985Y378800I-1365J787D01*
G01X1094966Y378834D01*
X1094941Y378876D01*
G02X1096896Y382321I2040J1120D01*
G01X1097025D01*
G03X1098346Y383109I-44J1575D01*
G02X1100291Y384272I2015J-1162D01*
G01X1100420D01*
G03X1101726Y385059I-59J1575D01*
G02X1103656Y386221I2015J-1163D01*
G01X1103785D01*
G03X1105106Y387009I-44J1575D01*
G02X1107051Y388172I2015J-1162D01*
G01X1107180D01*
G03X1108486Y388959I-59J1575D01*
G02X1110416Y390121I2015J-1163D01*
G01X1110545D01*
G03X1111866Y392483I-44J1575D01*
G01X1111841Y392525D01*
G02X1111866Y394808I2040J1119D01*
G03Y396382I-1365J787D01*
G01X1111841Y396424D01*
G02X1111866Y398707I2040J1119D01*
G03X1111885Y400248I-1365J787D01*
G01X1111866Y400282D01*
G02Y402608I2015J1163D01*
G01X1111885Y402642D01*
G03X1111866Y404183I-1384J754D01*
G02X1111831Y406449I2015J1164D01*
G01X1111893Y406557D01*
G03X1111866Y408083I-1392J739D01*
G02X1111831Y410349I2015J1164D01*
G01X1111893Y410457D01*
G03X1111866Y411983I-1392J739D01*
G02X1111831Y414249I2015J1164D01*
G01X1111838Y414258D01*
X1111894Y414357D01*
G03X1111889Y415843I-1393J738D01*
G01X1111393Y416702D01*
Y421758D01*
X1111238Y421913D01*
Y422000D01*
G01X1080082Y374146D02*
Y372815D01*
X1079854Y372587D01*
G02X1079123Y372896I228J1559D01*
G02X1078717Y374933I959J1250D01*
G03Y377259I-2015J1163D01*
G02X1078698Y378800I1365J787D01*
G01X1078717Y378834D01*
X1078742Y378876D01*
G03X1078717Y381159I-2040J1119D01*
G02X1078698Y382700I1365J787D01*
G01X1078717Y382734D01*
X1078742Y382776D01*
G03X1078717Y385059I-2040J1119D01*
G02X1078698Y386600I1365J787D01*
G01X1078717Y386634D01*
X1078742Y386676D01*
G03X1078717Y388959I-2040J1119D01*
G02X1080038Y391322I1365J788D01*
G01X1080167D01*
G03X1082097Y392484I-85J2325D01*
G01X1082739Y393596D01*
X1085780Y396637D01*
Y412332D01*
X1085935Y412487D01*
Y412574D01*
G01X1049284Y359260D02*
X1050100Y360076D01*
Y361300D01*
X1051968Y363168D01*
X1053900D01*
X1056100Y365368D01*
Y393400D01*
X1064201Y401501D01*
Y402640D01*
G01X1103892Y185697D02*
X1103332Y186257D01*
Y187037D01*
X1102546Y187823D01*
Y209589D01*
X1103676Y210719D01*
Y213026D01*
X1103818Y213168D01*
X1103986Y213459D01*
G03X1104005Y215000I-1365J787D01*
G01X1103986Y215034D01*
X1103961Y215076D01*
G02X1103986Y217359I2040J1119D01*
G03X1104005Y218900I-1365J787D01*
G01X1103986Y218934D01*
X1103961Y218976D01*
G02X1103986Y221259I2040J1119D01*
G03X1104005Y222800I-1365J787D01*
G01X1103986Y222834D01*
X1103961Y222876D01*
G02X1103986Y225159I2040J1119D01*
G03X1104005Y226700I-1365J787D01*
G01X1103986Y226734D01*
X1103961Y226776D01*
G02X1103986Y229059I2040J1119D01*
G03X1104005Y230600I-1365J787D01*
G01X1103986Y230634D01*
G02X1103961Y232917I2015J1164D01*
G01X1103986Y232959D01*
G03Y234533I-1365J787D01*
G02Y236859I2015J1163D01*
G03X1104005Y238400I-1365J787D01*
G01X1103986Y238434D01*
X1103961Y238476D01*
G02X1103986Y240759I2040J1119D01*
G03X1104005Y242300I-1365J787D01*
G01X1103986Y242334D01*
X1103961Y242376D01*
G02X1103986Y244659I2040J1119D01*
G01X1104052Y244775D01*
X1106001Y247396D01*
G01X1106100Y185400D02*
X1103296Y188204D01*
Y209273D01*
X1104426Y210403D01*
Y212725D01*
X1104634Y213085D01*
X1104636Y213084D01*
G03X1104661Y215367I-2015J1164D01*
G01X1104636Y215409D01*
X1104617Y215443D01*
G02X1104636Y216984I1384J754D01*
G03X1104661Y219267I-2015J1164D01*
G01X1104636Y219309D01*
X1104617Y219343D01*
G02X1104636Y220884I1384J754D01*
G03X1104661Y223167I-2015J1164D01*
G01X1104636Y223209D01*
X1104617Y223243D01*
G02X1104636Y224784I1384J754D01*
G03X1104661Y227067I-2015J1164D01*
G01X1104636Y227109D01*
X1104617Y227143D01*
G02X1104636Y228684I1384J754D01*
G03Y231010I-2015J1163D01*
G02Y232584I1365J787D01*
G01X1104661Y232626D01*
G03X1104636Y234909I-2040J1119D01*
G01X1104617Y234943D01*
G02X1104636Y236484I1384J754D01*
G03X1104661Y238767I-2015J1164D01*
G01X1104636Y238809D01*
X1104617Y238843D01*
G02X1104636Y240384I1384J754D01*
G03X1104661Y242667I-2015J1164D01*
G01X1104636Y242709D01*
X1104617Y242743D01*
G02X1105362Y244937I1384J753D01*
G01X1106426Y245640D01*
X1107204Y246328D01*
X1107385Y246643D01*
G03X1107366Y248184I-1384J754D01*
G01X1107243Y248397D01*
X1106820Y248819D01*
X1105271Y249899D01*
G02X1104636Y250509I731J1396D01*
G01X1104617Y250543D01*
G02X1104636Y252084I1384J754D01*
G01X1104702Y252197D01*
X1106001Y255196D01*
G01X1122056Y187055D02*
X1122928Y187927D01*
Y188961D01*
X1117768Y194121D01*
Y207945D01*
X1117196Y208517D01*
Y216821D01*
X1117506Y217359D01*
G03X1117525Y218900I-1365J787D01*
G01X1117506Y218934D01*
X1117481Y218976D01*
G02X1117506Y221259I2040J1119D01*
G03X1117525Y222800I-1365J787D01*
G01X1117506Y222834D01*
X1117481Y222876D01*
G02X1117506Y225159I2040J1119D01*
G03X1117525Y226700I-1365J787D01*
G01X1117506Y226734D01*
X1117481Y226776D01*
G02X1117506Y229059I2040J1119D01*
G03X1117525Y230600I-1365J787D01*
G01X1117506Y230634D01*
G02X1117481Y232917I2015J1164D01*
G01X1117506Y232959D01*
G03Y234533I-1365J787D01*
G02Y236859I2015J1163D01*
G03X1117525Y238400I-1365J787D01*
G01X1117506Y238434D01*
X1117481Y238476D01*
G02X1117506Y240759I2040J1119D01*
G03X1117525Y242300I-1365J787D01*
G01X1117506Y242334D01*
X1117481Y242376D01*
G02X1117506Y244659I2040J1119D01*
G03X1117525Y246200I-1365J787D01*
G03X1117506Y246234I-632J-331D01*
G01X1117481Y246276D01*
G02X1117389Y248329I2039J1120D01*
G01X1117295Y248681D01*
X1116141Y249347D01*
G01X1124556Y187055D02*
X1123678Y187933D01*
Y189272D01*
X1118518Y194432D01*
Y208256D01*
X1117946Y208828D01*
Y216620D01*
X1118156Y216984D01*
G03X1118181Y219267I-2015J1164D01*
G01X1118156Y219309D01*
X1118137Y219343D01*
G02X1118156Y220884I1384J754D01*
G03X1118181Y223167I-2015J1164D01*
G01X1118156Y223209D01*
X1118137Y223243D01*
G02X1118156Y224784I1384J754D01*
G03X1118181Y227067I-2015J1164D01*
G01X1118156Y227109D01*
X1118137Y227143D01*
G02X1118156Y228684I1384J754D01*
G03Y231010I-2015J1163D01*
G02Y232584I1365J787D01*
G01X1118181Y232626D01*
G03X1118156Y234909I-2040J1119D01*
G01X1118137Y234943D01*
G02X1118156Y236484I1384J754D01*
G03X1118181Y238767I-2015J1164D01*
G01X1118156Y238809D01*
X1118137Y238843D01*
G02X1118156Y240384I1384J754D01*
G03X1118181Y242667I-2015J1164D01*
G01X1118156Y242709D01*
X1118137Y242743D01*
G02X1118156Y244284I1384J754D01*
G03X1118181Y246567I-2015J1164D01*
G01X1118156Y246609D01*
X1118137Y246643D01*
G02X1118156Y248184I1384J754D01*
G03X1118034Y250700I-2015J1163D01*
G01X1117039Y252039D01*
X1116141Y253247D01*
G01X1099000Y185848D02*
X1099526Y186374D01*
Y209677D01*
X1100817Y210968D01*
Y212294D01*
G03X1100606Y213084I-1576J2D01*
G02X1100581Y215367I2015J1164D01*
G01X1100606Y215409D01*
X1100625Y215443D01*
G03X1100606Y216984I-1384J754D01*
G02X1100581Y219267I2015J1164D01*
G01X1100606Y219309D01*
X1100625Y219343D01*
G03X1100606Y220884I-1384J754D01*
G02X1100581Y223167I2015J1164D01*
G01X1100606Y223209D01*
X1100625Y223243D01*
G03X1100606Y224784I-1384J754D01*
G02X1100581Y227067I2015J1164D01*
G01X1100606Y227109D01*
X1100625Y227143D01*
G03X1100606Y228684I-1384J754D01*
G02Y231010I2015J1163D01*
G03Y232584I-1365J787D01*
G01X1100581Y232626D01*
G02X1100606Y234909I2040J1119D01*
G01X1100625Y234943D01*
G03X1100606Y236484I-1384J754D01*
G02X1100581Y238767I2015J1164D01*
G01X1100606Y238809D01*
X1100625Y238843D01*
G03X1100606Y240384I-1384J754D01*
G02X1100581Y242667I2015J1164D01*
G01X1100606Y242709D01*
X1100625Y242743D01*
G03X1100606Y244284I-1384J754D01*
G02X1100581Y246567I2015J1164D01*
G01X1100606Y246609D01*
G02X1101014Y247128I2014J-1163D01*
G01X1102621Y249347D01*
G01X1101200Y185669D02*
X1100276Y186593D01*
Y209366D01*
X1101568Y210658D01*
Y212294D01*
G03X1101256Y213459I-2327J1D01*
G02X1101237Y215000I1365J787D01*
G01X1101256Y215034D01*
X1101281Y215076D01*
G03X1101256Y217359I-2040J1119D01*
G02X1101237Y218900I1365J787D01*
G01X1101256Y218934D01*
X1101281Y218976D01*
G03X1101256Y221259I-2040J1119D01*
G02X1101237Y222800I1365J787D01*
G01X1101256Y222834D01*
X1101281Y222876D01*
G03X1101256Y225159I-2040J1119D01*
G02X1101237Y226700I1365J787D01*
G01X1101256Y226734D01*
X1101281Y226776D01*
G03X1101256Y229059I-2040J1119D01*
G02X1101237Y230600I1365J787D01*
G01X1101256Y230634D01*
G03X1101281Y232917I-2015J1164D01*
G01X1101256Y232959D01*
G02Y234533I1365J787D01*
G03Y236859I-2015J1163D01*
G02X1101237Y238400I1365J787D01*
G01X1101256Y238434D01*
X1101281Y238476D01*
G03X1101256Y240759I-2040J1119D01*
G02X1101237Y242300I1365J787D01*
G01X1101256Y242334D01*
X1101281Y242376D01*
G03X1101256Y244659I-2040J1119D01*
G02X1102023Y246905I1365J788D01*
G01X1103774Y248192D01*
G01X1117056Y187055D02*
X1117930Y187929D01*
Y189685D01*
X1114742Y192873D01*
Y201299D01*
X1113617Y202424D01*
Y214192D01*
X1114337Y214912D01*
Y216196D01*
G03X1114126Y216984I-1577J0D01*
G02X1114101Y219267I2015J1164D01*
G02X1114126Y219306I297J-163D01*
G03Y220882I-1365J788D01*
G02Y223208I2015J1163D01*
G03Y224784I-1365J788D01*
G02Y227110I2015J1163D01*
G03X1114145Y228651I-1365J787D01*
G01X1114126Y228685D01*
X1114101Y228727D01*
G02X1114126Y231010I2040J1119D01*
G03X1114145Y232551I-1365J787D01*
G01X1114126Y232585D01*
X1114101Y232627D01*
G02X1114126Y234910I2040J1119D01*
G03X1114145Y236451I-1365J787D01*
G01X1114126Y236485D01*
X1114101Y236527D01*
G02X1114126Y238810I2040J1119D01*
G03X1114145Y240351I-1365J787D01*
G01X1114126Y240385D01*
X1114101Y240427D01*
G02X1114126Y242710I2043J1119D01*
G03Y244284I-1365J787D01*
G02X1114009Y246380I2015J1164D01*
G01X1113915Y246731D01*
X1112761Y247396D01*
G01X1119556Y187055D02*
X1118680Y187931D01*
Y189996D01*
X1115492Y193184D01*
Y201619D01*
X1114367Y202744D01*
Y213879D01*
X1115088Y214600D01*
Y216196D01*
G03X1114776Y217359I-2327J-1D01*
G02X1114757Y218900I1365J787D01*
G03X1114776Y218931I-578J375D01*
G03Y221257I-2015J1163D01*
G02Y222833I1365J788D01*
G03Y225159I-2015J1163D01*
G02Y226735I1365J788D01*
G03X1114801Y229018I-2015J1164D01*
G01X1114776Y229060D01*
X1114757Y229094D01*
G02X1114776Y230635I1384J754D01*
G03X1114801Y232918I-2015J1164D01*
G01X1114776Y232960D01*
X1114757Y232994D01*
G02X1114776Y234535I1384J754D01*
G03X1114801Y236818I-2015J1164D01*
G01X1114776Y236860D01*
X1114757Y236894D01*
G02X1114776Y238435I1384J754D01*
G03X1114801Y240718I-2015J1164D01*
G01X1114776Y240760D01*
X1114757Y240794D01*
G02X1114776Y242334I1382J753D01*
G03Y244660I-2015J1163D01*
G02Y246234I1365J787D01*
G03Y248560I-2015J1163D01*
G02X1114313Y251027I3278J1892D01*
G01X1110626Y183900D02*
Y183987D01*
X1110471Y184142D01*
Y187157D01*
X1107216Y190412D01*
Y198442D01*
X1106656Y199908D01*
Y201300D01*
X1108327Y202971D01*
Y212285D01*
G01X1114427Y185913D02*
Y186000D01*
X1114272Y186155D01*
Y190124D01*
X1110056Y194340D01*
Y198734D01*
X1110812Y200246D01*
Y200954D01*
X1111347Y201489D01*
Y212621D01*
X1111834Y213108D01*
Y214650D01*
X1111376Y215444D01*
G02X1111395Y216983I1385J753D01*
G01X1111396Y216984D01*
G03X1111421Y219267I-2015J1164D01*
G01X1111396Y219309D01*
X1111377Y219343D01*
G02X1111396Y220884I1384J754D01*
G03X1111421Y223167I-2015J1164D01*
G01X1111396Y223209D01*
X1111377Y223243D01*
G02X1111396Y224784I1384J754D01*
G03X1111421Y227067I-2015J1164D01*
G01X1111396Y227109D01*
X1111377Y227143D01*
G02X1111396Y228684I1384J754D01*
G03Y231010I-2015J1163D01*
G02Y232584I1365J787D01*
G01X1111421Y232626D01*
G03X1111396Y234909I-2040J1119D01*
G01X1111377Y234943D01*
G02X1111396Y236484I1384J754D01*
G03X1111421Y238767I-2015J1164D01*
G01X1111396Y238809D01*
X1111377Y238843D01*
G02X1111396Y240384I1384J754D01*
G03X1111421Y242667I-2015J1164D01*
G01X1111396Y242709D01*
X1111377Y242743D01*
G02X1111396Y244284I1384J754D01*
G03X1111421Y246567I-2015J1164D01*
G01X1111396Y246609D01*
X1111377Y246643D01*
G02X1111396Y248184I1384J754D01*
G03X1111421Y250467I-2015J1164D01*
G01X1111396Y250509D01*
X1111377Y250543D01*
G02X1111396Y252084I1384J754D01*
G03X1109638Y255559I-2015J1163D01*
G01X1109381Y255816D01*
Y257147D01*
G01X1109566Y183900D02*
Y183987D01*
X1109721Y184142D01*
Y186846D01*
X1106466Y190101D01*
Y198303D01*
X1105906Y199769D01*
Y201611D01*
X1107577Y203282D01*
Y212288D01*
G03X1107367Y213083I-1573J10D01*
G01X1107366Y213084D01*
G02X1107341Y215367I2015J1164D01*
G01X1107366Y215409D01*
X1107385Y215443D01*
G03X1107366Y216984I-1384J754D01*
G02X1107341Y219267I2015J1164D01*
G01X1107366Y219309D01*
X1107385Y219343D01*
G03X1107366Y220884I-1384J754D01*
G02X1107341Y223167I2015J1164D01*
G01X1107366Y223209D01*
X1107385Y223243D01*
G03X1107366Y224784I-1384J754D01*
G02X1107341Y227067I2015J1164D01*
G01X1107366Y227109D01*
X1107385Y227143D01*
G03X1107366Y228684I-1384J754D01*
G02Y231010I2015J1163D01*
G03Y232584I-1365J787D01*
G01X1107341Y232626D01*
G02X1107366Y234909I2040J1119D01*
G01X1107385Y234943D01*
G03X1107366Y236484I-1384J754D01*
G02X1107341Y238767I2015J1164D01*
G01X1107366Y238809D01*
X1107385Y238843D01*
G03X1107366Y240384I-1384J754D01*
G02Y242710I2015J1163D01*
G03X1107855Y245055I-3319J1916D01*
G02X1108016Y246234I1526J392D01*
G03X1109374Y249332I-13361J7703D01*
G01X1109381Y249339D01*
Y249347D01*
G01X1113367Y185913D02*
Y186000D01*
X1113522Y186155D01*
Y189813D01*
X1109306Y194029D01*
Y198912D01*
X1110062Y200424D01*
Y201265D01*
X1110597Y201800D01*
Y212932D01*
X1111084Y213419D01*
Y214448D01*
X1110721Y215076D01*
G02X1110746Y217359I2040J1119D01*
G03X1110765Y218900I-1365J787D01*
G01X1110746Y218934D01*
X1110721Y218976D01*
G02X1110746Y221259I2040J1119D01*
G03X1110765Y222800I-1365J787D01*
G01X1110746Y222834D01*
X1110721Y222876D01*
G02X1110746Y225159I2040J1119D01*
G03X1110765Y226700I-1365J787D01*
G01X1110746Y226734D01*
X1110721Y226776D01*
G02X1110746Y229059I2040J1119D01*
G03X1110765Y230600I-1365J787D01*
G01X1110746Y230634D01*
G02X1110721Y232917I2015J1164D01*
G01X1110746Y232959D01*
G03Y234533I-1365J787D01*
G02Y236859I2015J1163D01*
G03X1110765Y238400I-1365J787D01*
G01X1110746Y238434D01*
X1110721Y238476D01*
G02X1110746Y240759I2040J1119D01*
G03X1110765Y242300I-1365J787D01*
G01X1110746Y242334D01*
X1110721Y242376D01*
G02X1110746Y244659I2040J1119D01*
G03X1110765Y246200I-1365J787D01*
G01X1110746Y246234D01*
X1110721Y246276D01*
G02X1110746Y248559I2040J1119D01*
G03X1110765Y250100I-1365J787D01*
G01X1110746Y250134D01*
X1110721Y250176D01*
G02X1110746Y252459I2040J1119D01*
G03X1109609Y254806I-1365J788D01*
G01X1109381Y254578D01*
Y253247D01*
G01X1126280Y247396D02*
X1126114Y247220D01*
G03X1124281Y244688I11333J-10134D01*
G01X1124265Y244660D01*
G03Y242334I2015J-1163D01*
G02Y240759I-1364J-787D01*
G03X1124240Y238476I2015J-1164D01*
G01X1124265Y238434D01*
X1124284Y238400D01*
G02X1124265Y236859I-1384J-754D01*
G03Y234533I2015J-1163D01*
G02Y232959I-1365J-787D01*
G01X1124240Y232917D01*
G03X1124265Y230634I2040J-1119D01*
G01X1124284Y230600D01*
G02X1124265Y229059I-1384J-754D01*
G03X1124240Y226776I2015J-1164D01*
G01X1124265Y226734D01*
X1124284Y226700D01*
G02X1124265Y225159I-1384J-754D01*
G03X1124240Y222876I2015J-1164D01*
G01X1124265Y222834D01*
X1124284Y222800D01*
G02X1124265Y221259I-1384J-754D01*
G03X1124240Y218976I2015J-1164D01*
G01X1124265Y218934D01*
X1124284Y218900D01*
G02X1124265Y217359I-1384J-754D01*
G03X1124240Y215076I2015J-1164D01*
G01X1124265Y215034D01*
X1124284Y215000D01*
G02X1124265Y213459I-1384J-754D01*
G03X1123997Y211735I2093J-1208D01*
G01X1124317Y210266D01*
G01D02*
Y203200D01*
X1127000Y200517D01*
Y197815D01*
X1131200Y193615D01*
Y193300D01*
G01X1126280Y255196D02*
X1125206Y252749D01*
X1124915Y252084D01*
G03X1125676Y249842I1365J-787D01*
G02X1127530Y248356I-1636J-3940D01*
G02X1126854Y245930I-1250J-959D01*
G03X1124915Y244284I1328J-3530D01*
G03Y242710I1365J-787D01*
G02Y240384I-2017J-1163D01*
G03X1124896Y238843I1365J-787D01*
G01X1124915Y238809D01*
X1124940Y238767D01*
G02X1124915Y236484I-2040J-1119D01*
G03X1124896Y234943I1365J-787D01*
G01X1124915Y234909D01*
G02X1124940Y232626I-2015J-1164D01*
G01X1124915Y232584D01*
G03Y231010I1365J-787D01*
G02Y228684I-2015J-1163D01*
G03X1124896Y227143I1365J-787D01*
G01X1124915Y227109D01*
X1124940Y227067D01*
G02X1124915Y224784I-2040J-1119D01*
G03X1124896Y223243I1365J-787D01*
G01X1124915Y223209D01*
X1124940Y223167D01*
G02X1124915Y220884I-2040J-1119D01*
G03X1124896Y219343I1365J-787D01*
G01X1124915Y219309D01*
X1124940Y219267D01*
G02X1124915Y216984I-2040J-1119D01*
G03X1124896Y215443I1365J-787D01*
G01X1124915Y215409D01*
X1124940Y215367D01*
G02X1124915Y213084I-2040J-1119D01*
G03X1124821Y211632I1423J-821D01*
G01X1125066Y211043D01*
Y203512D01*
X1127800Y200778D01*
Y198696D01*
X1127750Y198646D01*
Y198130D01*
X1131680Y194200D01*
X1133100D01*
G01X1136420Y249347D02*
X1137574Y248681D01*
X1137668Y248329D01*
G03X1137760Y246276I2131J-933D01*
G01X1137785Y246234D01*
G02X1137970Y245844I-799J-618D01*
G02X1137785Y244603I-1667J-386D01*
G03Y242388I1919J-1108D01*
G01X1137876Y242230D01*
G02X1137877Y240768I-1268J-732D01*
G01X1137857Y240739D01*
G03X1137760Y238476I1818J-1211D01*
G01X1137785Y238434D01*
X1137804Y238400D01*
G02X1137785Y236859I-1384J-754D01*
G03Y234533I2015J-1163D01*
G02Y232959I-1365J-787D01*
G01X1137760Y232917D01*
G03X1137785Y230634I2040J-1119D01*
G01X1137804Y230600D01*
G02X1137785Y229059I-1384J-754D01*
G03X1137760Y226776I2015J-1164D01*
G01X1137785Y226734D01*
X1137804Y226700D01*
G02X1137785Y225159I-1384J-754D01*
G03X1137760Y222876I2015J-1164D01*
G01X1137785Y222834D01*
X1137804Y222800D01*
G02X1137785Y221259I-1384J-754D01*
G03X1137760Y218976I2015J-1164D01*
G01X1137785Y218934D01*
X1137804Y218900D01*
G02X1137785Y217359I-1384J-754D01*
G03X1137760Y215076I2015J-1164D01*
G01X1137785Y215034D01*
X1137804Y215000D01*
G02X1137785Y213459I-1384J-754D01*
G03X1137568Y211638I2015J-1164D01*
G01X1138426Y210780D01*
Y210089D01*
X1143300Y205215D01*
Y204500D01*
G01X1136420Y253247D02*
X1137565Y251600D01*
X1137995Y250981D01*
X1138253Y250723D01*
G02X1138435Y248127I-1833J-1433D01*
G03X1138448Y246665I1249J-720D01*
G01X1138476Y246618D01*
G02Y244298I-2010J-1160D01*
G01X1138435Y244227D01*
G03X1138400Y243085I1048J-604D01*
G01X1138551Y242781D01*
G02X1138478Y240233I-2423J-1206D01*
G01X1138443Y240172D01*
G03X1138435Y238809I1199J-689D01*
G01X1138460Y238767D01*
G02X1138435Y236484I-2040J-1119D01*
G03X1138416Y234943I1365J-787D01*
G01X1138435Y234909D01*
G02X1138460Y232626I-2015J-1164D01*
G01X1138435Y232584D01*
G03Y231010I1365J-787D01*
G02Y228684I-2015J-1163D01*
G03X1138416Y227143I1365J-787D01*
G01X1138435Y227109D01*
X1138460Y227067D01*
G02X1138435Y224784I-2040J-1119D01*
G03X1138416Y223243I1365J-787D01*
G01X1138435Y223209D01*
X1138460Y223167D01*
G02X1138435Y220884I-2040J-1119D01*
G03X1138416Y219343I1365J-787D01*
G01X1138435Y219309D01*
X1138460Y219267D01*
G02X1138435Y216984I-2040J-1119D01*
G03X1138416Y215443I1365J-787D01*
G01X1138435Y215409D01*
X1138460Y215367D01*
G02X1138435Y213084I-2040J-1119D01*
G03X1138237Y212094I1365J-788D01*
G01X1139176Y211155D01*
Y210400D01*
X1144076Y205500D01*
X1145000D01*
G01X1129400Y189500D02*
X1129200Y189700D01*
Y191243D01*
X1121298Y199145D01*
Y207787D01*
X1121096Y207989D01*
Y212294D01*
G03X1120885Y213082I-1575J0D01*
G02X1120843Y215336I2015J1165D01*
G01X1120885Y215409D01*
G03Y216983I-1364J787D01*
G02X1120850Y219249I2015J1164D01*
G01X1120885Y219309D01*
G03Y220883I-1364J787D01*
G02X1120850Y223149I2015J1164D01*
G01X1120885Y223209D01*
G03Y224783I-1364J787D01*
G02X1120850Y227049I2015J1164D01*
G01X1120885Y227109D01*
G03Y228683I-1364J787D01*
G02X1120860Y230968I2015J1165D01*
G01X1120885Y231010D01*
G03Y232584I-1364J787D01*
G01X1120860Y232626D01*
G02X1120885Y234909I2040J1119D01*
G03Y236483I-1364J787D01*
G02X1120850Y238749I2015J1164D01*
G01X1120885Y238809D01*
G03Y240383I-1364J787D01*
G02Y242710I2017J1164D01*
G03Y244284I-1364J787D01*
G02Y246610I2015J1163D01*
G01X1120901Y246638D01*
G02X1122669Y249098I13168J-7599D01*
G01X1122900Y249347D01*
G01X1130750Y190750D02*
X1129952Y191548D01*
Y191552D01*
X1122048Y199456D01*
Y208098D01*
X1121849Y208297D01*
Y212294D01*
G03X1121536Y213459I-2328J-1D01*
G02X1121504Y214978I1364J789D01*
G01X1121571Y215094D01*
G03X1121536Y217360I-2050J1102D01*
G02Y218934I1364J787D01*
G01X1121571Y218994D01*
G03X1121536Y221260I-2050J1102D01*
G02Y222834I1364J787D01*
G01X1121571Y222894D01*
G03X1121536Y225160I-2050J1102D01*
G02Y226734I1364J787D01*
G01X1121571Y226794D01*
G03X1121536Y229060I-2050J1102D01*
G02Y230634I1364J787D01*
G03X1121561Y232917I-2015J1164D01*
G01X1121536Y232959D01*
G02Y234533I1364J787D01*
G01X1121561Y234575D01*
G03X1121536Y236860I-2040J1120D01*
G02Y238434I1364J787D01*
G01X1121571Y238494D01*
G03X1121536Y240760I-2050J1102D01*
G02Y242334I1364J787D01*
G03Y244660I-2015J1163D01*
G02Y246234I1364J787D01*
G01X1121549Y246257D01*
G02X1122365Y247116I2122J-1199D01*
G01X1123750Y247995D01*
X1123838Y248081D01*
G03X1124011Y250465I-938J1266D01*
G01X1123558Y251600D01*
X1122900Y253247D01*
G01X1133040Y247396D02*
X1134194Y246731D01*
X1134288Y246380D01*
G03X1134405Y244284I2132J-932D01*
G02Y242710I-1365J-787D01*
G03Y240384I2017J-1163D01*
G02X1134424Y238843I-1365J-787D01*
G01X1134405Y238809D01*
X1134380Y238767D01*
G03X1134405Y236484I2040J-1119D01*
G02X1134424Y234943I-1365J-787D01*
G01X1134405Y234909D01*
G03X1134380Y232626I2015J-1164D01*
G01X1134405Y232584D01*
G02Y231010I-1365J-787D01*
G03Y228684I2015J-1163D01*
G02X1134424Y227143I-1365J-787D01*
G01X1134405Y227109D01*
X1134380Y227067D01*
G03X1134405Y224784I2040J-1119D01*
G02X1134424Y223243I-1365J-787D01*
G01X1134405Y223209D01*
X1134380Y223167D01*
G03X1134405Y220884I2040J-1119D01*
G02X1134424Y219343I-1365J-787D01*
G01X1134405Y219309D01*
X1134380Y219267D01*
G03X1134405Y216984I2040J-1119D01*
G02X1134424Y215443I-1365J-787D01*
G01X1134405Y215409D01*
X1134380Y215367D01*
G03X1134405Y213084I2040J-1119D01*
G02X1134424Y211543I-1365J-787D01*
G03X1134405Y209183I2000J-1196D01*
G03X1134985Y208516I1996J1150D01*
G02X1135572Y207311I-936J-1202D01*
G01Y206287D01*
X1141409Y200450D01*
X1141450D01*
G01X1133040Y255196D02*
X1134405Y252084D01*
G02X1134592Y251027I-1365J-787D01*
G03X1135055Y248560I3741J-575D01*
G02Y246234I-2015J-1163D01*
G03Y244660I1365J-787D01*
G02Y242334I-2015J-1163D01*
G03Y240759I1364J-787D01*
G02X1135080Y238476I-2015J-1164D01*
G01X1135055Y238434D01*
X1135036Y238400D01*
G03X1135055Y236859I1384J-754D01*
G02Y234533I-2015J-1163D01*
G03Y232959I1365J-787D01*
G01X1135080Y232917D01*
G02X1135055Y230634I-2040J-1119D01*
G01X1135036Y230600D01*
G03X1135055Y229059I1384J-754D01*
G02X1135080Y226776I-2015J-1164D01*
G01X1135055Y226734D01*
X1135036Y226700D01*
G03X1135055Y225159I1384J-754D01*
G02X1135080Y222876I-2015J-1164D01*
G01X1135055Y222834D01*
X1135036Y222800D01*
G03X1135055Y221259I1384J-754D01*
G02X1135080Y218976I-2015J-1164D01*
G01X1135055Y218934D01*
X1135036Y218900D01*
G03X1135055Y217359I1384J-754D01*
G02X1135080Y215076I-2015J-1164D01*
G01X1135055Y215034D01*
X1135036Y215000D01*
G03X1135055Y213459I1384J-754D01*
G02Y211133I-2015J-1163D01*
G03Y209558I1364J-788D01*
G01X1135053Y209557D01*
G03X1135450Y209103I1347J778D01*
G02X1136326Y207311I-1374J-1782D01*
G01Y206600D01*
X1140126Y202800D01*
X1142200D01*
G01X1108327Y212285D02*
G03X1108017Y213458I-2323J14D01*
G01X1108016Y213459D01*
G02X1107997Y215000I1365J787D01*
G01X1108016Y215034D01*
X1108041Y215076D01*
G03X1108016Y217359I-2040J1119D01*
G02X1107997Y218900I1365J787D01*
G01X1108016Y218934D01*
X1108041Y218976D01*
G03X1108016Y221259I-2040J1119D01*
G02X1107997Y222800I1365J787D01*
G01X1108016Y222834D01*
X1108041Y222876D01*
G03X1108016Y225159I-2040J1119D01*
G02X1107997Y226700I1365J787D01*
G01X1108016Y226734D01*
X1108041Y226776D01*
G03X1108016Y229059I-2040J1119D01*
G02X1107997Y230600I1365J787D01*
G01X1108016Y230634D01*
G03X1108041Y232917I-2015J1164D01*
G01X1108016Y232959D01*
G02Y234533I1365J787D01*
G03Y236859I-2015J1163D01*
G02X1107997Y238400I1365J787D01*
G01X1108016Y238434D01*
X1108041Y238476D01*
G03X1108016Y240759I-2040J1119D01*
G02Y242334I1366J787D01*
G03X1109374Y245432I-13361J7703D01*
G01X1109381Y245439D01*
Y245447D01*
G01X1134819Y197063D02*
X1133632Y198250D01*
X1132410D01*
X1130200Y200460D01*
Y203000D01*
X1128086Y205114D01*
Y210807D01*
X1128230Y211029D01*
G03X1128295Y213459I-1947J1268D01*
G02X1128276Y215000I1365J787D01*
G01X1128295Y215034D01*
X1128320Y215076D01*
G03X1128295Y217359I-2040J1119D01*
G02X1128276Y218900I1365J787D01*
G01X1128295Y218934D01*
X1128320Y218976D01*
G03X1128295Y221259I-2040J1119D01*
G02X1128276Y222800I1365J787D01*
G01X1128295Y222834D01*
X1128320Y222876D01*
G03X1128295Y225159I-2040J1119D01*
G02X1128276Y226700I1365J787D01*
G01X1128295Y226734D01*
X1128320Y226776D01*
G03X1128295Y229059I-2040J1119D01*
G02X1128276Y230600I1365J787D01*
G01X1128295Y230634D01*
G03X1128320Y232917I-2015J1164D01*
G01X1128295Y232959D01*
G02Y234533I1365J787D01*
G03Y236859I-2015J1163D01*
G02X1128276Y238400I1365J787D01*
G01X1128295Y238434D01*
X1128320Y238476D01*
G03X1128295Y240759I-2040J1119D01*
G02Y242334I1366J787D01*
G03X1129653Y245432I-13361J7703D01*
G01X1129660Y245447D01*
G01X1134819Y197063D02*
X1135870Y196012D01*
X1136088D01*
X1136150Y195950D01*
G01X1129660Y257147D02*
Y255816D01*
X1129917Y255559D01*
G02X1131675Y252084I-257J-2312D01*
G03X1131656Y250543I1365J-787D01*
G01X1131675Y250509D01*
X1131700Y250467D01*
G02X1131675Y248184I-2040J-1119D01*
G03X1131656Y246643I1365J-787D01*
G01X1131675Y246609D01*
X1131700Y246567D01*
G02X1131675Y244284I-2040J-1119D01*
G03X1131656Y242743I1365J-787D01*
G01X1131675Y242709D01*
X1131700Y242667D01*
G02X1131675Y240384I-2040J-1119D01*
G03X1131656Y238843I1365J-787D01*
G01X1131675Y238809D01*
X1131700Y238767D01*
G02X1131675Y236484I-2040J-1119D01*
G03X1131656Y234943I1365J-787D01*
G01X1131675Y234909D01*
G02X1131700Y232626I-2015J-1164D01*
G01X1131675Y232584D01*
G03Y231010I1365J-787D01*
G02Y228684I-2015J-1163D01*
G03X1131656Y227143I1365J-787D01*
G01X1131675Y227109D01*
X1131700Y227067D01*
G02X1131675Y224784I-2040J-1119D01*
G03X1131656Y223243I1365J-787D01*
G01X1131675Y223209D01*
X1131700Y223167D01*
G02X1131675Y220884I-2040J-1119D01*
G03X1131656Y219343I1365J-787D01*
G01X1131675Y219309D01*
X1131700Y219267D01*
G02X1131675Y216984I-2040J-1119D01*
G03X1131656Y215443I1365J-787D01*
G01X1131675Y215409D01*
X1131700Y215367D01*
G02X1131675Y213084I-2040J-1119D01*
G03X1131656Y211543I1365J-787D01*
G01X1132255Y210505D01*
Y202706D01*
X1133761Y201200D01*
X1136382D01*
X1137120Y200462D01*
X1137338D01*
X1137400Y200400D01*
G01X1129660Y249347D02*
X1129653Y249332D01*
G02X1128295Y246234I-14719J4605D01*
G03X1128134Y245055I1365J-787D01*
G02X1127645Y242710I-3808J-429D01*
G03Y240384I2015J-1163D01*
G02X1127664Y238843I-1365J-787D01*
G01X1127645Y238809D01*
X1127620Y238767D01*
G03X1127645Y236484I2040J-1119D01*
G02X1127664Y234943I-1365J-787D01*
G01X1127645Y234909D01*
G03X1127620Y232626I2015J-1164D01*
G01X1127645Y232584D01*
G02Y231010I-1365J-787D01*
G03Y228684I2015J-1163D01*
G02X1127664Y227143I-1365J-787D01*
G01X1127645Y227109D01*
X1127620Y227067D01*
G03X1127645Y224784I2040J-1119D01*
G02X1127664Y223243I-1365J-787D01*
G01X1127645Y223209D01*
X1127620Y223167D01*
G03X1127645Y220884I2040J-1119D01*
G02X1127664Y219343I-1365J-787D01*
G01X1127645Y219309D01*
X1127620Y219267D01*
G03X1127645Y216984I2040J-1119D01*
G02X1127664Y215443I-1365J-787D01*
G01X1127645Y215409D01*
X1127620Y215367D01*
G03X1127645Y213084I2040J-1119D01*
G01X1127646Y213083D01*
G02X1127601Y211439I-1363J-785D01*
G01Y211438D01*
X1127336Y211029D01*
Y204803D01*
X1129450Y202689D01*
Y200149D01*
X1132099Y197500D01*
X1133320D01*
X1135338Y195482D01*
Y195262D01*
X1135400Y195200D01*
G01X1129660Y253247D02*
Y254578D01*
X1129888Y254806D01*
G02X1131025Y252459I-228J-1559D01*
G03X1131000Y250176I2015J-1164D01*
G01X1131025Y250134D01*
X1131044Y250100D01*
G02X1131025Y248559I-1384J-754D01*
G03X1131000Y246276I2015J-1164D01*
G01X1131025Y246234D01*
X1131044Y246200D01*
G02X1131025Y244659I-1384J-754D01*
G03X1131000Y242376I2015J-1164D01*
G01X1131025Y242334D01*
X1131044Y242300D01*
G02X1131025Y240759I-1384J-754D01*
G03X1131000Y238476I2015J-1164D01*
G01X1131025Y238434D01*
X1131044Y238400D01*
G02X1131025Y236859I-1384J-754D01*
G03Y234533I2015J-1163D01*
G02Y232959I-1365J-787D01*
G01X1131000Y232917D01*
G03X1131025Y230634I2040J-1119D01*
G01X1131044Y230600D01*
G02X1131025Y229059I-1384J-754D01*
G03X1131000Y226776I2015J-1164D01*
G01X1131025Y226734D01*
X1131044Y226700D01*
G02X1131025Y225159I-1384J-754D01*
G03X1131000Y222876I2015J-1164D01*
G01X1131025Y222834D01*
X1131044Y222800D01*
G02X1131025Y221259I-1384J-754D01*
G03X1131000Y218976I2015J-1164D01*
G01X1131025Y218934D01*
X1131044Y218900D01*
G02X1131025Y217359I-1384J-754D01*
G03X1131000Y215076I2015J-1164D01*
G01X1131025Y215034D01*
X1131044Y215000D01*
G02X1131025Y213459I-1384J-754D01*
G03Y211133I2015J-1163D01*
G01X1131505Y210303D01*
Y202395D01*
X1133450Y200450D01*
X1136071D01*
X1136650Y199871D01*
Y199650D01*
G01X1164661Y276270D02*
X1164660Y276271D01*
X1164536D01*
G03X1163215Y275483I44J-1575D01*
G02X1161285Y274321I-2015J1163D01*
G01X1161115D01*
G02X1159185Y275483I85J2325D01*
G03X1156455Y275485I-1366J-788D01*
G02X1154510Y274322I-2015J1162D01*
G03X1154169Y274299I138J-4587D01*
G03X1153075Y273534I271J-1552D01*
G02X1151130Y272371I-2015J1162D01*
G01X1151001D01*
G03X1149676Y270043I59J-1575D01*
G01X1149695Y270009D01*
X1149720Y269967D01*
G02X1147765Y266522I-2040J-1120D01*
G01X1147636D01*
G03X1146443Y265922I45J-1575D01*
G01X1146526Y265612D01*
X1147680Y264947D01*
G01X1143349Y265620D02*
X1143605Y265364D01*
X1143613D01*
X1143650Y265327D01*
X1145294D01*
X1145981Y264640D01*
X1147373D01*
X1147680Y264947D01*
G01X1102621Y253247D02*
X1103334Y251600D01*
X1103853Y250400D01*
X1103918Y250251D01*
X1104005Y250100D01*
G02X1103986Y248559I-1384J-754D01*
G01X1103774Y248192D01*
G01X1112761Y255196D02*
X1114126Y252084D01*
G02X1114313Y251027I-1365J-787D01*
G01X1240022Y141773D02*
X1238939Y142856D01*
X1237755D01*
X1237398Y143213D01*
X1237397D01*
X1232765Y147845D01*
G01X1196149Y205523D02*
X1193764Y207908D01*
Y208321D01*
X1193582Y208501D01*
G02X1192984Y209184I1417J1844D01*
G03X1191690Y209971I-1365J-787D01*
G01X1191534D01*
G02X1189604Y211133I85J2325D01*
G03X1188283Y211921I-1365J-787D01*
G01X1188188D01*
G02X1186224Y213084I51J2326D01*
G03X1184918Y213871I-1365J-788D01*
G01X1184789D01*
G02X1182844Y215034I70J2325D01*
G03X1181523Y215822I-1365J-787D01*
G01X1181394D01*
G02X1179464Y216984I85J2325D01*
G03X1178158Y217771I-1365J-788D01*
G01X1178029D01*
G02X1176084Y218934I70J2325D01*
G03X1174763Y219722I-1365J-787D01*
G01X1174634D01*
G02X1172704Y220884I85J2325D01*
G03X1171398Y221671I-1365J-788D01*
G01X1171269D01*
G02X1169324Y222834I70J2325D01*
G01X1169311Y222857D01*
G03X1167960Y223622I-1351J-810D01*
G01X1167875D01*
G02X1165945Y224784I85J2325D01*
G03X1164639Y225571I-1365J-788D01*
G01X1164510D01*
G02X1162565Y226734I70J2325D01*
G03X1161244Y227522I-1365J-787D01*
G01X1161115D01*
G02X1159185Y228684I85J2325D01*
G03X1157879Y229471I-1365J-788D01*
G01X1157769D01*
G02X1155805Y230634I51J2326D01*
G02X1155780Y232917I2015J1164D01*
G01X1155805Y232959D01*
G03Y234533I-1365J787D01*
G02Y236859I2015J1163D01*
G03X1155824Y238400I-1365J787D01*
G01X1155805Y238434D01*
X1155780Y238476D01*
G02X1155805Y240759I2040J1119D01*
G03X1155824Y242300I-1365J787D01*
G01X1155805Y242334D01*
G03X1154484Y243122I-1365J-787D01*
G01X1154355D01*
G02X1152425Y244284I85J2325D01*
G02X1152400Y246567I2015J1164D01*
G01X1152425Y246609D01*
X1152444Y246643D01*
G03X1152425Y248184I-1384J754D01*
G02X1152400Y250467I2015J1164D01*
G01X1152425Y250509D01*
X1152444Y250543D01*
G03X1152425Y252084I-1384J754D01*
G02X1152400Y254367I2015J1164D01*
G01X1152425Y254409D01*
G02X1154183Y255559I2015J-1162D01*
G01X1154440Y255816D01*
Y257147D01*
G01X1240010Y144754D02*
X1239261Y144006D01*
X1238448D01*
X1202500Y179954D01*
G01Y194343D02*
Y200802D01*
X1196435Y206867D01*
X1194432Y208865D01*
X1194298Y208863D01*
X1194115Y209043D01*
G02X1193964Y209159I883J1305D01*
G02X1193885Y209232I885J1037D01*
G02X1193634Y209559I1114J1115D01*
G03X1191689Y210722I-2015J-1162D01*
G01X1191548D01*
G02X1190254Y211509I71J1574D01*
G03X1188290Y212672I-2015J-1163D01*
G01X1188180D01*
G02X1186874Y213459I59J1575D01*
G03X1184944Y214621I-2015J-1163D01*
G01X1184815D01*
G02X1183494Y215409I44J1575D01*
G03X1181549Y216572I-2015J-1162D01*
G01X1181420D01*
G02X1180114Y217359I59J1575D01*
G03X1178184Y218521I-2015J-1163D01*
G01X1178055D01*
G02X1176734Y219309I44J1575D01*
G03X1174789Y220472I-2015J-1162D01*
G01X1174660D01*
G02X1173354Y221259I59J1575D01*
G03X1171424Y222421I-2015J-1163D01*
G01X1171339D01*
G02X1169988Y223186I0J1575D01*
G01X1169975Y223209D01*
G03X1168030Y224372I-2015J-1162D01*
G01X1167901D01*
G02X1166595Y225159I59J1575D01*
G03X1164665Y226321I-2015J-1163D01*
G01X1164536D01*
G02X1163215Y227109I44J1575D01*
G03X1161270Y228272I-2015J-1162D01*
G01X1161141D01*
G02X1159835Y229059I59J1575D01*
G03X1157871Y230222I-2015J-1163D01*
G01X1157776D01*
G02X1156455Y232584I44J1575D01*
G01X1156480Y232626D01*
G03X1156455Y234909I-2040J1119D01*
G01X1156436Y234943D01*
G02X1156455Y236484I1384J754D01*
G03X1156480Y238767I-2015J1164D01*
G01X1156455Y238809D01*
X1156436Y238843D01*
G02X1156455Y240384I1384J754D01*
G03X1154510Y243872I-2015J1163D01*
G01X1154381D01*
G02X1153056Y246200I59J1575D01*
G01X1153075Y246234D01*
X1153100Y246276D01*
G03X1153075Y248559I-2040J1119D01*
G02X1153056Y250100I1365J787D01*
G01X1153075Y250134D01*
X1153100Y250176D01*
G03X1153376Y251072I-2040J1119D01*
G01X1153600Y251296D01*
X1157820D01*
G01X1197943Y209344D02*
X1197145Y210136D01*
X1197144Y210270D01*
X1196962Y210450D01*
G02X1196364Y211133I1417J1844D01*
G03X1195043Y211921I-1365J-787D01*
G01X1194948D01*
G02X1192984Y213084I51J2326D01*
G03X1191678Y213871I-1365J-788D01*
G01X1191549D01*
G02X1189604Y215034I70J2325D01*
G03X1188283Y215822I-1365J-787D01*
G01X1188154D01*
G02X1186224Y216984I85J2325D01*
G03X1184918Y217771I-1365J-788D01*
G01X1184789D01*
G02X1182844Y218934I70J2325D01*
G03X1181523Y219722I-1365J-787D01*
G01X1181394D01*
G02X1179464Y220884I85J2325D01*
G03X1178158Y221671I-1365J-788D01*
G01X1178029D01*
G02X1176084Y222834I70J2325D01*
G03X1174763Y223622I-1365J-787D01*
G01X1174634D01*
G02X1172704Y224784I85J2325D01*
G03X1171398Y225571I-1365J-788D01*
G01X1171269D01*
G02X1169324Y226734I70J2325D01*
G01X1169311Y226757D01*
G03X1167960Y227522I-1351J-810D01*
G01X1167875D01*
G02X1165945Y228684I85J2325D01*
G03X1164639Y229471I-1365J-788D01*
G01X1164529D01*
G02X1162565Y230634I51J2326D01*
G03X1161271Y231421I-1365J-787D01*
G01X1161130D01*
G02X1159185Y234909I70J2325D01*
G01X1159204Y234943D01*
G03X1159185Y236484I-1384J754D01*
G02X1159160Y238767I2015J1164D01*
G01X1159185Y238809D01*
X1159204Y238843D01*
G03X1159185Y240384I-1384J754D01*
G02X1159160Y242667I2015J1164D01*
G01X1159185Y242709D01*
X1159204Y242743D01*
G03X1157879Y245071I-1384J753D01*
G01X1157750D01*
G02X1155627Y246619I70J2325D01*
G03X1154440Y249347I-20075J-7113D01*
G01X1213640Y233600D02*
X1211300D01*
X1209116Y231416D01*
X1207869D01*
X1206950Y230497D01*
Y225297D01*
X1206970Y225277D01*
Y223426D01*
X1205968Y222424D01*
X1205133D01*
G02X1203774Y223209I0J1568D01*
G03X1201829Y224372I-2015J-1162D01*
G01X1201700D01*
G02X1200394Y225159I59J1575D01*
G03X1196364I-2015J-1163D01*
G02X1195058Y224372I-1365J788D01*
G01X1194940D01*
G02X1193634Y225159I59J1575D01*
G03X1189604I-2015J-1163D01*
G02X1186874I-1365J788D01*
G03X1184944Y226321I-2015J-1163D01*
G01X1184815D01*
G02X1183494Y227109I44J1575D01*
G03X1181549Y228272I-2015J-1162D01*
G01X1181420D01*
G02X1180114Y229059I59J1575D01*
G03X1178150Y230222I-2015J-1163D01*
G01X1178055D01*
G02X1176734Y231010I44J1575D01*
G03X1174804Y232172I-2015J-1163D01*
G01X1174648D01*
G02X1173354Y232959I71J1574D01*
G03X1171409Y234122I-2015J-1162D01*
G01X1171291D01*
G02X1169975Y234909I48J1574D01*
G03X1168011Y236072I-2015J-1163D01*
G01X1167901D01*
G02X1166595Y236859I59J1575D01*
G02X1166576Y238400I1365J787D01*
G01X1166595Y238434D01*
X1166620Y238476D01*
G03X1166595Y240759I-2040J1119D01*
G02X1166576Y242300I1365J787D01*
G01X1166595Y242334D01*
X1166620Y242376D01*
G03X1166595Y244659I-2040J1119D01*
G02X1166576Y246200I1365J787D01*
G01X1166595Y246234D01*
X1166620Y246276D01*
G03X1166595Y248559I-2040J1119D01*
G03X1164665Y249721I-2015J-1163D01*
G01X1164536D01*
G02X1163215Y250509I44J1575D01*
G01X1163196Y250543D01*
G02X1163215Y252084I1384J754D01*
G03X1163332Y254180I-2015J1164D01*
G01X1162112Y255400D01*
X1158940D01*
X1155340Y259000D01*
X1153500D01*
X1151834Y260666D01*
X1150366D01*
X1148500Y258800D01*
X1147600D01*
X1145400Y261000D01*
X1140800D01*
X1139200Y259400D01*
X1135846D01*
X1134446Y260800D01*
X1132100D01*
X1130300Y259000D01*
X1129200D01*
X1127500Y260700D01*
X1125200D01*
X1123700Y259200D01*
X1122526D01*
X1120626Y261100D01*
X1118600D01*
X1117083Y262617D01*
X1116183D01*
X1113853Y264947D01*
X1109381D01*
G01X1151060Y262996D02*
X1152214Y262331D01*
X1152566Y262426D01*
G02X1154370Y263372I1873J-1379D01*
G01X1154440D01*
G03X1155804Y264160I0J1575D01*
G01X1155823Y265699D02*
G02X1155805Y268059I2000J1195D01*
G02X1157735Y269221I2015J-1163D01*
G01X1157864D01*
G03X1159185Y270009I-44J1575D01*
G02X1161130Y271172I2015J-1162D01*
G01X1161259D01*
G03X1162565Y271959I-59J1575D01*
G02X1164495Y273121I2015J-1163D01*
G01X1164665D01*
G02X1166595Y271959I-85J-2325D01*
G03X1169311Y271937I1364J788D01*
G01X1169324Y271960D01*
G02X1171241Y273121I2015J-1164D01*
G01X1171383D01*
G03X1172704Y273909I-44J1575D01*
G02X1174649Y275072I2015J-1162D01*
G01X1174789D01*
G02X1176734Y273909I-70J-2325D01*
G03X1179464I1365J787D01*
G02X1181409Y275072I2015J-1162D01*
G01X1181549D01*
G02X1183494Y273909I-70J-2325D01*
G03X1186224I1365J787D01*
G02X1188169Y275072I2015J-1162D01*
G01X1188309D01*
G02X1190254Y273909I-70J-2325D01*
G03X1191575Y273121I1365J787D01*
G01X1191704D01*
G02X1193634Y271959I-85J-2325D01*
G03X1194940Y271172I1365J788D01*
G01X1195069D01*
G02X1197014Y270009I-70J-2325D01*
G03X1198308Y269222I1365J787D01*
G01X1198450D01*
G03X1199744Y270009I-71J1574D01*
G02X1203774I2015J-1162D01*
G03X1206504I1365J787D01*
G02X1208262Y271169I2036J-1174D01*
G01X1210134D01*
X1210240Y271275D01*
G01X1154440Y261047D02*
X1153286Y261712D01*
X1153203Y262022D01*
G02X1154396Y262622I1238J-975D01*
G01X1154440D01*
G03X1156456Y263783I0J2331D01*
G01X1156481Y266068D02*
G02X1156455Y267684I1336J830D01*
G02X1157761Y268471I1365J-788D01*
G01X1157890D01*
G03X1159835Y269634I-70J2325D01*
G02X1161156Y270422I1365J-787D01*
G01X1161285D01*
G03X1163215Y271584I-85J2325D01*
G02X1164521Y272371I1365J-788D01*
G01X1164639D01*
G02X1165945Y271584I-59J-1575D01*
G03X1169988Y271606I2015J1163D01*
G02X1171339Y272371I1351J-810D01*
G01X1171409D01*
G03X1173354Y273534I-70J2325D01*
G02X1174648Y274321I1365J-787D01*
G01X1174790D01*
G02X1176084Y273534I-71J-1574D01*
G03X1180114I2015J1162D01*
G02X1181408Y274321I1365J-787D01*
G01X1181550D01*
G02X1182844Y273534I-71J-1574D01*
G03X1186874I2015J1162D01*
G02X1188168Y274321I1365J-787D01*
G01X1188310D01*
G02X1189604Y273534I-71J-1574D01*
G03X1191549Y272371I2015J1162D01*
G01X1191678D01*
G02X1192984Y271584I-59J-1575D01*
G03X1194914Y270422I2015J1163D01*
G01X1195043D01*
G02X1196364Y269634I-44J-1575D01*
G03X1198281Y268472I2015J1162D01*
G01X1198477D01*
G03X1200394Y269634I-98J2324D01*
G02X1203124I1365J-787D01*
G03X1207154I2015J1162D01*
G02X1208511Y270418I1357J-783D01*
G01X1210157D01*
X1210250Y270325D01*
G01X1130865Y288721D02*
G02X1132795Y287559I-85J-2325D01*
G03X1134101Y286772I1365J788D01*
G01X1134230D01*
G02X1136034Y285826I-69J-2325D01*
G01X1136386Y285731D01*
X1137540Y286396D01*
G01X1134160Y284447D02*
X1135314Y285112D01*
X1135397Y285422D01*
G03X1134204Y286022I-1238J-975D01*
G01X1134075D01*
G02X1132145Y287184I85J2325D01*
G03X1130784Y287970I-1361J-785D01*
G01X1129570D01*
X1128300Y286700D01*
X1123415D01*
G01X1200602Y304184D02*
X1199264Y305522D01*
X1194955D01*
G03X1193634Y304734I44J-1575D01*
G02X1189604I-2015J1162D01*
G03X1186874I-1365J-787D01*
G02X1182844I-2015J1162D01*
G03X1180114I-1365J-787D01*
G02X1176084I-2015J1162D01*
G03X1173354I-1365J-787D01*
G02X1169324I-2015J1162D01*
G01X1169298Y304779D01*
G03X1166595Y304734I-1338J-832D01*
G02X1162565I-2015J1162D01*
G03X1159835I-1365J-787D01*
G02X1155805I-2015J1162D01*
G03X1154484Y305522I-1365J-787D01*
G01X1154355D01*
G02X1152566Y306467I84J2325D01*
G01X1152214Y306562D01*
X1151060Y305896D01*
G01X1147632Y294573D02*
G02X1146315Y295358I43J1569D01*
G03X1144370Y296521I-2015J-1162D01*
G01X1144241D01*
G02X1143063Y297120I60J1575D01*
G01X1143146Y297430D01*
X1144300Y298096D01*
G01X1199664Y301490D02*
X1199577D01*
X1199576Y301491D01*
X1199128D01*
G01X1197264Y301622D02*
X1194955D01*
G03X1193634Y300834I44J-1575D01*
G02X1191689Y299671I-2015J1162D01*
G01X1191549D01*
G02X1189604Y300834I70J2325D01*
G03X1188283Y301622I-1365J-787D01*
G01X1188195D01*
G03X1186874Y300834I44J-1575D01*
G02X1184929Y299671I-2015J1162D01*
G01X1184789D01*
G02X1182844Y300834I70J2325D01*
G03X1181523Y301622I-1365J-787D01*
G01X1181435D01*
G03X1180114Y300834I44J-1575D01*
G02X1178169Y299671I-2015J1162D01*
G01X1178029D01*
G02X1176084Y300834I70J2325D01*
G03X1174763Y301622I-1365J-787D01*
G01X1174675D01*
G03X1173354Y300834I44J-1575D01*
G02X1171409Y299671I-2015J1162D01*
G01X1171339D01*
G03X1169988Y298906I0J-1575D01*
G01X1169975Y298883D01*
G02X1168058Y297722I-2015J1164D01*
G01X1167916D01*
G03X1166595Y296934I44J-1575D01*
G02X1164650Y295771I-2015J1162D01*
G01X1164510D01*
G02X1162565Y296934I70J2325D01*
G03X1161244Y297722I-1365J-787D01*
G01X1161156D01*
G03X1159835Y296934I44J-1575D01*
G02X1157890Y295771I-2015J1162D01*
G01X1157750D01*
G02X1155805Y296934I70J2325D01*
G03X1154484Y297722I-1365J-787D01*
G01X1154355D01*
G02X1152425Y298884I85J2325D01*
G03X1151119Y299671I-1365J-788D01*
G01X1150990D01*
G02X1149045Y300834I70J2325D01*
G03X1147724Y301622I-1365J-787D01*
G01X1147595D01*
G02X1145665Y302784I85J2325D01*
G03X1144359Y303571I-1365J-788D01*
G01X1144230D01*
G02X1142285Y304734I70J2325D01*
G03X1140964Y305522I-1365J-787D01*
G01X1140876D01*
G03X1139683Y304922I45J-1575D01*
G01X1139766Y304612D01*
X1140920Y303947D01*
G01X1199586Y302520D02*
X1197661D01*
X1197514Y302373D01*
X1194999D01*
G03X1192984Y301209I0J-2326D01*
G02X1191663Y300421I-1365J787D01*
G01X1191575D01*
G02X1190254Y301209I44J1575D01*
G03X1188309Y302372I-2015J-1162D01*
G01X1188169D01*
G03X1186224Y301209I70J-2325D01*
G02X1184903Y300421I-1365J787D01*
G01X1184815D01*
G02X1183494Y301209I44J1575D01*
G03X1181549Y302372I-2015J-1162D01*
G01X1181409D01*
G03X1179464Y301209I70J-2325D01*
G02X1178143Y300421I-1365J787D01*
G01X1178055D01*
G02X1176734Y301209I44J1575D01*
G03X1174789Y302372I-2015J-1162D01*
G01X1174649D01*
G03X1172704Y301209I70J-2325D01*
G02X1171383Y300421I-1365J787D01*
G01X1171241D01*
G03X1169324Y299260I98J-2325D01*
G01X1169311Y299237D01*
G02X1167960Y298472I-1351J810D01*
G01X1167890D01*
G03X1165945Y297309I70J-2325D01*
G02X1164624Y296521I-1365J787D01*
G01X1164536D01*
G02X1163215Y297309I44J1575D01*
G03X1161270Y298472I-2015J-1162D01*
G01X1161130D01*
G03X1159185Y297309I70J-2325D01*
G02X1157864Y296521I-1365J787D01*
G01X1157776D01*
G02X1156455Y297309I44J1575D01*
G03X1154510Y298472I-2015J-1162D01*
G01X1154381D01*
G02X1153075Y299259I59J1575D01*
G03X1151145Y300421I-2015J-1163D01*
G01X1151016D01*
G02X1149695Y301209I44J1575D01*
G03X1147750Y302372I-2015J-1162D01*
G01X1147621D01*
G02X1146315Y303159I59J1575D01*
G03X1144385Y304321I-2015J-1163D01*
G01X1144256D01*
G02X1142935Y305109I44J1575D01*
G03X1140990Y306272I-2015J-1162D01*
G01X1140850D01*
G03X1139046Y305326I69J-2325D01*
G01X1138694Y305231D01*
X1137540Y305896D01*
G01X1214344Y290787D02*
X1212510Y292621D01*
X1204639D01*
G03X1203267Y291448I800J-2325D01*
G02X1202416Y290672I-1508J799D01*
G01X1201689D01*
G03X1199744Y289509I70J-2325D01*
G02X1198423Y288721I-1365J787D01*
G01X1198335D01*
G02X1197014Y289509I44J1575D01*
G03X1195069Y290672I-2015J-1162D01*
G01X1194929D01*
G03X1192984Y289509I70J-2325D01*
G02X1191663Y288721I-1365J787D01*
G01X1191575D01*
G02X1190254Y289509I44J1575D01*
G03X1188309Y290672I-2015J-1162D01*
G01X1188169D01*
G03X1186224Y289509I70J-2325D01*
G02X1184903Y288721I-1365J787D01*
G01X1184815D01*
G02X1183494Y289509I44J1575D01*
G03X1181549Y290672I-2015J-1162D01*
G01X1181409D01*
G03X1179464Y289509I70J-2325D01*
G02X1178143Y288721I-1365J787D01*
G01X1178055D01*
G02X1176734Y289509I44J1575D01*
G03X1174789Y290672I-2015J-1162D01*
G01X1174649D01*
G03X1172704Y289509I70J-2325D01*
G02X1171383Y288721I-1365J787D01*
G01X1171241D01*
G03X1169324Y287560I98J-2325D01*
G01X1169311Y287537D01*
G02X1167960Y286772I-1351J810D01*
G01X1167890D01*
G03X1165945Y285609I70J-2325D01*
G02X1164624Y284821I-1365J787D01*
G01X1164536D01*
G02X1163215Y285609I44J1575D01*
G03X1161270Y286772I-2015J-1162D01*
G01X1161130D01*
G03X1159185Y285609I70J-2325D01*
G02X1157864Y284821I-1365J787D01*
G01X1157776D01*
G02X1156455Y285609I44J1575D01*
G03X1154510Y286772I-2015J-1162D01*
G01X1154381D01*
G02X1153075Y287559I59J1575D01*
G03X1151145Y288721I-2015J-1163D01*
G01X1151016D01*
G02X1149695Y289509I44J1575D01*
G03X1147750Y290672I-2015J-1162D01*
G01X1147621D01*
G02X1146315Y291459I59J1575D01*
G03X1144385Y292621I-2015J-1163D01*
G01X1144256D01*
G02X1142935Y293409I44J1575D01*
G03X1140990Y294572I-2015J-1162D01*
G01X1140861D01*
G02X1139683Y295171I60J1575D01*
G01X1139766Y295481D01*
X1140920Y296147D01*
G01X1214033Y289754D02*
X1212116Y291671D01*
X1209303D01*
X1209103Y291871D01*
X1204782D01*
G03X1203931Y291095I657J-1575D01*
G02X1202559Y289922I-2172J1152D01*
G01X1201715D01*
G03X1200394Y289134I44J-1575D01*
G02X1198449Y287971I-2015J1162D01*
G01X1198309D01*
G02X1196364Y289134I70J2325D01*
G03X1195043Y289922I-1365J-787D01*
G01X1194955D01*
G03X1193634Y289134I44J-1575D01*
G02X1191689Y287971I-2015J1162D01*
G01X1191549D01*
G02X1189604Y289134I70J2325D01*
G03X1188283Y289922I-1365J-787D01*
G01X1188195D01*
G03X1186874Y289134I44J-1575D01*
G02X1184929Y287971I-2015J1162D01*
G01X1184789D01*
G02X1182844Y289134I70J2325D01*
G03X1181523Y289922I-1365J-787D01*
G01X1181435D01*
G03X1180114Y289134I44J-1575D01*
G02X1178169Y287971I-2015J1162D01*
G01X1178029D01*
G02X1176084Y289134I70J2325D01*
G03X1174763Y289922I-1365J-787D01*
G01X1174675D01*
G03X1173354Y289134I44J-1575D01*
G02X1171409Y287971I-2015J1162D01*
G01X1171339D01*
G03X1169988Y287206I0J-1575D01*
G01X1169975Y287183D01*
G02X1168058Y286022I-2015J1164D01*
G01X1167916D01*
G03X1166595Y285234I44J-1575D01*
G02X1164650Y284071I-2015J1162D01*
G01X1164510D01*
G02X1162565Y285234I70J2325D01*
G03X1161244Y286022I-1365J-787D01*
G01X1161156D01*
G03X1159835Y285234I44J-1575D01*
G02X1157890Y284071I-2015J1162D01*
G01X1157750D01*
G02X1155805Y285234I70J2325D01*
G03X1154484Y286022I-1365J-787D01*
G01X1154355D01*
G02X1152425Y287184I85J2325D01*
G03X1151119Y287971I-1365J-788D01*
G01X1150990D01*
G02X1149045Y289134I70J2325D01*
G03X1147724Y289922I-1365J-787D01*
G01X1147595D01*
G02X1145665Y291084I85J2325D01*
G03X1144359Y291871I-1365J-788D01*
G01X1144230D01*
G02X1142285Y293034I70J2325D01*
G03X1140964Y293822I-1365J-787D01*
G01X1140835D01*
G02X1139046Y294767I84J2325D01*
G01X1138694Y294862D01*
X1137540Y294196D01*
G01X1103741Y356596D02*
X1102145Y358743D01*
G02X1102026Y360681I2349J1117D01*
G02X1104242Y362902I3333J-1109D01*
G03X1105106Y365184I-501J1494D01*
G02X1105081Y367467I2015J1164D01*
G01X1105106Y367509D01*
X1105125Y367543D01*
G03X1105106Y369084I-1384J754D01*
G02Y371410I2015J1163D01*
G03Y372984I-1365J787D01*
G01X1105081Y373026D01*
G02X1107070Y376472I2040J1120D01*
G01X1107180D01*
G03X1108486Y377259I-59J1575D01*
G02X1110416Y378421I2015J-1163D01*
G01X1110545D01*
G03X1111866Y379209I-44J1575D01*
G02X1113811Y380372I2015J-1162D01*
G01X1113940D01*
G03X1115246Y381159I-59J1575D01*
G02X1117176Y382321I2015J-1163D01*
G01X1117305D01*
G03X1118626Y383109I-44J1575D01*
G02X1120571Y384272I2015J-1162D01*
G01X1120700D01*
G03X1122025Y386600I-59J1575D01*
G01X1122006Y386634D01*
X1121981Y386676D01*
G02X1122006Y388959I2040J1119D01*
G03X1122025Y390500I-1365J787D01*
G01X1122006Y390534D01*
X1121981Y390576D01*
G02X1122006Y392859I2040J1119D01*
G03X1122025Y394400I-1365J787D01*
G01X1122006Y394434D01*
X1121981Y394476D01*
G02X1122006Y396759I2040J1119D01*
G03X1122025Y398300I-1365J787D01*
G01X1122006Y398334D01*
X1121981Y398376D01*
G02X1122006Y400659I2040J1119D01*
G03X1122025Y402200I-1365J787D01*
G01X1122006Y402234D01*
X1121981Y402276D01*
G02X1122006Y404559I2040J1119D01*
G03X1122025Y406100I-1365J787D01*
G01X1122006Y406134D01*
X1121981Y406176D01*
G02X1122006Y408459I2040J1119D01*
G03X1122025Y410000I-1365J787D01*
G01X1122006Y410034D01*
X1121981Y410076D01*
G02X1122006Y412359I2040J1119D01*
G03X1122025Y413900I-1365J787D01*
G01X1122006Y413934D01*
X1121981Y413976D01*
G02X1122375Y416738I2038J1118D01*
G01X1124454Y418817D01*
Y419174D01*
X1123687Y419941D01*
G01X1103741Y360496D02*
X1105690Y363118D01*
X1105756Y363234D01*
X1105781Y363276D01*
G03X1105756Y365559I-2040J1119D01*
G02X1105737Y367100I1365J787D01*
G01X1105756Y367134D01*
X1105781Y367176D01*
G03X1105756Y369459I-2040J1119D01*
G02X1105737Y371000I1365J787D01*
G01X1105756Y371034D01*
G03X1105781Y373317I-2015J1164D01*
G01X1105756Y373359D01*
G02X1107077Y375721I1365J787D01*
G01X1107172D01*
G03X1109136Y376884I-51J2326D01*
G02X1110442Y377671I1365J-788D01*
G01X1110571D01*
G03X1112516Y378834I-70J2325D01*
G02X1113837Y379622I1365J-787D01*
G01X1113966D01*
G03X1115896Y380784I-85J2325D01*
G02X1117202Y381571I1365J-788D01*
G01X1117331D01*
G03X1119276Y382734I-70J2325D01*
G02X1120597Y383522I1365J-787D01*
G01X1120726D01*
G03X1122681Y386967I-85J2325D01*
G01X1122656Y387009D01*
X1122637Y387043D01*
G02X1122656Y388584I1384J754D01*
G03X1122681Y390867I-2015J1164D01*
G01X1122656Y390909D01*
X1122637Y390943D01*
G02X1122656Y392484I1384J754D01*
G03X1122681Y394767I-2015J1164D01*
G01X1122656Y394809D01*
X1122637Y394843D01*
G02X1122656Y396384I1384J754D01*
G03X1122681Y398667I-2015J1164D01*
G01X1122656Y398709D01*
X1122637Y398743D01*
G02X1122656Y400284I1384J754D01*
G03X1122681Y402567I-2015J1164D01*
G01X1122656Y402609D01*
X1122637Y402643D01*
G02X1122656Y404184I1384J754D01*
G03X1122681Y406467I-2015J1164D01*
G01X1122656Y406509D01*
X1122637Y406543D01*
G02X1122656Y408084I1384J754D01*
G03X1122681Y410367I-2015J1164D01*
G01X1122656Y410409D01*
X1122637Y410443D01*
G02X1122656Y411984I1384J754D01*
G03X1122681Y414267I-2015J1164D01*
G01X1122656Y414309D01*
X1122637Y414343D01*
G02X1122907Y416210I1383J753D01*
G01X1125204Y418507D01*
Y418958D01*
X1126187Y419941D01*
G01X1100361Y354647D02*
X1099062Y357646D01*
X1098996Y357759D01*
G02X1098977Y359300I1365J787D01*
G01X1098996Y359334D01*
X1099021Y359376D01*
G03X1098996Y361659I-2040J1119D01*
G02X1099498Y363765I1365J787D01*
G03X1100026Y364181I-2096J3203D01*
G02X1100992Y364903I2026J-1703D01*
G03X1101745Y367100I-631J1444D01*
G01X1101726Y367134D01*
X1101701Y367176D01*
G02X1101726Y369459I2040J1119D01*
G03X1101745Y371000I-1365J787D01*
G01X1101726Y371034D01*
G02X1101701Y373317I2015J1164D01*
G01X1101726Y373359D01*
G03Y374933I-1365J787D01*
G02X1103656Y378421I2015J1163D01*
G01X1103785D01*
G03X1105106Y379209I-44J1575D01*
G02X1107051Y380372I2015J-1162D01*
G01X1107180D01*
G03X1108486Y381159I-59J1575D01*
G02X1110416Y382321I2015J-1163D01*
G01X1110545D01*
G03X1111866Y383109I-44J1575D01*
G02X1113811Y384272I2015J-1162D01*
G01X1113940D01*
G03X1115246Y385059I-59J1575D01*
G02X1117176Y386221I2015J-1163D01*
G01X1117305D01*
G03X1118626Y388584I-44J1575D01*
G02X1118601Y390867I2015J1164D01*
G01X1118626Y390909D01*
X1118645Y390943D01*
G03X1118626Y392484I-1384J754D01*
G02X1118601Y394767I2015J1164D01*
G01X1118626Y394809D01*
X1118645Y394843D01*
G03X1118626Y396384I-1384J754D01*
G02X1118601Y398667I2015J1164D01*
G01X1118626Y398709D01*
X1118645Y398743D01*
G03X1118626Y400284I-1384J754D01*
G02X1118601Y402567I2015J1164D01*
G01X1118626Y402609D01*
X1118645Y402643D01*
G03X1118626Y404184I-1384J754D01*
G02X1118601Y406467I2015J1164D01*
G01X1118626Y406509D01*
X1118645Y406543D01*
G03X1118626Y408084I-1384J754D01*
G02X1118601Y410367I2015J1164D01*
G01X1118626Y410409D01*
X1118645Y410443D01*
G03X1118626Y411984I-1384J754D01*
G02X1118601Y414267I2015J1164D01*
G01X1118626Y414309D01*
X1118645Y414343D01*
G03X1118626Y415884I-1384J754D01*
G02X1118314Y417047I2015J1164D01*
G01X1100361Y362447D02*
X1102310Y365068D01*
X1102376Y365184D01*
G03X1102401Y367467I-2015J1164D01*
G01X1102376Y367509D01*
X1102357Y367543D01*
G02X1102376Y369084I1384J754D01*
G03Y371410I-2015J1163D01*
G02Y372984I1365J787D01*
G01X1102401Y373026D01*
G03X1102376Y375309I-2040J1119D01*
G01X1102357Y375343D01*
G02X1103682Y377671I1384J753D01*
G01X1103811D01*
G03X1105756Y378834I-70J2325D01*
G02X1107077Y379622I1365J-787D01*
G01X1107206D01*
G03X1109136Y380784I-85J2325D01*
G02X1110442Y381571I1365J-788D01*
G01X1110571D01*
G03X1112516Y382734I-70J2325D01*
G02X1113837Y383522I1365J-787D01*
G01X1113966D01*
G03X1115896Y384684I-85J2325D01*
G02X1117202Y385471I1365J-788D01*
G01X1117331D01*
G03X1119276Y388959I-70J2325D01*
G02X1119257Y390500I1365J787D01*
G01X1119276Y390534D01*
X1119301Y390576D01*
G03X1119276Y392859I-2040J1119D01*
G02X1119257Y394400I1365J787D01*
G01X1119276Y394434D01*
X1119301Y394476D01*
G03X1119276Y396759I-2040J1119D01*
G02X1119257Y398300I1365J787D01*
G01X1119276Y398334D01*
X1119301Y398376D01*
G03X1119276Y400659I-2040J1119D01*
G02X1119257Y402200I1365J787D01*
G01X1119276Y402234D01*
X1119301Y402276D01*
G03X1119276Y404559I-2040J1119D01*
G02X1119257Y406100I1365J787D01*
G01X1119276Y406134D01*
X1119301Y406176D01*
G03X1119276Y408459I-2040J1119D01*
G02X1119257Y410000I1365J787D01*
G01X1119276Y410034D01*
X1119301Y410076D01*
G03X1119276Y412359I-2040J1119D01*
G02X1119257Y413900I1365J787D01*
G01X1119276Y413934D01*
X1119301Y413976D01*
G03X1119276Y416259I-2040J1119D01*
G02X1119065Y417047I1365J788D01*
G01Y417887D01*
X1120306Y419128D01*
Y420144D01*
X1121187Y421025D01*
G01X1113881Y354647D02*
X1112023Y357146D01*
X1111932Y357268D01*
X1111866Y357384D01*
G02X1111841Y359667I2015J1164D01*
G01X1111866Y359709D01*
X1111885Y359743D01*
G03X1111866Y361284I-1384J754D01*
G02X1111841Y363567I2015J1164D01*
G01X1111866Y363609D01*
X1111885Y363643D01*
G03X1111866Y365184I-1384J754D01*
G02X1111841Y367467I2015J1164D01*
G01X1111866Y367509D01*
X1111885Y367543D01*
G03X1111866Y369084I-1384J754D01*
G02X1113796Y372572I2015J1163D01*
G01X1113952D01*
G03X1115246Y373359I-71J1574D01*
G02X1117191Y374522I2015J-1162D01*
G01X1117332D01*
G03X1118626Y375309I-71J1574D01*
G02X1120590Y376472I2015J-1163D01*
G01X1120700D01*
G03X1122006Y377259I-59J1575D01*
G02X1123936Y378421I2015J-1163D01*
G01X1124021D01*
G03X1125372Y379186I0J1575D01*
G01X1125385Y379209D01*
G02X1127330Y380372I2015J-1162D01*
G01X1127459D01*
G03X1128765Y381159I-59J1575D01*
G02X1130695Y382321I2015J-1163D01*
G01X1130824D01*
G03X1132145Y384684I-44J1575D01*
G02Y387012I2017J1164D01*
G03Y388584I-1362J786D01*
G02X1132120Y390867I2015J1164D01*
G01X1132145Y390909D01*
X1132164Y390943D01*
G03X1132145Y392484I-1384J754D01*
G02X1132120Y394767I2015J1164D01*
G01X1132145Y394809D01*
X1132164Y394843D01*
G03X1132145Y396384I-1384J754D01*
G02X1132120Y398667I2015J1164D01*
G01X1132145Y398709D01*
X1132164Y398743D01*
G03X1132145Y400284I-1384J754D01*
G02X1132120Y402567I2015J1164D01*
G01X1132145Y402609D01*
X1132164Y402643D01*
G03X1132145Y404184I-1384J754D01*
G02X1134090Y407672I2015J1163D01*
G01X1134219D01*
G03X1135236Y408116I-57J1517D01*
G01X1136665Y409545D01*
Y411732D01*
X1135756Y412641D01*
G01X1113881Y362447D02*
X1112582Y365446D01*
X1112516Y365559D01*
G02X1112497Y367100I1365J787D01*
G01X1112516Y367134D01*
X1112541Y367176D01*
G03X1112516Y369459I-2040J1119D01*
G02X1113810Y371821I1365J788D01*
G01X1113951D01*
G03X1115896Y372984I-70J2325D01*
G02X1117190Y373771I1365J-787D01*
G01X1117346D01*
G03X1119276Y374933I-85J2325D01*
G02X1120597Y375721I1365J-787D01*
G01X1120692D01*
G03X1122656Y376884I-51J2326D01*
G02X1123962Y377671I1365J-788D01*
G01X1124091D01*
G03X1126036Y378834I-70J2325D01*
G01X1126049Y378857D01*
G02X1127400Y379622I1351J-810D01*
G01X1127485D01*
G03X1129415Y380784I-85J2325D01*
G02X1130721Y381571I1365J-788D01*
G01X1130850D01*
G03X1132795Y385059I-70J2325D01*
G02Y386636I1368J788D01*
G03Y388959I-2015J1161D01*
G02X1132776Y390500I1365J787D01*
G01X1132795Y390534D01*
X1132820Y390576D01*
G03X1132795Y392859I-2040J1119D01*
G02X1132776Y394400I1365J787D01*
G01X1132795Y394434D01*
X1132820Y394476D01*
G03X1132795Y396759I-2040J1119D01*
G02X1132776Y398300I1365J787D01*
G01X1132795Y398334D01*
X1132820Y398376D01*
G03X1132795Y400659I-2040J1119D01*
G02X1132776Y402200I1365J787D01*
G01X1132795Y402234D01*
X1132820Y402276D01*
G03X1132795Y404559I-2040J1119D01*
G02X1134116Y406922I1365J788D01*
G01X1134245D01*
G03X1135597Y407417I-85J2325D01*
G01X1137422Y409242D01*
Y413499D01*
X1138256Y414333D01*
G01X1124021Y356596D02*
X1122072Y359218D01*
X1122006Y359334D01*
X1121981Y359376D01*
G02X1123936Y362821I2040J1120D01*
G01X1124021D01*
G03X1125372Y363586I0J1575D01*
G01X1125385Y363609D01*
G02X1127330Y364772I2015J-1162D01*
G01X1127459D01*
G03X1128765Y365559I-59J1575D01*
G02X1130695Y366721I2015J-1163D01*
G01X1130824D01*
G03X1132145Y367509I-44J1575D01*
G02X1134090Y368672I2015J-1162D01*
G01X1134219D01*
G03X1135525Y369459I-59J1575D01*
G02X1137489Y370622I2015J-1163D01*
G01X1137584D01*
G03X1138905Y371410I-44J1575D01*
G02X1140835Y372572I2015J-1163D01*
G01X1140991D01*
G03X1142285Y373359I-71J1574D01*
G02X1144230Y374522I2015J-1162D01*
G01X1144371D01*
G03X1145665Y376884I-71J1574D01*
G02X1145640Y379167I2015J1164D01*
G01X1145665Y379209D01*
G03Y380786I-1366J788D01*
G02Y383112I2015J1163D01*
G03Y384686I-1365J787D01*
G02Y387012I2015J1163D01*
G03Y388586I-1365J787D01*
G02X1145684Y390943I2016J1162D01*
G03X1145665Y392484I-1384J754D01*
G02Y394810I2015J1163D01*
G03Y396384I-1365J787D01*
G01X1145640Y396426D01*
G02X1147595Y399871I2040J1120D01*
G01X1147724D01*
G03X1149045Y400659I-44J1575D01*
G02X1150990Y401822I2015J-1162D01*
G01X1151485D01*
X1151971Y402308D01*
Y404889D01*
X1152559Y405477D01*
Y406743D01*
G01X1124021Y360496D02*
X1125972Y363121D01*
X1126049Y363257D01*
G02X1127400Y364022I1351J-810D01*
G01X1127485D01*
G03X1129415Y365184I-85J2325D01*
G02X1130721Y365971I1365J-788D01*
G01X1130850D01*
G03X1132795Y367134I-70J2325D01*
G02X1134116Y367922I1365J-787D01*
G01X1134245D01*
G03X1136175Y369084I-85J2325D01*
G02X1137481Y369871I1365J-788D01*
G01X1137591D01*
G03X1139555Y371034I-51J2326D01*
G02X1140849Y371821I1365J-787D01*
G01X1140990D01*
G03X1142935Y372984I-70J2325D01*
G02X1144229Y373771I1365J-787D01*
G01X1144385D01*
G03X1146315Y377259I-85J2325D01*
G02X1146296Y378800I1365J787D01*
G01X1146315Y378834D01*
X1146340Y378876D01*
G03X1146315Y381162I-2046J1121D01*
G02Y382736I1365J787D01*
G03Y385062I-2015J1163D01*
G02Y386636I1365J787D01*
G03Y388962I-2015J1163D01*
G02Y390534I1362J786D01*
G01X1146340Y390576D01*
G03X1146315Y392859I-2040J1119D01*
G02X1146296Y394400I1365J787D01*
G01X1146315Y394434D01*
G03X1146340Y396717I-2015J1164D01*
G01X1146315Y396759D01*
G02X1147636Y399121I1365J787D01*
G01X1147750D01*
G03X1149695Y400284I-70J2325D01*
G02X1151016Y401072I1365J-787D01*
G01X1151796D01*
X1152721Y401997D01*
Y404578D01*
X1153046Y404903D01*
X1154399D01*
G01X1110501Y356596D02*
X1108552Y359218D01*
X1108486Y359334D01*
X1108461Y359376D01*
G02X1108486Y361659I2040J1119D01*
G03X1108505Y363200I-1365J787D01*
G01X1108486Y363234D01*
X1108461Y363276D01*
G02X1108486Y365559I2040J1119D01*
G03X1108505Y367100I-1365J787D01*
G01X1108486Y367134D01*
X1108461Y367176D01*
G02X1108486Y369459I2040J1119D01*
G03X1108505Y371000I-1365J787D01*
G01X1108486Y371034D01*
G02X1110431Y374522I2015J1163D01*
G01X1110572D01*
G03X1111866Y375309I-71J1574D01*
G02X1113830Y376472I2015J-1163D01*
G01X1113940D01*
G03X1115246Y377259I-59J1575D01*
G02X1117176Y378421I2015J-1163D01*
G01X1117305D01*
G03X1118626Y379209I-44J1575D01*
G02X1120571Y380372I2015J-1162D01*
G01X1120700D01*
G03X1122006Y381159I-59J1575D01*
G02X1123936Y382321I2015J-1163D01*
G01X1124021D01*
G03X1125372Y383086I0J1575D01*
G01X1125385Y383109D01*
G02X1127330Y384272I2015J-1162D01*
G01X1127459D01*
G03X1128765Y385062I-64J1580D01*
G03Y386636I-1365J787D01*
G02Y388962I2015J1163D01*
G03X1128869Y389175I-1221J728D01*
G03X1128784Y390500I-1469J571D01*
G01X1128765Y390534D01*
X1128740Y390576D01*
G02X1128765Y392859I2040J1119D01*
G03X1128784Y394400I-1365J787D01*
G01X1128765Y394434D01*
X1128740Y394476D01*
G02X1128765Y396759I2040J1119D01*
G03X1128784Y398300I-1365J787D01*
G01X1128765Y398334D01*
X1128740Y398376D01*
G02X1128765Y400659I2040J1119D01*
G03X1128784Y402200I-1365J787D01*
G01X1128765Y402234D01*
X1128740Y402276D01*
G02X1128765Y404559I2040J1119D01*
G03X1128784Y406100I-1365J787D01*
G01X1128765Y406134D01*
X1128740Y406176D01*
G02X1130695Y409621I2040J1120D01*
G01X1130824D01*
G03X1132145Y411984I-44J1575D01*
G01X1131700Y412429D01*
Y413643D01*
X1130756Y414587D01*
G01X1110501Y360496D02*
X1109204Y363492D01*
X1109117Y363643D01*
G02X1109136Y365184I1384J754D01*
G03X1109161Y367467I-2015J1164D01*
G01X1109136Y367509D01*
X1109117Y367543D01*
G02X1109136Y369084I1384J754D01*
G03Y371410I-2015J1163D01*
G02X1110430Y373771I1365J787D01*
G01X1110586D01*
G03X1112516Y374933I-85J2325D01*
G02X1113837Y375721I1365J-787D01*
G01X1113932D01*
G03X1115896Y376884I-51J2326D01*
G02X1117202Y377671I1365J-788D01*
G01X1117331D01*
G03X1119276Y378834I-70J2325D01*
G02X1120597Y379622I1365J-787D01*
G01X1120726D01*
G03X1122656Y380784I-85J2325D01*
G02X1123962Y381571I1365J-788D01*
G01X1124091D01*
G03X1126036Y382734I-70J2325D01*
G01X1126049Y382757D01*
G02X1127400Y383522I1351J-810D01*
G01X1127485D01*
G03X1129415Y384686I-89J2329D01*
G03Y387012I-2015J1163D01*
G02Y388586I1365J787D01*
G03X1129489Y388723I-2430J1401D01*
G03X1129440Y390867I-2089J1025D01*
G01X1129415Y390909D01*
X1129396Y390943D01*
G02X1129415Y392484I1384J754D01*
G03X1129440Y394767I-2015J1164D01*
G01X1129415Y394809D01*
X1129396Y394843D01*
G02X1129415Y396384I1384J754D01*
G03X1129440Y398667I-2015J1164D01*
G01X1129415Y398709D01*
X1129396Y398743D01*
G02X1129415Y400284I1384J754D01*
G03X1129440Y402567I-2015J1164D01*
G01X1129415Y402609D01*
X1129396Y402643D01*
G02X1129415Y404184I1384J754D01*
G03X1129440Y406467I-2015J1164D01*
G01X1129415Y406509D01*
X1129396Y406543D01*
G02X1130721Y408871I1384J753D01*
G01X1130850D01*
G03X1132795Y412359I-70J2325D01*
G01X1132488Y412891D01*
Y413819D01*
X1133600Y414931D01*
G01X1120641Y354647D02*
X1119342Y357646D01*
X1119276Y357759D01*
G02X1119257Y359300I1365J787D01*
G01X1119276Y359334D01*
X1119301Y359376D01*
G03X1119276Y361659I-2040J1119D01*
G02X1119784Y363769I1365J787D01*
G03X1120576Y364571I-1424J2198D01*
G02X1121128Y364848I1186J-1675D01*
G03X1122006Y365559I-487J1499D01*
G02X1123936Y366721I2015J-1163D01*
G01X1124021D01*
G03X1125372Y367486I0J1575D01*
G01X1125385Y367509D01*
G02X1127330Y368672I2015J-1162D01*
G01X1127459D01*
G03X1128765Y369459I-59J1575D01*
G02X1130729Y370622I2015J-1163D01*
G01X1130824D01*
G03X1132145Y371410I-44J1575D01*
G02X1134075Y372572I2015J-1163D01*
G01X1134231D01*
G03X1135525Y373359I-71J1574D01*
G02X1137470Y374522I2015J-1162D01*
G01X1137611D01*
G03X1138905Y375309I-71J1574D01*
G02X1140850Y376473I2017J-1163D01*
G03X1140991I70J1563D01*
G03X1142285Y378835I-71J1574D01*
G02X1142260Y381118I2015J1164D01*
G01X1142285Y381160D01*
X1142304Y381194D01*
G03X1142285Y382736I-1384J754D01*
G02Y385062I2015J1163D01*
G03X1142260Y386676I-1362J786D01*
G02X1142285Y388959I2040J1119D01*
G03X1142304Y390500I-1365J787D01*
G01X1142285Y390534D01*
X1142260Y390576D01*
G02X1142285Y392859I2040J1119D01*
G03X1142304Y394400I-1365J787D01*
G01X1142285Y394434D01*
G02X1142260Y396717I2015J1164D01*
G01X1142285Y396759D01*
G03Y398333I-1365J787D01*
G02X1144215Y401821I2015J1163D01*
G01X1144344D01*
G03X1145665Y402609I-44J1575D01*
G02X1147595Y403771I2015J-1163D01*
G01X1148339Y404515D01*
Y408515D01*
X1148959Y409135D01*
Y410343D01*
G01X1120641Y362447D02*
X1122590Y365068D01*
X1122656Y365184D01*
G02X1123962Y365971I1365J-788D01*
G01X1124091D01*
G03X1126036Y367134I-70J2325D01*
G01X1126049Y367157D01*
G02X1127400Y367922I1351J-810D01*
G01X1127485D01*
G03X1129415Y369084I-85J2325D01*
G02X1130721Y369871I1365J-788D01*
G01X1130831D01*
G03X1132795Y371034I-51J2326D01*
G02X1134089Y371821I1365J-787D01*
G01X1134230D01*
G03X1136175Y372984I-70J2325D01*
G02X1137469Y373771I1365J-787D01*
G01X1137625D01*
G03X1139555Y374933I-85J2325D01*
G02X1140876Y375721I1365J-787D01*
G03X1141005Y375722I47J2240D01*
G03X1142935Y379210I-85J2325D01*
G02X1142916Y380751I1365J787D01*
G01X1142935Y380785D01*
X1142960Y380827D01*
G03X1142935Y383112I-2045J1120D01*
G02Y384686I1365J787D01*
G03Y387009I-2015J1161D01*
G01X1142916Y387043D01*
G02X1142935Y388584I1384J754D01*
G03X1142960Y390867I-2015J1164D01*
G01X1142935Y390909D01*
X1142916Y390943D01*
G02X1142935Y392484I1384J754D01*
G03Y394810I-2015J1163D01*
G02Y396384I1365J787D01*
G01X1142960Y396426D01*
G03X1142935Y398709I-2040J1119D01*
G01X1142916Y398743D01*
G02X1144241Y401071I1384J753D01*
G01X1144385D01*
G03X1146315Y402233I-85J2325D01*
G02X1147273Y402968I1365J-787D01*
G01X1147272D01*
G02X1147622Y403021I409J-1522D01*
G01X1147917Y403032D01*
X1149089Y404204D01*
Y408204D01*
X1149453Y408568D01*
X1150734D01*
G01X1096981Y356596D02*
Y355265D01*
X1096753Y355037D01*
G02X1095616Y357384I228J1559D01*
G03X1095641Y359667I-2015J1164D01*
G01X1095616Y359709D01*
X1095597Y359743D01*
G02X1095616Y361284I1384J754D01*
G03X1095641Y363567I-2015J1164D01*
G01X1095616Y363609D01*
X1095597Y363643D01*
G02X1095616Y365184I1384J754D01*
G03X1095641Y367467I-2015J1164D01*
G01X1095616Y367509D01*
X1095597Y367543D01*
G02X1095616Y369084I1384J754D01*
G03Y371410I-2015J1163D01*
G02Y372984I1365J787D01*
G01X1095641Y373026D01*
G03X1095616Y375309I-2040J1119D01*
G01X1095597Y375343D01*
G02X1095616Y376884I1384J754D01*
G03X1095641Y379167I-2015J1164D01*
G01X1095616Y379209D01*
X1095597Y379243D01*
G02X1096922Y381571I1384J753D01*
G01X1097051D01*
G03X1098996Y382734I-70J2325D01*
G02X1100317Y383522I1365J-787D01*
G01X1100446D01*
G03X1102376Y384684I-85J2325D01*
G02X1103682Y385471I1365J-788D01*
G01X1103811D01*
G03X1105756Y386634I-70J2325D01*
G02X1107077Y387422I1365J-787D01*
G01X1107206D01*
G03X1109136Y388584I-85J2325D01*
G02X1110442Y389371I1365J-788D01*
G01X1110571D01*
G03X1112516Y392858I-70J2325D01*
G02Y394432I1365J787D01*
G03X1112541Y396715I-2015J1164D01*
G01X1112516Y396757D01*
X1112497Y396791D01*
G02X1112516Y398332I1384J754D01*
G03Y400658I-2015J1163D01*
G02Y402232I1365J787D01*
G01X1112541Y402274D01*
G03X1112516Y404559I-2040J1120D01*
G02X1112489Y406085I1365J787D01*
G01X1112551Y406193D01*
G03X1112516Y408459I-2050J1102D01*
G02X1112489Y409985I1365J787D01*
G01X1112551Y410093D01*
G03X1112516Y412359I-2050J1102D01*
G02X1112489Y413885I1365J787D01*
G01X1112551Y413993D01*
G03X1112517Y416258I-2050J1102D01*
G01X1112516D01*
X1112143Y416903D01*
Y421758D01*
X1112298Y421913D01*
Y422000D01*
G01X1117261Y356596D02*
Y355265D01*
X1117033Y355037D01*
G02X1115896Y357384I228J1559D01*
G03X1115921Y359667I-2015J1164D01*
G01X1115896Y359709D01*
X1115877Y359743D01*
G02X1115896Y361284I1384J754D01*
G03X1115921Y363567I-2015J1164D01*
G01X1115896Y363609D01*
X1115877Y363643D01*
G02X1115896Y365184I1384J754D01*
G03X1115921Y367467I-2015J1164D01*
G01X1115896Y367509D01*
X1115877Y367543D01*
G02X1117202Y369871I1384J753D01*
G01X1117312D01*
G03X1119276Y371034I-51J2326D01*
G02X1120570Y371821I1365J-787D01*
G01X1120711D01*
G03X1122656Y372984I-70J2325D01*
G02X1123950Y373771I1365J-787D01*
G01X1124106D01*
G03X1126036Y374933I-85J2325D01*
G01X1126049Y374956D01*
G02X1127400Y375721I1351J-810D01*
G01X1127451D01*
G03X1129415Y376884I-51J2326D01*
G02X1130721Y377671I1365J-788D01*
G01X1130850D01*
G03X1132795Y378834I-70J2325D01*
G02X1134116Y379622I1365J-787D01*
G01X1134245D01*
G03X1136200Y383067I-85J2325D01*
G01X1136175Y383109D01*
X1136156Y383143D01*
G02X1136175Y384684I1384J754D01*
G03X1136200Y386967I-2015J1164D01*
G01X1136175Y387009D01*
X1136156Y387043D01*
G02X1136175Y388584I1384J754D01*
G03X1136200Y390867I-2015J1164D01*
G01X1136175Y390909D01*
X1136156Y390943D01*
G02X1136175Y392484I1384J754D01*
G03Y394810I-2015J1163D01*
G02Y396384I1365J787D01*
G03X1136200Y398667I-2015J1164D01*
G01X1136175Y398709D01*
X1136156Y398743D01*
G02X1136175Y400284I1384J754D01*
G03X1136200Y402567I-2015J1164D01*
G01X1136175Y402609D01*
X1136156Y402643D01*
G02X1137481Y404971I1384J753D01*
G01X1137610D01*
G03X1139555Y406134I-70J2325D01*
G02X1140876Y406922I1365J-787D01*
G01X1141161D01*
X1141801Y407562D01*
Y411273D01*
X1141956Y411428D01*
Y411515D01*
G01X1096981Y364396D02*
G02X1098347Y367511I14819J-4642D01*
G01X1098346Y367510D01*
G03Y369084I-1365J787D01*
G02Y371410I2017J1163D01*
G03Y372984I-1365J787D01*
G01X1098321Y373026D01*
G02X1098346Y375309I2040J1119D01*
G01X1098365Y375343D01*
G03X1098346Y376884I-1384J754D01*
G02X1100291Y380372I2015J1163D01*
G01X1100420D01*
G03X1101726Y381159I-59J1575D01*
G02X1103656Y382321I2015J-1163D01*
G01X1103785D01*
G03X1105106Y383109I-44J1575D01*
G02X1107051Y384272I2015J-1162D01*
G01X1107180D01*
G03X1108486Y385059I-59J1575D01*
G02X1110416Y386221I2015J-1163D01*
G01X1110545D01*
G03X1111866Y387009I-44J1575D01*
G02X1113811Y388172I2015J-1162D01*
G01X1113940D01*
G03X1115265Y390500I-59J1575D01*
G01X1115246Y390534D01*
G02Y392858I2015J1162D01*
G01X1115265Y392892D01*
G03X1115246Y394433I-1384J754D01*
G02X1115221Y396715I2018J1163D01*
G03X1115367Y397020I-1349J833D01*
G03X1115246Y398333I-1486J525D01*
G02X1115221Y400615I2018J1163D01*
G03X1115265Y400692I-1874J1122D01*
G03X1115246Y402233I-1384J754D01*
G02Y404559I2015J1163D01*
G03X1115265Y406100I-1365J787D01*
G01X1115246Y406134D01*
X1115221Y406176D01*
G02X1115246Y408459I2040J1119D01*
G03X1115265Y410000I-1365J787D01*
G01X1115246Y410034D01*
X1115221Y410076D01*
G02X1115246Y412359I2040J1119D01*
G03X1115265Y413900I-1365J787D01*
G01X1115246Y413934D01*
X1115221Y413976D01*
G02X1115246Y416259I2040J1119D01*
G01X1115456Y416623D01*
Y417837D01*
X1115156Y418137D01*
Y421758D01*
X1115001Y421913D01*
Y422000D01*
G01X1117261Y364396D02*
G03X1118330Y366618I-2692J2663D01*
G02X1120571Y368672I2310J-271D01*
G01X1120700D01*
G03X1122006Y369459I-59J1575D01*
G02X1123970Y370622I2015J-1163D01*
G01X1124021D01*
G03X1125372Y371387I0J1575D01*
G01X1125385Y371410D01*
G02X1127315Y372572I2015J-1163D01*
G01X1127471D01*
G03X1128765Y373359I-71J1574D01*
G02X1130710Y374522I2015J-1162D01*
G01X1130851D01*
G03X1132145Y375309I-71J1574D01*
G02X1134109Y376472I2015J-1163D01*
G01X1134219D01*
G03X1135525Y377259I-59J1575D01*
G02X1137455Y378421I2015J-1163D01*
G01X1137584D01*
G03X1138905Y380784I-44J1575D01*
G02X1138880Y383067I2015J1164D01*
G01X1138905Y383109D01*
G03Y384686I-1366J788D01*
G02Y387012I2015J1163D01*
G03Y388584I-1362J786D01*
G02X1138880Y390867I2015J1164D01*
G01X1138905Y390909D01*
X1138924Y390943D01*
G03X1138905Y392484I-1384J754D01*
G02Y394810I2015J1163D01*
G03Y396384I-1365J787D01*
G01X1138880Y396426D01*
G02X1138905Y398709I2040J1119D01*
G01X1138924Y398743D01*
G03X1138905Y400284I-1384J754D01*
G02X1140850Y403772I2015J1163D01*
G01X1140979D01*
G03X1142285Y404559I-59J1575D01*
G02X1144213Y405721I2015J-1163D01*
G01X1144341D01*
X1144741Y406121D01*
Y410141D01*
X1144586Y410296D01*
Y410383D01*
G01X1117261Y352696D02*
Y354027D01*
X1117004Y354284D01*
G02X1115246Y357759I257J2312D01*
G03X1115265Y359300I-1365J787D01*
G01X1115246Y359334D01*
X1115221Y359376D01*
G02X1115246Y361659I2040J1119D01*
G03X1115265Y363200I-1365J787D01*
G01X1115246Y363234D01*
X1115221Y363276D01*
G02X1115246Y365559I2040J1119D01*
G03X1115265Y367100I-1365J787D01*
G01X1115246Y367134D01*
X1115221Y367176D01*
G02X1117210Y370622I2040J1120D01*
G01X1117305D01*
G03X1118626Y371410I-44J1575D01*
G02X1120556Y372572I2015J-1163D01*
G01X1120712D01*
G03X1122006Y373359I-71J1574D01*
G02X1123951Y374522I2015J-1162D01*
G01X1124069D01*
G03X1125385Y375309I-48J1574D01*
G02X1127349Y376472I2015J-1163D01*
G01X1127459D01*
G03X1128765Y377259I-59J1575D01*
G02X1130695Y378421I2015J-1163D01*
G01X1130824D01*
G03X1132145Y379209I-44J1575D01*
G02X1134090Y380372I2015J-1162D01*
G01X1134219D01*
G03X1135544Y382700I-59J1575D01*
G01X1135525Y382734D01*
X1135500Y382776D01*
G02X1135525Y385059I2040J1119D01*
G03X1135544Y386600I-1365J787D01*
G01X1135525Y386634D01*
X1135500Y386676D01*
G02X1135525Y388959I2040J1119D01*
G03X1135544Y390500I-1365J787D01*
G01X1135525Y390534D01*
X1135500Y390576D01*
G02X1135525Y392859I2040J1119D01*
G03X1135544Y394400I-1365J787D01*
G01X1135525Y394434D01*
G02Y396760I2015J1163D01*
G03Y398334I-1365J787D01*
G01X1135500Y398376D01*
G02X1135525Y400659I2040J1119D01*
G03X1135544Y402200I-1365J787D01*
G01X1135525Y402234D01*
X1135500Y402276D01*
G02X1137455Y405721I2040J1120D01*
G01X1137584D01*
G03X1138905Y406509I-44J1575D01*
G02X1140850Y407672I2015J-1162D01*
G01X1141051Y407873D01*
Y411273D01*
X1140896Y411428D01*
Y411515D01*
G01X1096981Y360496D02*
G02X1098333Y363588I14866J-4659D01*
G01X1098372Y363656D01*
G03X1098530Y364691I-1390J742D01*
G02X1098997Y367135I3748J551D01*
G01X1098996Y367134D01*
G03X1099021Y369417I-2015J1164D01*
G01X1098996Y369459D01*
G02Y371034I1363J787D01*
G03X1099021Y373317I-2015J1164D01*
G01X1098996Y373359D01*
G02Y374933I1365J787D01*
G03Y377259I-2015J1163D01*
G02X1100317Y379622I1365J788D01*
G01X1100446D01*
G03X1102376Y380784I-85J2325D01*
G02X1103682Y381571I1365J-788D01*
G01X1103811D01*
G03X1105756Y382734I-70J2325D01*
G02X1107077Y383522I1365J-787D01*
G01X1107206D01*
G03X1109136Y384684I-85J2325D01*
G02X1110442Y385471I1365J-788D01*
G01X1110571D01*
G03X1112516Y386634I-70J2325D01*
G02X1113837Y387422I1365J-787D01*
G01X1113966D01*
G03X1115921Y390867I-85J2325D01*
G01X1115896Y390909D01*
G02Y392483I1365J787D01*
G01X1115921Y392525D01*
G03X1115896Y394808I-2040J1119D01*
G02Y396382I1365J787D01*
G03X1116033Y396659I-1997J1160D01*
G03X1115896Y398708I-2141J886D01*
G02Y400282I1365J787D01*
G03X1115921Y400325I-850J523D01*
G03X1115896Y402608I-2040J1119D01*
G02Y404184I1365J788D01*
G03X1115921Y406467I-2015J1164D01*
G01X1115896Y406509D01*
X1115877Y406543D01*
G02X1115896Y408084I1384J754D01*
G03X1115921Y410367I-2015J1164D01*
G01X1115896Y410409D01*
X1115877Y410443D01*
G02X1115896Y411984I1384J754D01*
G03X1115921Y414267I-2015J1164D01*
G01X1115896Y414309D01*
X1115877Y414343D01*
G02X1115896Y415884I1384J754D01*
G01X1116206Y416422D01*
Y418148D01*
X1115906Y418448D01*
Y421758D01*
X1116061Y421913D01*
Y422000D01*
G01X1117261Y360496D02*
G03X1118317Y362559I-1754J2200D01*
G02X1118626Y363609I2324J-113D01*
G02X1118986Y364082I2016J-1161D01*
G03X1119276Y365559I-954J954D01*
G02X1119076Y366530I1366J787D01*
G02X1120597Y367922I1566J-184D01*
G01X1120726D01*
G03X1122656Y369084I-85J2325D01*
G02X1123962Y369871I1365J-788D01*
G01X1124072D01*
G03X1126036Y371034I-51J2326D01*
G02X1127352Y371821I1364J-787D01*
G01X1127470D01*
G03X1129415Y372984I-70J2325D01*
G02X1130709Y373771I1365J-787D01*
G01X1130865D01*
G03X1132795Y374933I-85J2325D01*
G02X1134116Y375721I1365J-787D01*
G01X1134211D01*
G03X1136175Y376884I-51J2326D01*
G02X1137481Y377671I1365J-788D01*
G01X1137610D01*
G03X1139555Y381159I-70J2325D01*
G02X1139536Y382700I1365J787D01*
G01X1139555Y382734D01*
G03Y385062I-2020J1164D01*
G02Y386636I1366J787D01*
G03Y388959I-2015J1161D01*
G02X1139536Y390500I1365J787D01*
G01X1139555Y390534D01*
X1139580Y390576D01*
G03X1139555Y392859I-2040J1119D01*
G02X1139536Y394400I1365J787D01*
G01X1139555Y394434D01*
G03X1139580Y396717I-2015J1164D01*
G01X1139555Y396759D01*
G02Y398333I1365J787D01*
G03Y400659I-2015J1163D01*
G02X1140876Y403022I1365J788D01*
G01X1141005D01*
G03X1142935Y404184I-85J2325D01*
G02X1144241Y404971I1365J-788D01*
G01X1144652D01*
G01X1118314Y417047D02*
Y418199D01*
X1119556Y419441D01*
Y420156D01*
X1118687Y421025D01*
G01X1144652Y404971D02*
X1145491Y405810D01*
Y410141D01*
X1145646Y410296D01*
Y410383D01*
G01X1161200Y245447D02*
X1162354Y244781D01*
X1162448Y244429D01*
G03X1162540Y242376I2131J-933D01*
G01X1162565Y242334D01*
X1162584Y242300D01*
G02X1162565Y240759I-1384J-754D01*
G03X1162540Y238476I2015J-1164D01*
G01X1162565Y238434D01*
X1162584Y238400D01*
G02X1162565Y236859I-1384J-754D01*
G03Y234533I2015J-1163D01*
G03X1164495Y233371I2015J1163D01*
G01X1164651D01*
G02X1165945Y232584I-71J-1574D01*
G03X1167890Y231421I2015J1162D01*
G01X1168008D01*
G02X1169324Y230634I-48J-1574D01*
G03X1171288Y229471I2015J1163D01*
G01X1171398D01*
G02X1172704Y228684I-59J-1575D01*
G03X1174634Y227522I2015J1163D01*
G01X1174763D01*
G02X1176084Y226734I-44J-1575D01*
G03X1178029Y225571I2015J1162D01*
G01X1178158D01*
G02X1179464Y224784I-59J-1575D01*
G03X1181394Y223622I2015J1163D01*
G01X1181523D01*
G02X1182844Y222834I-44J-1575D01*
G03X1184789Y221671I2015J1162D01*
G01X1184918D01*
G02X1186224Y220884I-59J-1575D01*
G03X1188154Y219722I2015J1163D01*
G01X1188283D01*
G02X1189604Y218934I-44J-1575D01*
G03X1191549Y217771I2015J1162D01*
G01X1191678D01*
G02X1192984Y216984I-59J-1575D01*
G03X1194914Y215822I2015J1163D01*
G01X1195043D01*
G02X1196364Y215034I-44J-1575D01*
G03X1198309Y213871I2015J1162D01*
G01X1200215D01*
X1201013Y213073D01*
G01X1164580Y243496D02*
X1163572Y244078D01*
X1163116D01*
G03X1163196Y242743I1465J-582D01*
G01X1163215Y242709D01*
X1163240Y242667D01*
G02X1163215Y240384I-2040J-1119D01*
G03X1163196Y238843I1365J-787D01*
G01X1163215Y238809D01*
X1163240Y238767D01*
G02X1163215Y236484I-2040J-1119D01*
G03X1164509Y234122I1365J-788D01*
G01X1164650D01*
G02X1166595Y232959I-70J-2325D01*
G03X1167889Y232172I1365J787D01*
G01X1168045D01*
G02X1169975Y231010I-85J-2325D01*
G01X1169988Y230987D01*
G03X1171339Y230222I1351J810D01*
G01X1171390D01*
G02X1173354Y229059I-51J-2326D01*
G03X1174660Y228272I1365J788D01*
G01X1174789D01*
G02X1176734Y227109I-70J-2325D01*
G03X1178055Y226321I1365J787D01*
G01X1178184D01*
G02X1180114Y225159I-85J-2325D01*
G03X1181420Y224372I1365J788D01*
G01X1181549D01*
G02X1183494Y223209I-70J-2325D01*
G03X1184815Y222421I1365J787D01*
G01X1184944D01*
G02X1186874Y221259I-85J-2325D01*
G03X1188180Y220472I1365J788D01*
G01X1188309D01*
G02X1190254Y219309I-70J-2325D01*
G03X1191575Y218521I1365J787D01*
G01X1191704D01*
G02X1193634Y217359I-85J-2325D01*
G03X1194940Y216572I1365J788D01*
G01X1195069D01*
G02X1197014Y215409I-70J-2325D01*
G03X1198335Y214621I1365J787D01*
G01X1200545D01*
X1202179Y212987D01*
G01X1199815Y208816D02*
X1197812Y210814D01*
X1197678Y210812D01*
X1197495Y210992D01*
G02X1197014Y211509I884J1305D01*
G03X1195050Y212672I-2015J-1163D01*
G01X1194940D01*
G02X1193634Y213459I59J1575D01*
G03X1191704Y214621I-2015J-1163D01*
G01X1191575D01*
G02X1190254Y215409I44J1575D01*
G03X1188309Y216572I-2015J-1162D01*
G01X1188180D01*
G02X1186874Y217359I59J1575D01*
G03X1184944Y218521I-2015J-1163D01*
G01X1184815D01*
G02X1183494Y219309I44J1575D01*
G03X1181549Y220472I-2015J-1162D01*
G01X1181420D01*
G02X1180114Y221259I59J1575D01*
G03X1178184Y222421I-2015J-1163D01*
G01X1178055D01*
G02X1176734Y223209I44J1575D01*
G03X1174789Y224372I-2015J-1162D01*
G01X1174660D01*
G02X1173354Y225159I59J1575D01*
G03X1171424Y226321I-2015J-1163D01*
G01X1171339D01*
G02X1169988Y227086I0J1575D01*
G01X1169975Y227109D01*
G03X1168030Y228272I-2015J-1162D01*
G01X1167901D01*
G02X1166595Y229059I59J1575D01*
G03X1164631Y230222I-2015J-1163D01*
G01X1164536D01*
G02X1163215Y231010I44J1575D01*
G03X1161285Y232172I-2015J-1163D01*
G01X1161129D01*
G02X1159835Y234533I71J1574D01*
G03Y236859I-2015J1163D01*
G02X1159816Y238400I1365J787D01*
G01X1159835Y238434D01*
X1159860Y238476D01*
G03X1159835Y240759I-2040J1119D01*
G02X1159816Y242300I1365J787D01*
G01X1159835Y242334D01*
X1159860Y242376D01*
G03X1159511Y245094I-2040J1119D01*
G02X1157820Y247396I8398J7941D01*
G01X1205139Y221671D02*
X1205069D01*
G02X1203124Y222834I70J2325D01*
G03X1201803Y223622I-1365J-787D01*
G01X1201674D01*
G02X1199744Y224784I85J2325D01*
G03X1197014I-1365J-788D01*
G02X1195084Y223622I-2015J1163D01*
G01X1194914D01*
G02X1192984Y224784I85J2325D01*
G03X1190254I-1365J-788D01*
G02X1186224I-2015J1163D01*
G03X1184918Y225571I-1365J-788D01*
G01X1184789D01*
G02X1182844Y226734I70J2325D01*
G03X1181523Y227522I-1365J-787D01*
G01X1181394D01*
G02X1179464Y228684I85J2325D01*
G03X1178158Y229471I-1365J-788D01*
G01X1178048D01*
G02X1176084Y230634I51J2326D01*
G03X1174790Y231421I-1365J-787D01*
G01X1174649D01*
G02X1172704Y232584I70J2325D01*
G03X1171410Y233371I-1365J-787D01*
G01X1171254D01*
G02X1169324Y234533I85J2325D01*
G01X1169311Y234556D01*
G03X1167960Y235321I-1351J-810D01*
G01X1167909D01*
G02X1165945Y236484I51J2326D01*
G02X1165920Y238767I2015J1164D01*
G01X1165945Y238809D01*
X1165964Y238843D01*
G03X1165945Y240384I-1384J754D01*
G02X1165920Y242667I2015J1164D01*
G01X1165945Y242709D01*
X1165964Y242743D01*
G03X1165945Y244284I-1384J754D01*
G02X1165920Y246567I2015J1164D01*
G01X1165945Y246609D01*
X1165964Y246643D01*
G03X1165945Y248184I-1384J754D01*
G03X1164639Y248971I-1365J-788D01*
G01X1164510D01*
G02X1162540Y250176I69J2325D01*
G02X1162262Y251503I2040J1120D01*
G01Y252185D01*
X1161200Y253247D01*
G01X1305842Y280168D02*
X1217194D01*
G01X1214094Y271303D02*
X1216362Y273571D01*
G01X1167960Y249347D02*
X1169113Y248682D01*
X1169207Y248330D01*
G03X1169289Y246294I2131J-934D01*
G01X1169324Y246234D01*
G03X1171269Y245071I2015J1162D01*
G01X1171398D01*
G02X1172704Y244284I-59J-1575D01*
G03X1174634Y243122I2015J1163D01*
G01X1174763D01*
G02X1176084Y242334I-44J-1575D01*
G03X1178029Y241171I2015J1162D01*
G01X1178169D01*
G03X1180114Y242334I-70J2325D01*
G02X1181435Y243122I1365J-787D01*
G01X1181523D01*
G02X1182844Y242334I-44J-1575D01*
G03X1184789Y241171I2015J1162D01*
G01X1184929D01*
G03X1186874Y242334I-70J2325D01*
G02X1189604I1365J-787D01*
G03X1191549Y241171I2015J1162D01*
G01X1191689D01*
G03X1193634Y242334I-70J2325D01*
G02X1196364I1365J-787D01*
G03X1198309Y241171I2015J1162D01*
G01X1198449D01*
G03X1200394Y242334I-70J2325D01*
G02X1203124I1365J-787D01*
G03X1205069Y241171I2015J1162D01*
G01X1205209D01*
G03X1207154Y242334I-70J2325D01*
G02X1207404Y242662I1368J-783D01*
G01X1207957Y243215D01*
X1209101D01*
X1211144Y241172D01*
X1213908D01*
X1215319Y239761D01*
X1225061D01*
X1234640Y249340D01*
G01X1267204Y256929D02*
X1265273Y258860D01*
X1232550D01*
X1227550Y253860D01*
X1227520D01*
X1224080Y250420D01*
X1214459D01*
X1213760Y249721D01*
X1211544D01*
G02X1210691Y250498I655J1575D01*
G03X1209317Y251672I-2172J-1151D01*
G01X1208449D01*
G03X1206504Y250509I70J-2325D01*
G02X1206254Y250181I-1368J783D01*
G01X1205795Y249722D01*
X1205068D01*
G02X1203774Y250509I71J1574D01*
G03X1201829Y251672I-2015J-1162D01*
G01X1201700D01*
G02X1200394Y252459I59J1575D01*
G03X1198464Y253621I-2015J-1163D01*
G01X1198294D01*
G03X1196364Y252459I85J-2325D01*
G02X1195058Y251672I-1365J788D01*
G01X1194940D01*
G02X1193634Y252459I59J1575D01*
G03X1191704Y253621I-2015J-1163D01*
G01X1191534D01*
G03X1189604Y252459I85J-2325D01*
G02X1188298Y251672I-1365J788D01*
G01X1188180D01*
G02X1186874Y252459I59J1575D01*
G03X1184944Y253621I-2015J-1163D01*
G01X1184815D01*
G02X1183494Y254409I44J1575D01*
G03X1181549Y255572I-2015J-1162D01*
G01X1181420D01*
G02X1180242Y256171I60J1575D01*
G01X1180325Y256481D01*
X1181479Y257147D01*
G01X1178099Y255196D02*
X1179253Y255862D01*
X1179605Y255767D01*
G03X1181394Y254822I1873J1380D01*
G01X1181523D01*
G02X1182844Y254034I-44J-1575D01*
G03X1184789Y252871I2015J1162D01*
G01X1184918D01*
G02X1186224Y252084I-59J-1575D01*
G03X1188154Y250922I2015J1163D01*
G01X1188324D01*
G03X1190254Y252084I-85J2325D01*
G02X1191560Y252871I1365J-788D01*
G01X1191678D01*
G02X1192984Y252084I-59J-1575D01*
G03X1194914Y250922I2015J1163D01*
G01X1195084D01*
G03X1197014Y252084I-85J2325D01*
G02X1198320Y252871I1365J-788D01*
G01X1198438D01*
G02X1199744Y252084I-59J-1575D01*
G03X1201674Y250922I2015J1163D01*
G01X1201803D01*
G02X1203124Y250134I-44J-1575D01*
G03X1205041Y248972I2015J1162D01*
G01X1206113D01*
X1206757Y249616D01*
G03X1207154Y250134I-1761J1761D01*
G02X1208475Y250922I1365J-787D01*
G01X1209174D01*
G02X1210027Y250145I-655J-1575D01*
G03X1211401Y248971I2172J1151D01*
G01X1224258D01*
X1227997Y252710D01*
X1228027D01*
X1233026Y257709D01*
X1264794D01*
G01X1167960Y241547D02*
Y242878D01*
X1168187Y243105D01*
G02X1169311Y242357I-226J-1559D01*
G01X1169324Y242334D01*
G03X1171269Y241171I2015J1162D01*
G01X1171398D01*
G02X1172704Y240384I-59J-1575D01*
G03X1174634Y239222I2015J1163D01*
G01X1174763D01*
G02X1176084Y238434I-44J-1575D01*
G03X1178029Y237271I2015J1162D01*
G01X1178169D01*
G03X1180114Y238434I-70J2325D01*
G02X1182844I1365J-787D01*
G03X1184789Y237271I2015J1162D01*
G01X1184929D01*
G03X1186874Y238434I-70J2325D01*
G02X1189604I1365J-787D01*
G03X1191549Y237271I2015J1162D01*
G01X1191689D01*
G03X1193634Y238434I-70J2325D01*
G02X1196364I1365J-787D01*
G03X1198309Y237271I2015J1162D01*
G01X1198449D01*
G03X1200394Y238434I-70J2325D01*
G02X1201715Y239222I1365J-787D01*
G01X1201803D01*
G02X1203124Y238434I-44J-1575D01*
G03X1205069Y237271I2015J1162D01*
G01X1205209D01*
G03X1207154Y238434I-70J2325D01*
G02X1208475Y239222I1365J-787D01*
G01X1209174D01*
G02X1210027Y238445I-655J-1575D01*
G01X1210424Y237698D01*
X1211182Y236940D01*
X1226250D01*
G01X1167960Y245447D02*
Y244116D01*
X1168217Y243859D01*
G02X1169975Y242709I-257J-2312D01*
G01X1169988Y242686D01*
G03X1171339Y241921I1351J810D01*
G01X1171424D01*
G02X1173354Y240759I-85J-2325D01*
G03X1174660Y239972I1365J788D01*
G01X1174789D01*
G02X1176734Y238809I-70J-2325D01*
G03X1178055Y238021I1365J787D01*
G01X1178143D01*
G03X1179464Y238809I-44J1575D01*
G02X1183494I2015J-1162D01*
G03X1184815Y238021I1365J787D01*
G01X1184903D01*
G03X1186224Y238809I-44J1575D01*
G02X1190254I2015J-1162D01*
G03X1191575Y238021I1365J787D01*
G01X1191663D01*
G03X1192984Y238809I-44J1575D01*
G02X1197014I2015J-1162D01*
G03X1198335Y238021I1365J787D01*
G01X1198423D01*
G03X1199744Y238809I-44J1575D01*
G02X1201689Y239972I2015J-1162D01*
G01X1201829D01*
G02X1203774Y238809I-70J-2325D01*
G03X1205095Y238021I1365J787D01*
G01X1205183D01*
G03X1206504Y238809I-44J1575D01*
G02X1208449Y239972I2015J-1162D01*
G01X1209317D01*
G02X1210691Y238798I-798J-2325D01*
G01X1211034Y238149D01*
X1211394Y237789D01*
X1216226D01*
X1216934Y238497D01*
X1225777D01*
X1235368Y248088D01*
G01X1227911Y233811D02*
X1215159D01*
X1214219Y234751D01*
X1211876D01*
X1211306Y235321D01*
X1208475D01*
G03X1207154Y234533I44J-1575D01*
G02X1205224Y233371I-2015J1163D01*
G01X1205054D01*
G02X1203124Y234533I85J2325D01*
G03X1200394I-1365J-787D01*
G02X1198464Y233371I-2015J1163D01*
G01X1198294D01*
G02X1196364Y234533I85J2325D01*
G03X1193634I-1365J-787D01*
G02X1191704Y233371I-2015J1163D01*
G01X1191534D01*
G02X1189604Y234533I85J2325D01*
G03X1188283Y235321I-1365J-787D01*
G01X1188195D01*
G03X1186874Y234533I44J-1575D01*
G02X1184944Y233371I-2015J1163D01*
G01X1184774D01*
G02X1182844Y234533I85J2325D01*
G03X1180114I-1365J-787D01*
G02X1178184Y233371I-2015J1163D01*
G01X1178014D01*
G02X1176084Y234533I85J2325D01*
G03X1174763Y235321I-1365J-787D01*
G01X1174668D01*
G02X1172704Y236484I51J2326D01*
G03X1171398Y237271I-1365J-788D01*
G01X1171269D01*
G02X1169465Y238217I69J2325D01*
G01X1169113Y238312D01*
X1167960Y237647D01*
G01X1236390Y244960D02*
X1226760Y235330D01*
X1215180D01*
X1214438Y236072D01*
X1208468D01*
G03X1206504Y234909I51J-2326D01*
G02X1205210Y234122I-1365J787D01*
G01X1205068D01*
G02X1203774Y234909I71J1574D01*
G03X1199744I-2015J-1163D01*
G02X1198450Y234122I-1365J787D01*
G01X1198308D01*
G02X1197014Y234909I71J1574D01*
G03X1192984I-2015J-1163D01*
G02X1191690Y234122I-1365J787D01*
G01X1191548D01*
G02X1190254Y234909I71J1574D01*
G03X1188290Y236072I-2015J-1163D01*
G01X1188188D01*
G03X1186224Y234909I51J-2326D01*
G02X1184930Y234122I-1365J787D01*
G01X1184788D01*
G02X1183494Y234909I71J1574D01*
G03X1179464I-2015J-1163D01*
G02X1178170Y234122I-1365J787D01*
G01X1178028D01*
G02X1176734Y234909I71J1574D01*
G03X1174770Y236072I-2015J-1163D01*
G01X1174660D01*
G02X1173354Y236859I59J1575D01*
G03X1171424Y238021I-2015J-1163D01*
G01X1171339D01*
G02X1170103Y238621I1J1575D01*
G01X1170186Y238931D01*
X1171339Y239596D01*
G01X1174719Y245447D02*
Y244116D01*
X1174976Y243859D01*
G02X1176734Y242709I-257J-2312D01*
G03X1178055Y241921I1365J787D01*
G01X1178143D01*
G03X1179464Y242709I-44J1575D01*
G02X1181409Y243872I2015J-1162D01*
G01X1181549D01*
G02X1183494Y242709I-70J-2325D01*
G03X1184815Y241921I1365J787D01*
G01X1184903D01*
G03X1186224Y242709I-44J1575D01*
G02X1190254I2015J-1162D01*
G03X1191575Y241921I1365J787D01*
G01X1191663D01*
G03X1192984Y242709I-44J1575D01*
G02X1197014I2015J-1162D01*
G03X1198335Y241921I1365J787D01*
G01X1198423D01*
G03X1199744Y242709I-44J1575D01*
G02X1203774I2015J-1162D01*
G03X1205095Y241921I1365J787D01*
G01X1205183D01*
G03X1206504Y242709I-44J1575D01*
G02X1206608Y242874I2018J-1157D01*
G02X1206873Y243192I1912J-1324D01*
G01X1207708Y244027D01*
X1209349D01*
X1209411Y243965D01*
X1209412D01*
X1211455Y241922D01*
X1214219D01*
X1214220Y241921D01*
X1214797D01*
X1215602Y241116D01*
X1224295D01*
X1233949Y250770D01*
G01X1221387Y254822D02*
X1208475D01*
G03X1207154Y254034I44J-1575D01*
G02X1203124I-2015J1162D01*
G03X1201803Y254822I-1365J-787D01*
G01X1201674D01*
G02X1199744Y255984I85J2325D01*
G03X1197014I-1365J-788D01*
G02X1192984I-2015J1163D01*
G03X1190254I-1365J-788D01*
G02X1186224I-2015J1163D01*
G03X1184918Y256771I-1365J-788D01*
G01X1184789D01*
G02X1182844Y257934I70J2325D01*
G03X1180114I-1365J-787D01*
G02X1178029Y256771I-2016J1164D01*
G02X1176225Y257717I69J2325D01*
G01X1175873Y257812D01*
X1174719Y257147D01*
G01X1209936Y255574D02*
X1208521D01*
G03X1206504Y254409I0J-2328D01*
G02X1203774I-1365J787D01*
G03X1201829Y255572I-2015J-1162D01*
G01X1201700D01*
G02X1200394Y256359I59J1575D01*
G03X1196364I-2015J-1163D01*
G02X1193634I-1365J788D01*
G03X1189604I-2015J-1163D01*
G02X1186874I-1365J788D01*
G03X1184944Y257521I-2015J-1163D01*
G01X1184815D01*
G02X1183494Y258309I44J1575D01*
G03X1179464I-2015J-1162D01*
G02X1176862Y258121I-1365J787D01*
G01X1176945Y258431D01*
X1178099Y259096D01*
G01X1214360Y327750D02*
X1214273D01*
X1214073Y327950D01*
X1212194D01*
X1211814Y327570D01*
X1210764D01*
X1210384Y327950D01*
X1209334D01*
X1208954Y327570D01*
X1207904D01*
X1207524Y327950D01*
X1206865D01*
X1205886Y326971D01*
X1198309D01*
G02X1196364Y328134I70J2325D01*
G03X1195043Y328922I-1365J-787D01*
G01X1194914D01*
G02X1192959Y332367I85J2325D01*
G01X1192984Y332409D01*
X1193003Y332443D01*
G03X1191678Y334771I-1384J753D01*
G01X1191549D01*
G02X1189604Y335934I70J2325D01*
G03X1188283Y336722I-1365J-787D01*
G01X1188154D01*
G02X1186224Y337884I85J2325D01*
G03X1184918Y338671I-1365J-788D01*
G01X1184800D01*
G03X1183622Y338072I60J-1575D01*
G01X1183705Y337762D01*
X1184000Y337592D01*
X1184859Y337096D01*
G01X1178099Y340996D02*
X1179253Y341662D01*
X1179605Y341567D01*
G03X1181394Y340622I1873J1380D01*
G01X1181564D01*
G03X1183494Y341784I-85J2325D01*
G02X1184800Y342571I1365J-788D01*
G01X1184918D01*
G02X1186224Y341784I-59J-1575D01*
G03X1188154Y340622I2015J1163D01*
G01X1188283D01*
G02X1189604Y339834I-44J-1575D01*
G03X1191549Y338671I2015J1162D01*
G01X1191678D01*
G02X1192984Y337884I-59J-1575D01*
G03X1194914Y336722I2015J1163D01*
G01X1195043D01*
G02X1196364Y335934I-44J-1575D01*
G01X1196383Y335900D01*
G02X1196364Y334359I-1384J-754D01*
G03X1198309Y330871I2015J-1163D01*
G01X1198448D01*
G02X1199744Y330084I-69J-1575D01*
G01X1200044Y329565D01*
X1200688Y328921D01*
X1204652D01*
X1206581Y330850D01*
X1213258D01*
X1213458Y330650D01*
X1213545D01*
G01X1174719Y346847D02*
X1175873Y346181D01*
X1175956Y345871D01*
G02X1174778Y345272I-1238J976D01*
G01X1174649D01*
G03X1172704Y344109I70J-2325D01*
G01X1172679Y344067D01*
G03X1172704Y341784I2040J-1119D01*
G02X1172723Y340243I-1365J-787D01*
G01X1172704Y340209D01*
X1172679Y340167D01*
G03X1172704Y337884I2040J-1119D01*
G02X1172723Y336343I-1365J-787D01*
G01X1172704Y336309D01*
X1172679Y336267D01*
G03X1174634Y332822I2040J-1120D01*
G01X1174763D01*
G02X1176084Y332034I-44J-1575D01*
G03X1178029Y330871I2015J1162D01*
G01X1178158D01*
G02X1179464Y330084I-59J-1575D01*
G03X1181394Y328922I2015J1163D01*
G01X1181523D01*
G02X1182844Y328134I-44J-1575D01*
G03X1184789Y326971I2015J1162D01*
G01X1184918D01*
G02X1186224Y326184I-59J-1575D01*
G03X1188188Y325021I2015J1163D01*
G01X1188283D01*
G02X1189604Y324233I-44J-1575D01*
G03X1191534Y323071I2015J1163D01*
G01X1191663D01*
G02X1192984Y322283I-44J-1575D01*
G03X1194914Y321121I2015J1163D01*
G01X1195070D01*
G02X1196364Y320334I-71J-1574D01*
G01X1197063Y319116D01*
X1206075D01*
X1208485Y321526D01*
X1221413D01*
X1221613Y321326D01*
G01X1213087Y324821D02*
X1213000D01*
X1212800Y325021D01*
X1201715D01*
G03X1200394Y324233I44J-1575D01*
G02X1198464Y323071I-2015J1163D01*
G01X1198294D01*
G02X1196364Y324233I85J2325D01*
G03X1195043Y325021I-1365J-787D01*
G01X1194948D01*
G02X1192984Y326184I51J2326D01*
G03X1191678Y326971I-1365J-788D01*
G01X1191549D01*
G02X1189604Y328134I70J2325D01*
G03X1188283Y328922I-1365J-787D01*
G01X1188154D01*
G02X1186224Y330084I85J2325D01*
G03X1184918Y330871I-1365J-788D01*
G01X1184789D01*
G02X1182844Y332034I70J2325D01*
G03X1181523Y332822I-1365J-787D01*
G01X1181394D01*
G02X1179464Y333984I85J2325D01*
G03X1178158Y334771I-1365J-788D01*
G01X1178029D01*
G02X1176084Y338259I70J2325D01*
G03X1176103Y339800I-1365J787D01*
G01X1176084Y339834D01*
X1176059Y339876D01*
G02X1178014Y343321I2040J1120D01*
G01X1178143D01*
G03X1179464Y345684I-44J1575D01*
G02X1179439Y347967I2015J1164D01*
G01X1179464Y348009D01*
X1179483Y348043D01*
G03X1178327Y350355I-1384J753D01*
G01X1178099Y350127D01*
Y348796D01*
G01X1214360Y328900D02*
X1214273D01*
X1214073Y328700D01*
X1206554D01*
X1205575Y327721D01*
X1198335D01*
G02X1197014Y328509I44J1575D01*
G03X1195069Y329672I-2015J-1162D01*
G01X1194940D01*
G02X1193615Y332000I59J1575D01*
G01X1193634Y332034D01*
X1193659Y332076D01*
G03X1191704Y335521I-2040J1120D01*
G01X1191575D01*
G02X1190254Y336309I44J1575D01*
G03X1188309Y337472I-2015J-1162D01*
G01X1188180D01*
G02X1186874Y338259I59J1575D01*
G03X1184944Y339421I-2015J-1163D01*
G01X1184774D01*
G03X1182985Y338476I84J-2325D01*
G01X1182468D01*
X1181479Y339047D01*
G01Y342947D02*
X1180325Y342281D01*
X1180242Y341971D01*
G03X1181420Y341372I1238J976D01*
G01X1181538D01*
G03X1182844Y342159I-59J1575D01*
G02X1184774Y343321I2015J-1163D01*
G01X1184944D01*
G02X1186874Y342159I-85J-2325D01*
G03X1188180Y341372I1365J788D01*
G01X1188309D01*
G02X1190254Y340209I-70J-2325D01*
G03X1191575Y339421I1365J787D01*
G01X1191704D01*
G02X1193634Y338259I-85J-2325D01*
G03X1194940Y337472I1365J788D01*
G01X1195069D01*
G02X1197014Y336309I-70J-2325D01*
G01X1197039Y336267D01*
G02X1197014Y333984I-2040J-1119D01*
G03X1198335Y331621I1365J-788D01*
G01X1198464D01*
G02X1200394Y330459I-85J-2325D01*
G01X1200646Y330024D01*
X1200999Y329671D01*
X1202394D01*
X1202627Y329904D01*
X1203677D01*
X1203910Y329671D01*
X1204341D01*
X1206270Y331600D01*
X1206894D01*
X1207072Y331778D01*
Y331779D01*
X1207250Y331957D01*
X1208300D01*
X1208478Y331779D01*
Y331778D01*
X1208656Y331600D01*
X1209706D01*
X1209884Y331778D01*
Y331779D01*
X1210062Y331957D01*
X1211112D01*
X1211290Y331779D01*
Y331778D01*
X1211468Y331600D01*
X1213258D01*
X1213458Y331800D01*
X1213545D01*
G01X1178099Y344896D02*
X1176945Y345562D01*
X1176593Y345467D01*
G02X1174804Y344522I-1873J1380D01*
G01X1174675D01*
G03X1173338Y343705I44J-1575D01*
G03X1173354Y342159I1381J-759D01*
G02X1173379Y339876I-2015J-1164D01*
G01X1173354Y339834D01*
X1173335Y339800D01*
G03X1173354Y338259I1384J-754D01*
G02X1173379Y335976I-2015J-1164D01*
G01X1173354Y335934D01*
X1173335Y335900D01*
G03X1174660Y333572I1384J-753D01*
G01X1174789D01*
G02X1176734Y332409I-70J-2325D01*
G03X1178055Y331621I1365J787D01*
G01X1178184D01*
G02X1180114Y330459I-85J-2325D01*
G03X1181420Y329672I1365J788D01*
G01X1181549D01*
G02X1183494Y328509I-70J-2325D01*
G03X1184815Y327721I1365J787D01*
G01X1184944D01*
G02X1186874Y326559I-85J-2325D01*
G03X1188180Y325772I1365J788D01*
G01X1188290D01*
G02X1190254Y324609I-51J-2326D01*
G03X1191575Y323821I1365J787D01*
G01X1191704D01*
G02X1193634Y322659I-85J-2325D01*
G03X1194928Y321872I1365J787D01*
G01X1194950Y321871D01*
X1195086D01*
G02X1197015Y320709I-86J-2324D01*
G01X1197498Y319866D01*
X1199757D01*
X1200107Y320216D01*
X1201157D01*
X1201507Y319866D01*
X1202557D01*
X1202907Y320216D01*
X1203957D01*
X1204307Y319866D01*
X1205764D01*
X1208174Y322276D01*
X1209224D01*
X1209574Y322626D01*
X1210624D01*
X1210974Y322276D01*
X1212024D01*
X1212374Y322626D01*
X1213424D01*
X1213774Y322276D01*
X1214824D01*
X1215174Y322626D01*
X1216224D01*
X1216574Y322276D01*
X1217624D01*
X1217974Y322626D01*
X1219024D01*
X1219374Y322276D01*
X1221413D01*
X1221613Y322476D01*
G01X1178099Y352696D02*
Y351365D01*
X1178355Y351109D01*
G02X1180139Y347676I-256J-2313D01*
G01X1180114Y347634D01*
X1180095Y347600D01*
G03X1180114Y346059I1384J-754D01*
G02X1178169Y342571I-2015J-1163D01*
G01X1178040D01*
G03X1176715Y340243I59J-1575D01*
G01X1176734Y340209D01*
X1176759Y340167D01*
G02X1176734Y337884I-2040J-1119D01*
G03X1178055Y335521I1365J-788D01*
G01X1178184D01*
G02X1180114Y334359I-85J-2325D01*
G03X1181420Y333572I1365J788D01*
G01X1181549D01*
G02X1183494Y332409I-70J-2325D01*
G03X1184815Y331621I1365J787D01*
G01X1184944D01*
G02X1186874Y330459I-85J-2325D01*
G03X1188180Y329672I1365J788D01*
G01X1188309D01*
G02X1190254Y328509I-70J-2325D01*
G03X1191575Y327721I1365J787D01*
G01X1191704D01*
G02X1193634Y326559I-85J-2325D01*
G03X1194940Y325772I1365J788D01*
G01X1195050D01*
G02X1197014Y324609I-51J-2326D01*
G03X1198335Y323821I1365J787D01*
G01X1198423D01*
G03X1199744Y324609I-44J1575D01*
G02X1201674Y325771I2015J-1163D01*
G01X1212800D01*
X1213000Y325971D01*
X1213087D01*
G01X1216000Y334600D02*
X1215913D01*
X1215713Y334800D01*
X1211046D01*
X1210688Y334442D01*
X1209638D01*
X1209280Y334800D01*
X1208230D01*
X1207872Y334442D01*
X1206822D01*
X1206464Y334800D01*
X1204692D01*
X1204021Y334412D01*
X1203774Y333984D01*
G02X1201843Y332822I-2015J1163D01*
G01X1201715D01*
G03X1200522Y332222I45J-1575D01*
G01X1200605Y331912D01*
X1201759Y331247D01*
G01X1215194Y337368D02*
X1215107D01*
X1214907Y337568D01*
X1212668D01*
X1211822Y336722D01*
X1202109D01*
X1201759Y336372D01*
Y335147D01*
G01X1226543Y342178D02*
X1226456D01*
X1226256Y342378D01*
X1213955D01*
X1212198Y340621D01*
X1208352D01*
G03X1207304Y340056I1J-1256D01*
G01X1207079Y339714D01*
G02X1205237Y338672I-1939J1278D01*
G01X1205041D01*
G02X1203007Y341929I97J2324D01*
G01X1202913Y342281D01*
X1201759Y342947D01*
G01X1216000Y335750D02*
X1215913D01*
X1215713Y335550D01*
X1204490D01*
X1203471Y334961D01*
X1203124Y334359D01*
G02X1201828Y333572I-1365J788D01*
G01X1201689D01*
G03X1199885Y332626I69J-2325D01*
G01X1199533Y332531D01*
X1198379Y333196D01*
G01X1215194Y338518D02*
X1215107D01*
X1214907Y338318D01*
X1212357D01*
X1211511Y337472D01*
X1202109D01*
X1201759Y337822D01*
Y339047D01*
G01X1226543Y343328D02*
X1226456D01*
X1226256Y343128D01*
X1224712D01*
X1224529Y343311D01*
Y343312D01*
X1224346Y343495D01*
X1223296D01*
X1223113Y343312D01*
Y343311D01*
X1222930Y343128D01*
X1221880D01*
X1221697Y343311D01*
Y343312D01*
X1221514Y343495D01*
X1220464D01*
X1220281Y343312D01*
Y343311D01*
X1220098Y343128D01*
X1219048D01*
X1218865Y343311D01*
Y343312D01*
X1218682Y343495D01*
X1217632D01*
X1217449Y343312D01*
Y343311D01*
X1217266Y343128D01*
X1216216D01*
X1216033Y343311D01*
Y343312D01*
X1215850Y343495D01*
X1214800D01*
X1214617Y343312D01*
Y343311D01*
X1214434Y343128D01*
X1213644D01*
X1211887Y341371D01*
X1211024D01*
X1210668Y341727D01*
X1209618D01*
X1209262Y341371D01*
X1208353D01*
G03X1206677Y340469I-1J-2006D01*
G01X1206452Y340127D01*
G02X1205219Y339422I-1313J865D01*
G01X1205068D01*
G02X1203675Y341578I72J1574D01*
G01X1203985Y341662D01*
X1205139Y340996D01*
G01X1161200Y311747D02*
X1160046Y311082D01*
X1159963Y310772D01*
G03X1161156Y310172I1238J975D01*
G01X1161244D01*
G03X1162565Y310960I-44J1575D01*
G02X1164495Y312122I2015J-1163D01*
G01X1164651D01*
G03X1165945Y312909I-71J1574D01*
G02X1167890Y314072I2015J-1162D01*
G01X1168030D01*
G02X1169975Y312909I-70J-2325D01*
G03X1171291Y312122I1364J787D01*
G01X1171410D01*
G03X1172704Y312909I-71J1574D01*
G02X1174649Y314072I2015J-1162D01*
G01X1174789D01*
G02X1176734Y312909I-70J-2325D01*
G03X1178028Y312122I1365J787D01*
G01X1178170D01*
G03X1179464Y312909I-71J1574D01*
G02X1181409Y314072I2015J-1162D01*
G01X1181549D01*
G02X1183494Y312909I-70J-2325D01*
G03X1184788Y312122I1365J787D01*
G01X1184930D01*
G03X1186224Y312909I-71J1574D01*
G02X1188169Y314072I2015J-1162D01*
G01X1188309D01*
G02X1190254Y312909I-70J-2325D01*
G03X1191548Y312122I1365J787D01*
G01X1191704D01*
G02X1193634Y310960I-85J-2325D01*
G03X1194955Y310172I1365J787D01*
G01X1195043D01*
G03X1196364Y310960I-44J1575D01*
G02X1198294Y312122I2015J-1163D01*
G01X1200736D01*
X1200861Y312247D01*
X1200948D01*
G01Y311247D02*
X1200861D01*
X1200737Y311371D01*
X1198308D01*
G03X1197014Y310584I71J-1574D01*
G02X1195084Y309422I-2015J1163D01*
G01X1194914D01*
G02X1192984Y310584I85J2325D01*
G03X1191690Y311371I-1365J-787D01*
G01X1191549D01*
G02X1189604Y312534I70J2325D01*
G03X1188283Y313322I-1365J-787D01*
G01X1188195D01*
G03X1186874Y312534I44J-1575D01*
G02X1184929Y311371I-2015J1162D01*
G01X1184789D01*
G02X1182844Y312534I70J2325D01*
G03X1181523Y313322I-1365J-787D01*
G01X1181435D01*
G03X1180114Y312534I44J-1575D01*
G02X1178169Y311371I-2015J1162D01*
G01X1178029D01*
G02X1176084Y312534I70J2325D01*
G03X1174763Y313322I-1365J-787D01*
G01X1174675D01*
G03X1173354Y312534I44J-1575D01*
G02X1171409Y311371I-2015J1162D01*
G01X1171269D01*
G02X1169324Y312534I70J2325D01*
G01X1169311Y312557D01*
G03X1167960Y313322I-1351J-810D01*
G01X1167916D01*
G03X1166595Y312534I44J-1575D01*
G02X1164650Y311371I-2015J1162D01*
G01X1164509D01*
G03X1163215Y310584I71J-1574D01*
G02X1161285Y309422I-2015J1163D01*
G01X1161115D01*
G02X1159326Y310367I84J2325D01*
G01X1158974Y310462D01*
X1157820Y309797D01*
G01X1214500Y346750D02*
X1214413D01*
X1214213Y346950D01*
X1211815D01*
X1209387Y344522D01*
X1201701D01*
G02X1199966Y345242I-2J2445D01*
G01X1199759Y345448D01*
X1199471Y345526D01*
X1198379Y344896D01*
G01X1214500Y347900D02*
X1214413D01*
X1214213Y347700D01*
X1211504D01*
X1209076Y345272D01*
X1208026D01*
X1207676Y345622D01*
X1206626D01*
X1206276Y345272D01*
X1205226D01*
X1204876Y345622D01*
X1203826D01*
X1203476Y345272D01*
X1201700D01*
G02X1200497Y345772I-1J1695D01*
G01X1200496Y345773D01*
X1200605Y346181D01*
X1201759Y346847D01*
G01X1174719Y370247D02*
Y368916D01*
X1174976Y368659D01*
G02X1176734Y367509I-257J-2312D01*
G03X1178055Y366721I1365J787D01*
G01X1178184D01*
G02X1180114Y365559I-85J-2325D01*
G03X1181420Y364772I1365J788D01*
G01X1181538D01*
G03X1182844Y365559I-59J1575D01*
G02X1184774Y366721I2015J-1163D01*
G01X1184903D01*
G03X1186224Y367509I-44J1575D01*
G02X1188169Y368672I2015J-1162D01*
G01X1188298D01*
G03X1189623Y371000I-59J1575D01*
G01X1189604Y371034D01*
G02X1189579Y373317I2015J1164D01*
G01X1189604Y373359D01*
G03Y374933I-1365J787D01*
G02Y377259I2015J1163D01*
G03X1189623Y378800I-1365J787D01*
G01X1189604Y378834D01*
X1189579Y378876D01*
G02X1189604Y381159I2040J1119D01*
G03X1189623Y382700I-1365J787D01*
G01X1189604Y382734D01*
X1189579Y382776D01*
G02X1189604Y385059I2040J1119D01*
G01X1189800Y385400D01*
X1189802Y385403D01*
X1190599Y386200D01*
X1192259Y387309D01*
X1192358Y387809D01*
X1192941Y388198D01*
X1193440Y388099D01*
X1194088Y388531D01*
X1194176Y388973D01*
X1194759Y389362D01*
X1195200Y389274D01*
X1195310Y389347D01*
X1196855Y390379D01*
X1203271Y393036D01*
X1204413Y394178D01*
Y394462D01*
X1204474Y394523D01*
G01X1181479Y370247D02*
X1180325Y369581D01*
X1180242Y369271D01*
G03X1181420Y368672I1238J976D01*
G01X1181538D01*
G03X1182844Y369459I-59J1575D01*
G02X1184808Y370622I2015J-1163D01*
G01X1184903D01*
G03X1186224Y372984I-44J1575D01*
G01X1186199Y373026D01*
G02X1186224Y375309I2040J1119D01*
G01X1186243Y375343D01*
G03X1186224Y376884I-1384J754D01*
G02X1186199Y379167I2015J1164D01*
G01X1186224Y379209D01*
X1186243Y379243D01*
G03X1186224Y380784I-1384J754D01*
G02X1186199Y383067I2015J1164D01*
G01X1186224Y383109D01*
X1186243Y383143D01*
G03X1186224Y384684I-1384J754D01*
G02X1188185Y388172I2015J1162D01*
G01X1189543D01*
X1190223Y388852D01*
Y389335D01*
X1190718Y389830D01*
X1191201D01*
X1192171Y390800D01*
X1192815Y391073D01*
Y391072D01*
X1192996Y391519D01*
X1193641Y391792D01*
X1194087Y391611D01*
X1194731Y391883D01*
X1194912Y392330D01*
X1195557Y392603D01*
X1196003Y392422D01*
X1196647Y392694D01*
X1196828Y393141D01*
X1197473Y393414D01*
X1197919Y393233D01*
X1198563Y393505D01*
X1198744Y393952D01*
X1199390Y394225D01*
X1199835Y394044D01*
X1200661Y394393D01*
X1201131Y394863D01*
Y395147D01*
X1201192Y395208D01*
G01X1171339Y364396D02*
X1172493Y363731D01*
X1172803Y363815D01*
G03X1172704Y365184I-1465J582D01*
G02X1172679Y367467I2015J1164D01*
G01X1172704Y367509D01*
X1172723Y367543D01*
G03X1172704Y369084I-1384J754D01*
G02Y371410I2015J1163D01*
G03X1171410Y373771I-1365J787D01*
G01X1171254D01*
G02X1171241Y378421I85J2325D01*
G01X1171383D01*
G03X1172704Y379209I-44J1575D01*
G02X1174649Y380372I2015J-1162D01*
G01X1174778D01*
G03X1176103Y382700I-59J1575D01*
G01X1176084Y382734D01*
X1176059Y382776D01*
G02X1176084Y385059I2040J1119D01*
G03X1176103Y386600I-1365J787D01*
G01X1176084Y386634D01*
X1176059Y386676D01*
G02X1176084Y388959I2040J1119D01*
G03X1176103Y390500I-1365J787D01*
G01X1176084Y390534D01*
X1176059Y390576D01*
G02X1178048Y394022I2040J1120D01*
G01X1178143D01*
G03X1179464Y394810I-44J1575D01*
G02X1181394Y395972I2015J-1163D01*
G01X1181550D01*
G03X1182844Y396759I-71J1574D01*
G02X1184789Y397922I2015J-1162D01*
G01X1184930D01*
G03X1186224Y398709I-71J1574D01*
G01X1186273Y398794D01*
X1193000Y405520D01*
Y408000D01*
X1195800Y410800D01*
X1198600D01*
X1199500Y409900D01*
X1200613D01*
X1200813Y410100D01*
X1200900D01*
G01X1189350Y407627D02*
Y407540D01*
X1189150Y407340D01*
Y406128D01*
X1185993Y402971D01*
Y402408D01*
X1185498Y401913D01*
X1184935D01*
X1183751Y400729D01*
X1183494Y400284D01*
G02X1181530Y399121I-2015J1163D01*
G01X1181435D01*
G03X1180114Y398333I44J-1575D01*
G02X1178184Y397171I-2015J1163D01*
G01X1178028D01*
G03X1176734Y396384I71J-1574D01*
G02X1174789Y395221I-2015J1162D01*
G01X1174648D01*
G03X1173354Y392859I71J-1574D01*
G02X1173379Y390576I-2015J-1164D01*
G01X1173354Y390534D01*
X1173335Y390500D01*
G03X1173354Y388959I1384J-754D01*
G02X1173379Y386676I-2015J-1164D01*
G01X1173354Y386634D01*
X1173335Y386600D01*
G03X1173354Y385059I1384J-754D01*
G02X1171409Y381571I-2015J-1163D01*
G01X1171339D01*
G03X1169988Y380806I0J-1575D01*
G01X1169975Y380783D01*
G02X1168058Y379622I-2015J1164D01*
G01X1167916D01*
G03X1166595Y377259I44J-1575D01*
G02Y374933I-2015J-1163D01*
G03X1167889Y372572I1365J-787D01*
G01X1168045D01*
G02X1169975Y369083I-85J-2325D01*
G03Y367509I1364J-787D01*
G01X1170010Y367449D01*
G02X1169975Y365183I-2050J-1102D01*
G03X1171339Y362821I1364J-787D01*
G01X1171424D01*
G02X1173354Y361659I-85J-2325D01*
G03X1174660Y360872I1365J788D01*
G01X1174789D01*
G02X1176593Y359926I-69J-2325D01*
G01X1176945Y359831D01*
X1178099Y360496D01*
G01Y356596D02*
X1179253Y355931D01*
X1179563Y356015D01*
G03X1178158Y358171I-1465J581D01*
G01X1178040D01*
G03X1176734Y357384I59J-1575D01*
G02X1174804Y356222I-2015J1163D01*
G01X1174634D01*
G02X1172704Y357384I85J2325D01*
G03X1171398Y358171I-1365J-788D01*
G01X1171269D01*
G02X1169324Y359334I70J2325D01*
G01X1169311Y359357D01*
G03X1167960Y360122I-1351J-810D01*
G01X1167875D01*
G02X1165945Y361284I85J2325D01*
G03X1164639Y362071I-1365J-788D01*
G01X1164510D01*
G02X1162565Y365559I70J2325D01*
G03X1162584Y367100I-1365J787D01*
G01X1162565Y367134D01*
X1162540Y367176D01*
G02X1162565Y369459I2040J1119D01*
G03X1162584Y371000I-1365J787D01*
G01X1162565Y371034D01*
G02X1162540Y373317I2015J1164D01*
G01X1162565Y373359D01*
G03Y374933I-1365J787D01*
G02Y377259I2015J1163D01*
G03X1162584Y378800I-1365J787D01*
G01X1162565Y378834D01*
X1162540Y378876D01*
G02X1164495Y382321I2040J1120D01*
G01X1164624D01*
G03X1165945Y383109I-44J1575D01*
G02X1167890Y384272I2015J-1162D01*
G01X1167960D01*
G03X1169324Y386634I0J1575D01*
G01X1169289Y386694D01*
G02X1169324Y388960I2050J1102D01*
G03Y390534I-1364J787D01*
G01X1169289Y390594D01*
G02X1169324Y392860I2050J1102D01*
G03Y394434I-1364J787D01*
G02X1171269Y397922I2015J1163D01*
G01X1171410D01*
G03X1172704Y398709I-71J1574D01*
G02X1174668Y399872I2015J-1163D01*
G01X1174778D01*
G03X1176084Y400659I-59J1575D01*
G02X1178014Y401821I2015J-1163D01*
G01X1178143D01*
G03X1179464Y402609I-44J1575D01*
G02X1181409Y403772I2015J-1162D01*
G01X1182311D01*
X1183250Y404711D01*
Y408389D01*
X1184607Y409746D01*
Y409747D01*
X1185745Y410885D01*
Y411166D01*
X1185979Y411400D01*
G01X1184859Y352696D02*
X1183705Y352031D01*
X1183353Y352126D01*
G03X1181549Y353072I-1873J-1379D01*
G01X1181420D01*
G02X1180114Y353859I59J1575D01*
G03X1178184Y355021I-2015J-1163D01*
G01X1178014D01*
G03X1176084Y353859I85J-2325D01*
G02X1174778Y353072I-1365J788D01*
G01X1174660D01*
G02X1173354Y353859I59J1575D01*
G03X1171424Y355021I-2015J-1163D01*
G01X1171339D01*
G02X1169988Y355786I0J1575D01*
G01X1169975Y355809D01*
G03X1168030Y356972I-2015J-1162D01*
G01X1167901D01*
G02X1166595Y357759I59J1575D01*
G03X1164665Y358921I-2015J-1163D01*
G01X1164536D01*
G02X1163215Y359709I44J1575D01*
G03X1161270Y360872I-2015J-1162D01*
G01X1161141D01*
G02X1159816Y363200I59J1575D01*
G01X1159835Y363234D01*
X1159860Y363276D01*
G03X1159835Y365559I-2040J1119D01*
G02X1159816Y367100I1365J787D01*
G01X1159835Y367134D01*
X1159860Y367176D01*
G03X1159835Y369459I-2040J1119D01*
G02X1159816Y371000I1365J787D01*
G01X1159835Y371034D01*
G03X1159860Y373317I-2015J1164D01*
G01X1159835Y373359D01*
G02Y374933I1365J787D01*
G03Y377259I-2015J1163D01*
G02X1159816Y378800I1365J787D01*
G01X1159835Y378834D01*
X1159860Y378876D01*
G03X1159835Y381159I-2040J1119D01*
G02X1161156Y383522I1365J788D01*
G01X1161285D01*
G03X1163215Y384684I-85J2325D01*
G02X1164521Y385471I1365J-788D01*
G01X1164650D01*
G03X1166595Y388959I-70J2325D01*
G02X1166576Y390500I1365J787D01*
G01X1166595Y390534D01*
X1166620Y390576D01*
G03X1166595Y392859I-2040J1119D01*
G02X1166576Y394400I1365J787D01*
G01X1166595Y394434D01*
G03X1166620Y396717I-2015J1164D01*
G01X1166595Y396759D01*
G02X1167916Y399121I1365J787D01*
G01X1168030D01*
G03X1169975Y400283I-70J2326D01*
G01X1169988Y400306D01*
G02X1171339Y401071I1351J-810D01*
G01X1171409D01*
G03X1173354Y402234I-70J2325D01*
G02X1174675Y403022I1365J-787D01*
G01X1174804D01*
G03X1176734Y404184I-85J2325D01*
G01X1177130Y404870D01*
Y405903D01*
X1177872Y406645D01*
X1178367D01*
X1179110Y407388D01*
Y407883D01*
X1179852Y408625D01*
X1180347D01*
X1181090Y409368D01*
Y409863D01*
X1182666Y411439D01*
X1182950D01*
X1183011Y411500D01*
G01X1174719Y378047D02*
X1173565Y377381D01*
X1173482Y377071D01*
G03X1174660Y376472I1238J976D01*
G01X1174778D01*
G03X1176084Y377259I-59J1575D01*
G02X1178014Y378421I2015J-1163D01*
G01X1178143D01*
G03X1179464Y380784I-44J1575D01*
G02X1179439Y383067I2015J1164D01*
G01X1179464Y383109D01*
X1179483Y383143D01*
G03X1179464Y384684I-1384J754D01*
G02X1179439Y386967I2015J1164D01*
G01X1179464Y387009D01*
X1179483Y387043D01*
G03X1179464Y388584I-1384J754D01*
G02X1181409Y392072I2015J1163D01*
G01X1181538D01*
G03X1182844Y392859I-59J1575D01*
G02X1184808Y394022I2015J-1163D01*
G01X1184903D01*
G03X1186041Y394556I-45J1575D01*
G03X1186224Y394810I-1180J1043D01*
G01Y394809D01*
G02X1188152Y395971I2015J-1162D01*
G01X1189670D01*
G03X1192811Y397272I0J4442D01*
G01X1193469Y397930D01*
Y398346D01*
X1193964Y398841D01*
X1194381D01*
X1194989Y399449D01*
Y399883D01*
X1195484Y400378D01*
X1195917D01*
X1196436Y400897D01*
Y401379D01*
X1196931Y401874D01*
X1197413D01*
X1201539Y406000D01*
X1203000D01*
X1203200Y406200D01*
X1203287D01*
G01X1174719Y374146D02*
X1175873Y373481D01*
X1176225Y373576D01*
G02X1178029Y374522I1873J-1379D01*
G01X1178170D01*
G03X1179464Y375309I-71J1574D01*
G02X1181428Y376472I2015J-1163D01*
G01X1181538D01*
G03X1182863Y378800I-59J1575D01*
G01X1182844Y378834D01*
X1182819Y378876D01*
G02X1182844Y381159I2040J1119D01*
G03X1182863Y382700I-1365J787D01*
G01X1182844Y382734D01*
X1182819Y382776D01*
G02X1182844Y385059I2040J1119D01*
G03X1182863Y386600I-1365J787D01*
G01X1182844Y386634D01*
X1182819Y386676D01*
G02X1184774Y390121I2040J1120D01*
G01X1184903D01*
G03X1186224Y390909I-44J1575D01*
G02X1188169Y392072I2015J-1162D01*
G01X1189376D01*
X1190057Y392753D01*
X1198243Y396144D01*
X1199448Y397349D01*
X1199447Y397630D01*
X1199509Y397692D01*
G01X1174719Y366347D02*
Y367678D01*
X1174947Y367906D01*
G02X1176084Y367134I-228J-1559D01*
G03X1178029Y365971I2015J1162D01*
G01X1178158D01*
G02X1179464Y365184I-59J-1575D01*
G03X1181394Y364022I2015J1163D01*
G01X1181564D01*
G03X1183494Y365184I-85J2325D01*
G02X1184800Y365971I1365J-788D01*
G01X1184929D01*
G03X1186874Y367134I-70J2325D01*
G02X1188195Y367922I1365J-787D01*
G01X1188324D01*
G03X1190254Y371410I-85J2325D01*
G02Y372984I1365J787D01*
G01X1190279Y373026D01*
G03X1190254Y375309I-2040J1119D01*
G01X1190235Y375343D01*
G02X1190254Y376884I1384J754D01*
G03X1190279Y379167I-2015J1164D01*
G01X1190254Y379209D01*
X1190235Y379243D01*
G02X1190254Y380784I1384J754D01*
G03X1190279Y383067I-2015J1164D01*
G01X1190254Y383109D01*
X1190235Y383143D01*
G02X1190254Y384684I1384J754D01*
G01X1190403Y384943D01*
X1191077Y385617D01*
X1197210Y389714D01*
X1203696Y392400D01*
X1204943Y393647D01*
X1205227D01*
X1205287Y393707D01*
Y393709D01*
X1205288Y393710D01*
G01X1178099Y368296D02*
X1179253Y368962D01*
X1179605Y368867D01*
G03X1181394Y367922I1873J1380D01*
G01X1181564D01*
G03X1183494Y369084I-85J2325D01*
G02X1184800Y369871I1365J-788D01*
G01X1184910D01*
G03X1186899Y373317I-51J2326D01*
G01X1186874Y373359D01*
G02Y374933I1365J787D01*
G03Y377259I-2015J1163D01*
G02X1186855Y378800I1365J787D01*
G01X1186874Y378834D01*
X1186899Y378876D01*
G03X1186874Y381159I-2040J1119D01*
G02X1186855Y382700I1365J787D01*
G01X1186874Y382734D01*
X1186899Y382776D01*
G03X1186874Y385059I-2040J1119D01*
G02X1188195Y387422I1365J788D01*
G01X1189854D01*
X1192598Y390166D01*
X1201088Y393759D01*
X1201662Y394333D01*
X1201945D01*
X1202006Y394394D01*
G01X1174719Y362447D02*
X1173565Y363112D01*
X1173471Y363463D01*
G03X1173354Y365559I-2132J932D01*
G02X1173335Y367100I1365J787D01*
G01X1173354Y367134D01*
X1173379Y367176D01*
G03X1173354Y369459I-2040J1119D01*
G02X1173335Y371000I1365J787D01*
G01X1173354Y371034D01*
G03X1171409Y374522I-2015J1163D01*
G01X1171291D01*
G02X1171339Y377671I48J1574D01*
G01X1171409D01*
G03X1173354Y378834I-70J2325D01*
G02X1174675Y379622I1365J-787D01*
G01X1174804D01*
G03X1176759Y383067I-85J2325D01*
G01X1176734Y383109D01*
X1176715Y383143D01*
G02X1176734Y384684I1384J754D01*
G03X1176759Y386967I-2015J1164D01*
G01X1176734Y387009D01*
X1176715Y387043D01*
G02X1176734Y388584I1384J754D01*
G03X1176759Y390867I-2015J1164D01*
G01X1176734Y390909D01*
X1176715Y390943D01*
G02X1178040Y393271I1384J753D01*
G01X1178150D01*
G03X1180114Y394434I-51J2326D01*
G02X1181408Y395221I1365J-787D01*
G01X1181549D01*
G03X1183494Y396384I-70J2325D01*
G02X1184788Y397171I1365J-787D01*
G01X1184944D01*
G03X1186874Y398333I-85J2325D01*
G01X1187419Y398878D01*
X1187899D01*
X1188395Y399374D01*
Y399854D01*
X1188889Y400348D01*
X1189370D01*
X1189866Y400844D01*
Y401325D01*
X1190368Y401827D01*
X1190784D01*
X1191280Y402323D01*
Y402739D01*
X1193750Y405209D01*
Y407689D01*
X1196111Y410050D01*
X1198289D01*
X1199189Y409150D01*
X1200613D01*
X1200813Y408950D01*
X1200900D01*
G01X1188200Y407627D02*
Y407540D01*
X1188400Y407340D01*
Y406439D01*
X1183151Y401190D01*
X1182844Y400659D01*
G02X1181538Y399872I-1365J788D01*
G01X1181428D01*
G03X1179464Y398709I51J-2326D01*
G02X1178170Y397922I-1365J787D01*
G01X1178029D01*
G03X1176084Y396759I70J-2325D01*
G02X1174790Y395972I-1365J787D01*
G01X1174634D01*
G03X1172704Y392484I85J-2325D01*
G02X1172723Y390943I-1365J-787D01*
G01X1172704Y390909D01*
X1172679Y390867D01*
G03X1172704Y388584I2040J-1119D01*
G02X1172723Y387043I-1365J-787D01*
G01X1172704Y387009D01*
X1172679Y386967D01*
G03X1172704Y384684I2040J-1119D01*
G02X1171383Y382321I-1365J-788D01*
G01X1171241D01*
G03X1169324Y381160I98J-2325D01*
G01X1169311Y381137D01*
G02X1167960Y380372I-1351J810D01*
G01X1167890D01*
G03X1165945Y376884I70J-2325D01*
G02X1165964Y375343I-1365J-787D01*
G01X1165945Y375309D01*
G03X1167890Y371821I2015J-1163D01*
G01X1168008D01*
G02X1169324Y369460I-48J-1574D01*
G03X1169289Y367194I2015J-1164D01*
G01X1169324Y367134D01*
G02Y365560I-1364J-787D01*
G03X1171269Y362071I2014J-1164D01*
G01X1171398D01*
G02X1172704Y361284I-59J-1575D01*
G03X1174634Y360122I2015J1163D01*
G01X1174763D01*
G02X1175956Y359522I-45J-1575D01*
G01X1175873Y359212D01*
X1174719Y358547D01*
G01X1181479Y354647D02*
X1180325Y355312D01*
X1180231Y355663D01*
G03X1178184Y358921I-2132J933D01*
G01X1178014D01*
G03X1176084Y357759I85J-2325D01*
G02X1174778Y356972I-1365J788D01*
G01X1174660D01*
G02X1173354Y357759I59J1575D01*
G03X1171424Y358921I-2015J-1163D01*
G01X1171339D01*
G02X1169988Y359686I0J1575D01*
G01X1169975Y359709D01*
G03X1168030Y360872I-2015J-1162D01*
G01X1167901D01*
G02X1166595Y361659I59J1575D01*
G03X1164665Y362821I-2015J-1163D01*
G01X1164536D01*
G02X1163215Y365184I44J1575D01*
G03X1163240Y367467I-2015J1164D01*
G01X1163215Y367509D01*
X1163196Y367543D01*
G02X1163215Y369084I1384J754D01*
G03Y371410I-2015J1163D01*
G02Y372984I1365J787D01*
G01X1163240Y373026D01*
G03X1163215Y375309I-2040J1119D01*
G01X1163196Y375343D01*
G02X1163215Y376884I1384J754D01*
G03X1163240Y379167I-2015J1164D01*
G01X1163215Y379209D01*
X1163196Y379243D01*
G02X1164521Y381571I1384J753D01*
G01X1164650D01*
G03X1166595Y382734I-70J2325D01*
G02X1167916Y383522I1365J-787D01*
G01X1168058D01*
G03X1170010Y386949I-98J2325D01*
G01X1169975Y387009D01*
G02Y388583I1364J787D01*
G03X1170010Y390849I-2015J1164D01*
G01X1169975Y390909D01*
G02Y392483I1364J787D01*
G03X1170000Y394768I-2015J1165D01*
G01X1169975Y394810D01*
G02X1171291Y397171I1364J787D01*
G01X1171424D01*
G03X1173354Y398333I-85J2325D01*
G02X1174675Y399121I1365J-787D01*
G01X1174770D01*
G03X1176734Y400284I-51J2326D01*
G02X1178040Y401071I1365J-788D01*
G01X1178169D01*
G03X1180114Y402234I-70J2325D01*
G02X1181431Y403021I1364J-788D01*
G02X1181435Y403022I384J-1526D01*
G01X1182622D01*
X1184000Y404400D01*
Y405531D01*
X1184196Y405727D01*
Y406427D01*
X1184000Y406623D01*
Y408078D01*
X1186276Y410354D01*
X1186277D01*
X1186278Y410355D01*
X1186561D01*
X1186622Y410416D01*
Y410415D01*
G01X1181479Y350747D02*
X1182633Y351412D01*
X1182716Y351722D01*
G03X1181523Y352322I-1238J-975D01*
G01X1181394D01*
G02X1179464Y353484I85J2325D01*
G03X1178158Y354271I-1365J-788D01*
G01X1178040D01*
G03X1176734Y353484I59J-1575D01*
G02X1174804Y352322I-2015J1163D01*
G01X1174634D01*
G02X1172704Y353484I85J2325D01*
G03X1171398Y354271I-1365J-788D01*
G01X1171269D01*
G02X1169324Y355434I70J2325D01*
G01X1169311Y355457D01*
G03X1167960Y356222I-1351J-810D01*
G01X1167875D01*
G02X1165945Y357384I85J2325D01*
G03X1164639Y358171I-1365J-788D01*
G01X1164510D01*
G02X1162565Y359334I70J2325D01*
G03X1161244Y360122I-1365J-787D01*
G01X1161115D01*
G02X1159160Y363567I85J2325D01*
G01X1159185Y363609D01*
X1159204Y363643D01*
G03X1159185Y365184I-1384J754D01*
G02X1159160Y367467I2015J1164D01*
G01X1159185Y367509D01*
X1159204Y367543D01*
G03X1159185Y369084I-1384J754D01*
G02Y371410I2015J1163D01*
G03Y372984I-1365J787D01*
G01X1159160Y373026D01*
G02X1159185Y375309I2040J1119D01*
G01X1159204Y375343D01*
G03X1159185Y376884I-1384J754D01*
G02X1159160Y379167I2015J1164D01*
G01X1159185Y379209D01*
X1159204Y379243D01*
G03X1159185Y380784I-1384J754D01*
G02X1161130Y384272I2015J1163D01*
G01X1161259D01*
G03X1162565Y385059I-59J1575D01*
G02X1164495Y386221I2015J-1163D01*
G01X1164624D01*
G03X1165945Y388584I-44J1575D01*
G02X1165920Y390867I2015J1164D01*
G01X1165945Y390909D01*
X1165964Y390943D01*
G03X1165945Y392484I-1384J754D01*
G02Y394810I2015J1163D01*
G03Y396384I-1365J787D01*
G01X1165920Y396426D01*
G02X1167909Y399872I2040J1120D01*
G01X1167960D01*
G03X1169311Y400637I0J1575D01*
G01X1169324Y400660D01*
G02X1171241Y401821I2015J-1164D01*
G01X1171383D01*
G03X1172704Y402609I-44J1575D01*
G02X1174649Y403772I2015J-1162D01*
G01X1174788D01*
G03X1176084Y404559I-69J1575D01*
G01Y404560D01*
X1176085D01*
X1176380Y405072D01*
Y406214D01*
X1182136Y411970D01*
Y412252D01*
X1182197Y412313D01*
G01X1171339Y376096D02*
X1172493Y376762D01*
X1172845Y376667D01*
G03X1174632Y375722I1873J1381D01*
G03X1174806I87J2326D01*
G03X1176734Y376884I-87J2326D01*
G02X1178040Y377671I1365J-788D01*
G01X1178169D01*
G03X1180114Y381159I-70J2325D01*
G02X1180095Y382700I1365J787D01*
G01X1180114Y382734D01*
X1180139Y382776D01*
G03X1180114Y385059I-2040J1119D01*
G02X1180095Y386600I1365J787D01*
G01X1180114Y386634D01*
X1180139Y386676D01*
G03X1180114Y388959I-2040J1119D01*
G02X1181435Y391322I1365J788D01*
G01X1181564D01*
G03X1183494Y392484I-85J2325D01*
G02X1184800Y393271I1365J-788D01*
G01X1184910D01*
G03X1186605Y394059I-51J2326D01*
G01X1186658D01*
X1186874Y394434D01*
G02X1188168Y395221I1365J-787D01*
G01X1189670D01*
G03X1193342Y396741I1J5193D01*
G01X1201851Y405250D01*
X1203000D01*
X1203200Y405050D01*
X1203287D01*
G01X1178099Y372197D02*
X1177100Y372772D01*
X1177000Y372830D01*
X1176945Y372862D01*
X1176862Y373172D01*
G02X1178028Y373771I1238J-975D01*
G01X1178184D01*
G03X1180114Y374933I-85J2325D01*
G02X1181435Y375721I1365J-787D01*
G01X1181530D01*
G03X1183519Y379167I-51J2326D01*
G01X1183494Y379209D01*
X1183475Y379243D01*
G02X1183494Y380784I1384J754D01*
G03X1183519Y383067I-2015J1164D01*
G01X1183494Y383109D01*
X1183475Y383143D01*
G02X1183494Y384684I1384J754D01*
G03X1183519Y386967I-2015J1164D01*
G01X1183494Y387009D01*
X1183475Y387043D01*
G02X1184800Y389371I1384J753D01*
G01X1184929D01*
G03X1186874Y390534I-70J2325D01*
G02X1188182Y391322I1365J-787D01*
G01X1189687D01*
X1190482Y392117D01*
X1193411Y393330D01*
X1193683Y393217D01*
X1194331Y393485D01*
X1194444Y393758D01*
X1198668Y395508D01*
X1199978Y396818D01*
X1200262D01*
X1200323Y396879D01*
Y396878D01*
G01X1194999Y378047D02*
X1196153Y377381D01*
X1196247Y377029D01*
G03X1196364Y374933I2132J-932D01*
G03X1198294Y373771I2015J1163D01*
G01X1198464D01*
G03X1200394Y374933I-85J2325D01*
G02X1201245Y375722I1706J-987D01*
G01X1202517D01*
X1206418Y371821D01*
X1215084D01*
X1220961Y377698D01*
X1221245D01*
X1221306Y377759D01*
G01X1209992Y368814D02*
X1209905D01*
X1209655Y368564D01*
X1206680D01*
X1205367Y369108D01*
X1205213Y369479D01*
X1204566Y369747D01*
X1204196Y369594D01*
X1203371Y369935D01*
X1202767Y370539D01*
Y371102D01*
X1202272Y371597D01*
X1201709D01*
X1200872Y372434D01*
X1200702Y373058D01*
X1200851Y373620D01*
X1201759Y374146D01*
G01X1209157Y366085D02*
X1209070D01*
X1208870Y365885D01*
X1206327D01*
X1202248Y367575D01*
X1199786Y370037D01*
G03X1198382Y370620I-1406J-1404D01*
G01X1198378D01*
G02X1197014Y371408I0J1574D01*
G03X1195256Y372558I-2015J-1162D01*
G01X1194999Y372815D01*
Y374146D01*
G01X1208300Y362350D02*
X1208100Y362150D01*
X1206951D01*
X1205551Y363550D01*
X1200489D01*
X1199760Y362821D01*
X1198335D01*
G02X1198039Y362858I47J1575D01*
G02X1197142Y363421I340J1538D01*
G02X1196968Y363696I1244J979D01*
G01X1197113Y363982D01*
X1198379Y364396D01*
G01X1214210Y359350D02*
X1214200D01*
X1214000Y359150D01*
X1211370D01*
X1206029Y358888D01*
X1205199D01*
G02X1203773Y359711I-2J1644D01*
G01Y359712D01*
G03X1201844Y360872I-2014J-1165D01*
G01X1201714D01*
G03X1201184Y360844I-31J-4439D01*
G01X1198379Y360496D01*
G01Y356596D02*
Y355412D01*
X1198770Y355021D01*
X1213038D01*
X1213217Y355200D01*
X1213309D01*
G01X1213977Y381912D02*
Y381577D01*
X1211900Y379500D01*
X1209500D01*
X1208281Y379881D01*
X1201940Y386222D01*
X1197478D01*
X1196683Y385610D01*
X1196364Y385060D01*
Y385059D01*
G02X1195068Y384272I-1365J788D01*
G01X1194929D01*
G03X1192850Y382839I70J-2326D01*
G02X1191619Y379996I-96727J40194D01*
G01X1220325Y381728D02*
X1220293Y381696D01*
X1220012D01*
X1214516Y376200D01*
X1205940D01*
X1202519Y379621D01*
X1201688D01*
G03X1200394Y378834I71J-1574D01*
G02X1198449Y377671I-2015J1162D01*
G01X1198309D01*
G02X1196364Y378834I70J2325D01*
G01X1196339Y378876D01*
G02X1196364Y381159I2040J1119D01*
G02X1196966Y381844I2015J-1163D01*
G03X1198379Y383896I-2442J3194D01*
G01X1220492Y378572D02*
X1220460Y378540D01*
Y378258D01*
X1219432Y377230D01*
X1218868D01*
X1218373Y376735D01*
Y376171D01*
X1217879Y375677D01*
X1217315D01*
X1216820Y375182D01*
Y374618D01*
X1216326Y374124D01*
X1215762D01*
X1215267Y373629D01*
Y373065D01*
X1214773Y372571D01*
X1214245D01*
X1213880Y372936D01*
X1213180D01*
X1212815Y372571D01*
X1212066D01*
X1211692Y372945D01*
X1210992D01*
X1210618Y372571D01*
X1206729D01*
X1205880Y373420D01*
Y373892D01*
X1205385Y374387D01*
X1204913D01*
X1204338Y374962D01*
Y375450D01*
X1203843Y375945D01*
X1203355D01*
X1202828Y376472D01*
X1201024D01*
G03X1200920Y376398I1503J-2223D01*
G03X1199744Y375309I1179J-2453D01*
G02X1198450Y374522I-1365J787D01*
G01X1198308D01*
G02X1197014Y375309I71J1574D01*
G01X1196995Y375343D01*
G02X1196915Y376678I1385J753D01*
G01X1197225Y376762D01*
X1198379Y376096D01*
G01X1209992Y367664D02*
X1209948D01*
X1209798Y367814D01*
X1206530D01*
X1202946Y369299D01*
X1200006Y372239D01*
X1199493Y372511D01*
X1198985Y372608D01*
X1198379Y372197D01*
G01X1209157Y364935D02*
X1209070D01*
X1208870Y365135D01*
X1206177D01*
X1201823Y366939D01*
X1199255Y369507D01*
G03X1198381Y369870I-875J-873D01*
G01X1198379D01*
G02X1196364Y371033I-1J2325D01*
G03X1195227Y371805I-1365J-787D01*
G01X1194999Y371577D01*
Y370247D01*
G01X1208300Y361200D02*
X1208256D01*
X1208056Y361400D01*
X1206640D01*
X1205240Y362800D01*
X1200800D01*
X1200071Y362071D01*
X1198309D01*
G02X1197876Y362125I70J2325D01*
G01X1195310Y362412D01*
X1194999Y362447D01*
G01X1214210Y358200D02*
X1214153D01*
X1213953Y358400D01*
X1211389D01*
X1206048Y358138D01*
X1205199D01*
G02X1203124Y359335I-2J2394D01*
G03X1201828Y360122I-1365J-788D01*
G01X1201700D01*
G03X1200522Y359523I60J-1575D01*
G03X1200348Y359249I1254J-988D01*
G01X1200493Y358963D01*
X1201759Y358547D01*
G01X1198379Y352696D02*
Y353857D01*
X1198793Y354271D01*
X1212923D01*
X1213144Y354050D01*
X1213285D01*
G01X1214870Y381187D02*
X1214648D01*
X1212211Y378750D01*
X1209385D01*
X1207881Y379220D01*
X1201629Y385472D01*
X1197734D01*
X1197258Y385106D01*
X1197014Y384684D01*
G02X1195083Y383522I-2015J1163D01*
G01X1194955D01*
G03X1193544Y382551I44J-1575D01*
G03X1193535Y381365I1455J-604D01*
G03X1194999Y381947I732J291D01*
G01X1198379Y379996D02*
Y381327D01*
X1198151Y381555D01*
G03X1197014Y380784I228J-1560D01*
G03X1196995Y379243I1365J-787D01*
G01X1197014Y379209D01*
G03X1198335Y378421I1365J787D01*
G01X1198423D01*
G03X1199744Y379209I-44J1575D01*
G02X1201672Y380371I2015J-1162D01*
G01X1202830D01*
X1203373Y379828D01*
X1203821D01*
X1204316Y379333D01*
Y378885D01*
X1204874Y378327D01*
X1205297D01*
X1205792Y377832D01*
Y377409D01*
X1206251Y376950D01*
X1206951D01*
X1207341Y377340D01*
X1208041D01*
X1208431Y376950D01*
X1209131D01*
X1209521Y377340D01*
X1210221D01*
X1210611Y376950D01*
X1211311D01*
X1211701Y377340D01*
X1212401D01*
X1212791Y376950D01*
X1214204D01*
X1214785Y377531D01*
Y378094D01*
X1215280Y378589D01*
X1215843D01*
X1216337Y379083D01*
Y379647D01*
X1216832Y380142D01*
X1217396D01*
X1217890Y380636D01*
Y381200D01*
X1218385Y381695D01*
X1218949D01*
X1219473Y382219D01*
Y382503D01*
X1219512Y382542D01*
G01X1594260Y40288D02*
X1594887Y39661D01*
G01X1561400Y497400D02*
X1561313D01*
X1561113Y497200D01*
X1554400D01*
X1552700Y498900D01*
Y508206D01*
X1550031Y510875D01*
X1549225D01*
X1548300Y511800D01*
G01X1542475Y501900D02*
Y501619D01*
X1543259Y500835D01*
X1543706D01*
X1544152Y501281D01*
Y501590D01*
X1544150Y501592D01*
Y503013D01*
X1545055Y503918D01*
Y506029D01*
X1544705Y506379D01*
Y507429D01*
X1545055Y507779D01*
Y508829D01*
X1544705Y509179D01*
Y510229D01*
X1545055Y510579D01*
Y511629D01*
X1544855Y511829D01*
Y511873D01*
G01X1542475Y509600D02*
Y508805D01*
X1542239Y508569D01*
X1541825D01*
X1541101Y507845D01*
X1540755D01*
X1540281Y508319D01*
Y509657D01*
X1540631Y510007D01*
Y511057D01*
X1540281Y511407D01*
Y513501D01*
X1541023Y514243D01*
X1541518D01*
X1542261Y514986D01*
Y515481D01*
X1543393Y516613D01*
X1544443D01*
X1544793Y516263D01*
X1545843D01*
X1546193Y516613D01*
X1547890D01*
X1548090Y516413D01*
X1548177D01*
G01X1561400Y496250D02*
X1561313D01*
X1561113Y496450D01*
X1554089D01*
X1551950Y498589D01*
Y507895D01*
X1549720Y510125D01*
X1549225D01*
X1548300Y509200D01*
G01X1542475Y499400D02*
X1543160Y500085D01*
X1544017D01*
X1544902Y500970D01*
Y501901D01*
X1544900Y501903D01*
Y502702D01*
X1545805Y503607D01*
Y511586D01*
X1546005Y511786D01*
Y511873D01*
G01X1542475Y507000D02*
X1540539D01*
X1539531Y508008D01*
Y513812D01*
X1543082Y517363D01*
X1547890D01*
X1548090Y517563D01*
X1548177D01*
G01X1587946Y462603D02*
X1587885Y462664D01*
X1587886Y462946D01*
X1586626Y464206D01*
X1579567D01*
X1573900Y469873D01*
Y473109D01*
X1571990Y475019D01*
X1571375D01*
G02X1570212Y475332I2J2326D01*
G01Y475331D01*
G03X1568638I-787J-1365D01*
G02X1566312I-1163J2015D01*
G03X1564738I-787J-1365D01*
G02X1562413Y475330I-1163J2015D01*
G02X1561290Y476907I1162J2016D01*
G01X1560851Y477346D01*
X1559675D01*
G01X1548300Y504000D02*
X1547820Y503520D01*
X1547014D01*
X1545700Y502206D01*
Y493124D01*
X1547267Y491557D01*
X1560230D01*
X1560430Y491357D01*
X1560517D01*
G01X1548300Y501500D02*
Y502010D01*
X1547819Y502491D01*
X1547046D01*
X1546450Y501895D01*
Y498823D01*
X1546800Y498473D01*
Y497423D01*
X1546450Y497073D01*
Y496023D01*
X1546800Y495673D01*
Y494623D01*
X1546450Y494273D01*
Y493435D01*
X1547578Y492307D01*
X1548628D01*
X1548978Y492657D01*
X1550028D01*
X1550378Y492307D01*
X1551428D01*
X1551818Y492697D01*
X1552868D01*
X1553258Y492307D01*
X1554308D01*
X1554658Y492657D01*
X1555708D01*
X1556058Y492307D01*
X1557108D01*
X1557458Y492657D01*
X1558508D01*
X1558858Y492307D01*
X1560230D01*
X1560430Y492507D01*
X1560517D01*
G01X1549925Y480726D02*
X1550590Y479572D01*
X1550495Y479220D01*
G03X1549550Y477431I1380J-1873D01*
G01Y477261D01*
G03X1550712Y475331I2325J85D01*
G02X1551500Y474010I-787J-1365D01*
G01Y473881D01*
G03X1552662Y471951I2325J85D01*
G02X1553450Y470630I-787J-1365D01*
G01Y470501D01*
G03X1554612Y468571I2325J85D01*
G03X1556938I1163J2015D01*
G02X1558512I787J-1365D01*
G02X1559300Y467250I-787J-1365D01*
G01Y467121D01*
G03X1560462Y465191I2325J85D01*
G02X1561250Y463870I-787J-1365D01*
G01Y463741D01*
G03X1562412Y461811I2325J85D01*
G02X1563200Y460490I-787J-1365D01*
G01Y460361D01*
G03X1564362Y458431I2325J85D01*
G03X1566688I1163J2015D01*
G02X1568262I787J-1365D01*
G02X1569050Y457110I-787J-1365D01*
G01Y457065D01*
G03X1570213Y455051I2328J2D01*
G02X1570538Y454802I-780J-1355D01*
G01X1570539Y454801D01*
Y454800D01*
X1570540D01*
X1571370Y453970D01*
X1571970D01*
X1579609Y446331D01*
Y444269D01*
X1581307Y442571D01*
X1591535D01*
X1591735Y442371D01*
X1591822D01*
G01X1551875Y477346D02*
X1551210Y478500D01*
X1550900Y478583D01*
G03X1550300Y477390I975J-1238D01*
G01Y477302D01*
G03X1551088Y475981I1575J44D01*
G02X1552250Y474051I-1163J-2015D01*
G01Y473922D01*
G03X1553038Y472601I1575J44D01*
G02X1554200Y470671I-1163J-2015D01*
G01Y470542D01*
G03X1554988Y469221I1575J44D01*
G03X1556562I787J1365D01*
G02X1558888I1163J-2015D01*
G02X1560050Y467291I-1163J-2015D01*
G01Y467162D01*
G03X1560838Y465841I1575J44D01*
G02X1562000Y463911I-1163J-2015D01*
G01Y463782D01*
G03X1562788Y462461I1575J44D01*
G02X1563950Y460531I-1163J-2015D01*
G01Y460402D01*
G03X1564738Y459081I1575J44D01*
G03X1566312I787J1365D01*
G02X1568638I1163J-2015D01*
G02X1569800Y457151I-1163J-2015D01*
G01Y457066D01*
G03X1570588Y455701I1578J1D01*
G02X1571068Y455333I-1156J-2005D01*
G02X1571070Y455331I-1644J-1646D01*
G01X1571681Y454720D01*
X1572281D01*
X1573792Y453209D01*
X1574287D01*
X1575030Y452466D01*
Y451971D01*
X1575772Y451229D01*
X1576267D01*
X1577010Y450486D01*
Y449991D01*
X1577752Y449249D01*
X1578247D01*
X1578990Y448506D01*
Y448011D01*
X1580359Y446642D01*
Y444580D01*
X1581618Y443321D01*
X1582668D01*
X1583018Y443671D01*
X1584068D01*
X1584418Y443321D01*
X1585468D01*
X1585818Y443671D01*
X1586868D01*
X1587218Y443321D01*
X1588268D01*
X1588618Y443671D01*
X1589668D01*
X1590018Y443321D01*
X1591535D01*
X1591735Y443521D01*
X1591822D01*
G01X1526500Y501300D02*
X1525625Y502175D01*
X1525130D01*
X1524780Y501825D01*
Y496838D01*
X1525522Y496096D01*
X1526017D01*
X1526760Y495353D01*
Y494858D01*
X1527502Y494116D01*
X1527997D01*
X1528740Y493373D01*
Y492878D01*
X1531018Y490600D01*
X1533681D01*
X1534031Y490950D01*
X1535081D01*
X1535431Y490600D01*
X1536481D01*
X1536831Y490950D01*
X1537881D01*
X1538231Y490600D01*
X1539281D01*
X1539631Y490950D01*
X1540681D01*
X1541031Y490600D01*
X1542081D01*
G02X1544450Y488231I0J-2369D01*
G01Y487432D01*
G02X1543288Y485471I-2236J0D01*
G03X1542500Y484150I787J-1365D01*
G01Y484062D01*
G03X1543288Y482741I1575J44D01*
G02X1544450Y480811I-1163J-2015D01*
G01Y480682D01*
G03X1545238Y479361I1575J44D01*
G02X1546400Y477431I-1163J-2015D01*
G01Y477261D01*
G02X1545238Y475331I-2325J85D01*
G03X1544450Y474010I787J-1365D01*
G01Y473922D01*
G03X1545238Y472601I1575J44D01*
G02X1546400Y470671I-1163J-2015D01*
G01Y470542D01*
G03X1547188Y469221I1575J44D01*
G02X1548350Y467291I-1163J-2015D01*
G01Y467162D01*
G03X1549137Y465841I1575J43D01*
G03X1550712I788J1365D01*
G02X1553038I1163J-2015D01*
G03X1554612I787J1365D01*
G02X1556937Y465842I1163J-2015D01*
G02X1558100Y463911I-1162J-2016D01*
G01Y463782D01*
G03X1558888Y462461I1575J44D01*
G02X1560050Y460531I-1163J-2015D01*
G01Y460402D01*
G03X1560838Y459081I1575J44D01*
G02X1562000Y457151I-1163J-2015D01*
G01Y457022D01*
G03X1562787Y455701I1575J43D01*
G03X1564362I788J1365D01*
G02X1566687Y455702I1163J-2015D01*
G02X1567850Y453771I-1162J-2016D01*
G01Y453642D01*
G03X1568638Y452321I1575J44D01*
G02X1569800Y450391I-1163J-2015D01*
G01Y450237D01*
G03X1570587Y448941I1575J69D01*
G03X1572753Y448360I2166J3747D01*
G01X1572989D01*
G02X1574821Y447632I71J-2489D01*
G01X1576743Y445710D01*
Y444812D01*
X1576943Y444612D01*
Y444525D01*
G01X1526500Y503800D02*
X1525625Y502925D01*
X1524819D01*
X1524030Y502136D01*
Y496527D01*
X1530707Y489850D01*
X1542081D01*
G02X1543700Y488231I0J-1619D01*
G01Y487442D01*
G02X1542912Y486121I-1575J44D01*
G03X1541750Y484191I1163J-2015D01*
G01Y484021D01*
G03X1542912Y482091I2325J85D01*
G02X1543700Y480770I-787J-1365D01*
G01Y480641D01*
G03X1544862Y478711I2325J85D01*
G02X1545650Y477390I-787J-1365D01*
G01Y477302D01*
G02X1544862Y475981I-1575J44D01*
G03X1543700Y474051I1163J-2015D01*
G01Y473881D01*
G03X1544862Y471951I2325J85D01*
G02X1545650Y470630I-787J-1365D01*
G01Y470501D01*
G03X1546812Y468571I2325J85D01*
G02X1547600Y467250I-787J-1365D01*
G01Y467121D01*
G03X1548762Y465191I2325J85D01*
G03X1551088I1163J2015D01*
G02X1552662I787J-1365D01*
G03X1554988I1163J2015D01*
G02X1556562I787J-1365D01*
G02X1557350Y463870I-787J-1365D01*
G01Y463741D01*
G03X1558512Y461811I2325J85D01*
G02X1559300Y460490I-787J-1365D01*
G01Y460361D01*
G03X1560462Y458431I2325J85D01*
G02X1561250Y457110I-787J-1365D01*
G01Y456981D01*
G03X1562412Y455051I2325J85D01*
G03X1564738I1163J2015D01*
G02X1566312I787J-1365D01*
G02X1567100Y453730I-787J-1365D01*
G01Y453601D01*
G03X1568262Y451671I2325J85D01*
G02X1569050Y450350I-787J-1365D01*
G01Y450221D01*
G03X1570212Y448291I2325J85D01*
G03X1572752Y447610I2540J4398D01*
G01X1573010D01*
G02X1574291Y447101I50J-1740D01*
G01X1575993Y445399D01*
Y444812D01*
X1575793Y444612D01*
Y444525D01*
G01X1592054Y466338D02*
X1592022Y466370D01*
X1591738D01*
X1590810Y467298D01*
X1582727D01*
X1576955Y473070D01*
Y481006D01*
X1572689Y485272D01*
X1570158D01*
X1569457Y484571D01*
X1569255Y483920D01*
X1568817Y483688D01*
X1567475Y484106D01*
G01X1586693Y469837D02*
X1586606D01*
X1586406Y469637D01*
X1584248D01*
X1580559Y473326D01*
Y481318D01*
X1572064Y489813D01*
X1565402D01*
G03X1563201Y487612I0J-2201D01*
G01Y487429D01*
X1563200Y487401D01*
G03X1564145Y485612I2325J84D01*
G01Y485095D01*
X1563575Y484106D01*
G01X1591241Y465524D02*
X1591180Y465585D01*
Y465867D01*
X1590499Y466548D01*
X1582416D01*
X1581674Y467290D01*
X1581179D01*
X1580436Y468033D01*
Y468528D01*
X1579694Y469270D01*
X1579199D01*
X1578456Y470013D01*
Y470508D01*
X1576205Y472759D01*
Y473809D01*
X1575855Y474159D01*
Y475209D01*
X1576205Y475559D01*
Y476609D01*
X1575855Y476959D01*
Y478009D01*
X1576205Y478359D01*
Y480695D01*
X1575463Y481437D01*
X1574968D01*
X1574225Y482180D01*
Y482675D01*
X1572378Y484522D01*
X1570469D01*
X1570121Y484174D01*
X1569972Y483699D01*
X1570202Y483260D01*
X1571545Y482842D01*
G01X1586693Y468687D02*
X1586606D01*
X1586406Y468887D01*
X1583937D01*
X1583071Y469753D01*
X1582576D01*
X1581834Y470495D01*
Y470990D01*
X1579809Y473015D01*
Y475407D01*
X1579459Y475757D01*
Y476807D01*
X1579809Y477157D01*
Y478207D01*
X1579459Y478557D01*
Y479607D01*
X1579809Y479957D01*
Y481007D01*
X1577693Y483123D01*
X1577198D01*
X1576455Y483866D01*
Y484361D01*
X1575713Y485103D01*
X1575218D01*
X1574475Y485846D01*
Y486341D01*
X1573733Y487083D01*
X1573238D01*
X1572495Y487826D01*
Y488321D01*
X1571753Y489063D01*
X1565402D01*
G03X1563951Y487612I0J-1451D01*
G01Y487429D01*
G03X1564550Y486249I1574J57D01*
G01X1564844Y486328D01*
X1564860Y486332D01*
X1565192Y486908D01*
X1565525Y487486D01*
G01X1588759Y463417D02*
X1588476D01*
X1586937Y464956D01*
X1579878D01*
X1578551Y466283D01*
Y466834D01*
X1577809Y467577D01*
X1577257D01*
X1574650Y470184D01*
Y473420D01*
X1572301Y475769D01*
X1571376D01*
G02X1570588Y475981I2J1576D01*
G03X1568262I-1163J-2015D01*
G02X1566688I-787J1365D01*
G03X1564362I-1163J-2015D01*
G02X1562788I-787J1365D01*
G02X1562028Y477049I787J1365D01*
G02X1562016Y477118I1546J304D01*
G01X1562244Y477346D01*
X1563575D01*
G01X1571375D02*
X1570710Y478500D01*
X1570358Y478594D01*
G02X1568262Y478711I-932J2132D01*
G03X1566688I-787J-1365D01*
G02X1564362I-1163J2015D01*
G03X1562787I-787J-1366D01*
G02X1560463I-1162J2015D01*
G03X1558887I-788J-1365D01*
G03X1558100Y477415I788J-1365D01*
G01Y477277D01*
G03X1558887Y475981I1575J69D01*
G02X1560050Y474020I-1162J-2015D01*
G01Y473897D01*
G03X1562413Y472601I1575J69D01*
G02X1565900Y470640I1162J-2015D01*
G01Y470517D01*
G03X1566687Y469221I1575J69D01*
G02X1567850Y467260I-1162J-2015D01*
G01Y467137D01*
G03X1568637Y465841I1575J69D01*
G02X1569800Y463880I-1162J-2015D01*
G01Y463831D01*
G03X1569903Y463583I350J0D01*
G01X1570646Y462840D01*
X1571141D01*
X1571884Y462097D01*
Y461602D01*
X1572626Y460860D01*
X1573121D01*
X1573864Y460117D01*
Y459622D01*
X1574606Y458880D01*
X1575101D01*
X1575844Y458137D01*
Y457642D01*
X1576586Y456900D01*
X1576868D01*
X1576929Y456839D01*
G01X1569425Y480726D02*
X1569942Y479829D01*
X1569823Y479342D01*
G02X1568638Y479361I-575J1075D01*
G03X1566312I-1163J-2015D01*
G02X1564738I-787J1365D01*
G03X1562412I-1163J-2015D01*
G02X1560838I-787J1365D01*
G03X1558512I-1163J-2015D01*
G03X1557350Y477431I1163J-2015D01*
G01Y477261D01*
G03X1558512Y475331I2325J85D01*
G02X1559300Y474010I-787J-1365D01*
G01Y473881D01*
G03X1562788Y471951I2325J85D01*
G02X1565150Y470630I787J-1365D01*
G01Y470501D01*
G03X1566312Y468571I2325J85D01*
G02X1567100Y467250I-787J-1365D01*
G01Y467121D01*
G03X1568262Y465191I2325J85D01*
G02X1569050Y463870I-787J-1365D01*
G01Y463831D01*
G03X1569373Y463052I1101J0D01*
G01X1575625Y456799D01*
X1576055Y456370D01*
Y456086D01*
X1576116Y456025D01*
G01X1532785Y399363D02*
X1529775D01*
X1529758Y399346D01*
X1526286D01*
X1525973Y399033D01*
X1525971D01*
X1525015Y398077D01*
Y396193D01*
X1526500Y394708D01*
Y393278D01*
X1528094Y391684D01*
Y389531D01*
X1526896Y388333D01*
G01X1520027Y389494D02*
X1520603Y390070D01*
Y391876D01*
X1518344Y394135D01*
Y395546D01*
X1517156Y396734D01*
Y398444D01*
X1519106Y400394D01*
Y401824D01*
X1520025Y402743D01*
X1526906D01*
X1528475Y401174D01*
G01X1480887Y417334D02*
X1480974D01*
X1481174Y417134D01*
X1484348D01*
X1487422Y414060D01*
X1488688Y413329D01*
G02X1491425Y411314I-7673J-13289D01*
G01X1480887Y416184D02*
X1480974D01*
X1481174Y416384D01*
X1484037D01*
X1486961Y413460D01*
X1488312Y412679D01*
G02X1489084Y411542I-787J-1365D01*
G02X1487525Y411314I-779J-114D01*
G01X1542125Y460446D02*
X1540794D01*
X1540566Y460674D01*
G02X1542912Y461811I1559J-228D01*
G03X1545238I1163J2015D01*
G02X1546812I787J-1365D01*
G03X1549138I1163J2015D01*
G02X1550712I787J-1365D01*
G03X1553038I1163J2015D01*
G02X1555400Y460490I787J-1365D01*
G01Y460361D01*
G03X1556562Y458431I2325J85D01*
G02X1557350Y457110I-787J-1365D01*
G01Y456981D01*
G03X1558512Y455051I2325J85D01*
G02X1559125Y454409I-787J-1365D01*
G01X1561012Y452522D01*
X1561164Y451281D01*
Y450240D01*
X1561175Y450105D01*
X1560084Y448376D01*
X1560074Y447594D01*
X1560056Y447576D01*
Y446276D01*
X1560070Y446262D01*
Y446245D01*
X1561379Y444313D01*
G03X1561250Y443631I2196J-769D01*
G01Y443461D01*
G03X1562412Y441531I2325J85D01*
G02Y438801I-787J-1365D01*
G03X1561250Y436871I1163J-2015D01*
G01Y433438D01*
X1560056Y432244D01*
Y430944D01*
X1562006Y428994D01*
Y427564D01*
X1563495Y426075D01*
Y423593D01*
X1562006Y422104D01*
Y420677D01*
X1560056Y418727D01*
Y417294D01*
X1558106Y415344D01*
Y412222D01*
X1562006Y408322D01*
Y400524D01*
X1563495Y399035D01*
Y396553D01*
X1562006Y395064D01*
Y393764D01*
X1563495Y392275D01*
Y389793D01*
X1562006Y388304D01*
Y387004D01*
X1563495Y385515D01*
Y383033D01*
X1562006Y381544D01*
Y380244D01*
X1563205Y379045D01*
Y376875D01*
X1561719Y375389D01*
G01X1563955Y443499D02*
Y447463D01*
X1561998Y449420D01*
X1561976Y451686D01*
Y452618D01*
X1559733Y454861D01*
G03X1558888Y455701I-2008J-1175D01*
G02X1558100Y457022I787J1365D01*
G01Y457151D01*
G03X1556938Y459081I-2325J-85D01*
G02X1556150Y460402I787J1365D01*
G01Y460531D01*
G03X1552662Y462461I-2325J-85D01*
G02X1551088I-787J1365D01*
G03X1548762I-1163J-2015D01*
G02X1547188I-787J1365D01*
G03X1544862I-1163J-2015D01*
G02X1543288I-787J1365D01*
G03X1539812Y460702I-1163J-2015D01*
G01X1539556Y460446D01*
X1538225D01*
G01X1876832Y173919D02*
Y174632D01*
X1879200Y177000D01*
Y177356D01*
X1882819Y180975D01*
X1885530D01*
X1887125Y182570D01*
Y192825D01*
X1891378Y197078D01*
G01X1915294Y191475D02*
X1915894Y190875D01*
X1922836D01*
X1924036Y189675D01*
X1925964D01*
X1926770Y190481D01*
X1936719D01*
X1938400Y188800D01*
Y178200D01*
G01X1876657Y175801D02*
X1878250Y177394D01*
Y177750D01*
X1882425Y181925D01*
X1885136D01*
X1886175Y182964D01*
Y193219D01*
X1890786Y197830D01*
G01X1912336Y194627D02*
X1913206D01*
X1916008Y191825D01*
X1922947D01*
X1924347Y190425D01*
X1925653D01*
X1926659Y191431D01*
X1936331D01*
X1939200Y194300D01*
G54D25*
G01X-18160Y522609D02*
X-18562Y522207D01*
Y517462D01*
X-12600Y511500D01*
Y490836D01*
X-16000Y487436D01*
Y483200D01*
X-5690Y472890D01*
Y467840D01*
G01X-6650Y487800D02*
Y483750D01*
X-7300Y483100D01*
Y479700D01*
X-2500Y474900D01*
Y467600D01*
X-5260Y464840D01*
X-6100D01*
G01X-2500Y569500D02*
Y577892D01*
X-9100Y584492D01*
Y593831D01*
X-6839Y596092D01*
X687D01*
X2948Y593831D01*
X17473D01*
X17954Y594312D01*
X19917D01*
X21088Y595483D01*
X22982D01*
X32099Y604600D01*
X60900D01*
X63500Y602000D01*
G01X429781Y264793D02*
X429834D01*
Y259835D01*
X426571Y256572D01*
X425700Y254291D01*
Y253797D01*
X423370Y248172D01*
X422594Y247396D01*
G01X508707Y258532D02*
X509858D01*
X510701Y257689D01*
X515395D01*
X516801Y259095D01*
X519097D01*
X520154Y258038D01*
Y257735D01*
X520764Y257125D01*
X522497D01*
X523479Y256143D01*
Y255982D01*
X524225Y255236D01*
X525899D01*
X526877Y256214D01*
Y256462D01*
X527599Y257184D01*
X529259D01*
X530272Y258197D01*
Y258425D01*
X530941Y259094D01*
X532600D01*
X533709Y260203D01*
Y260423D01*
X534295Y261009D01*
X535999D01*
X536975Y261985D01*
Y262123D01*
X537865Y263013D01*
X539453D01*
X540346Y263906D01*
Y264090D01*
X541217Y264961D01*
X542812D01*
X543618Y265767D01*
Y265861D01*
X544612Y266855D01*
X546158D01*
X546956Y267653D01*
Y267763D01*
X548041Y268848D01*
X549620D01*
X550405Y269633D01*
Y269821D01*
X551347Y270763D01*
X552937D01*
X553782Y271608D01*
Y271768D01*
X554780Y272766D01*
X556343D01*
X557118Y273541D01*
Y273653D01*
X558180Y274715D01*
X560784D01*
X562045Y273454D01*
X564816D01*
X569461Y278099D01*
X575104D01*
G01X715130Y79574D02*
Y79660D01*
X715740D01*
X722584Y86504D01*
Y117102D01*
X672793Y166893D01*
X660107D01*
X654400Y172600D01*
Y177192D01*
X631235Y200357D01*
Y208208D01*
X627845Y211598D01*
Y241368D01*
X624062Y245151D01*
Y256036D01*
X605637Y274461D01*
X577118D01*
X575104Y276475D01*
Y278099D01*
G01D02*
X615849Y318844D01*
Y328010D01*
X646806Y358967D01*
X673091D01*
X673591Y358467D01*
X674194D01*
G01X674300Y489500D02*
Y487478D01*
X673180Y486358D01*
Y484782D01*
X673456Y484506D01*
Y467656D01*
X643400Y437600D01*
X640300D01*
G01X714391Y215809D02*
X714400Y215800D01*
X719700D01*
X744152Y191348D01*
X769044D01*
G01X714391Y215809D02*
X712691D01*
X710000Y218500D01*
Y221200D01*
X708800Y222400D01*
X702700D01*
X701100Y224000D01*
Y226000D01*
X701700Y226600D01*
G01X677563Y365496D02*
X674100Y368959D01*
Y377656D01*
X672024Y379732D01*
Y395824D01*
X687400Y411200D01*
G01X693604Y494303D02*
X693704Y494403D01*
Y500505D01*
X693900Y500701D01*
Y502800D01*
X697200Y506100D01*
Y513400D01*
X698814Y515014D01*
X705986D01*
X708500Y512500D01*
G01X743600Y304100D02*
X744300Y304800D01*
Y318600D01*
X756600Y330900D01*
Y352627D01*
X762602Y358629D01*
Y367886D01*
X767626Y372910D01*
Y377694D01*
X764957Y380363D01*
G01X1072202Y247396D02*
X1074100Y250800D01*
X1076931Y258888D01*
X1079691Y263700D01*
X1079859Y265000D01*
G01X1097374Y612659D02*
X1096700Y611985D01*
Y609300D01*
X1094900Y607500D01*
Y606900D01*
X1097200Y604600D01*
Y593500D01*
X1095900Y592200D01*
Y589900D01*
X1097343Y588457D01*
Y588394D01*
G01X1309462Y240229D02*
X1306270D01*
X1303429Y243070D01*
X1272923D01*
X1271443Y241590D01*
X1269690D01*
X1258008Y253272D01*
X1233805D01*
X1225980Y245447D01*
X1201759D01*
G01X1272100Y141603D02*
Y149830D01*
X1284870Y162600D01*
X1303021D01*
X1303906Y161715D01*
X1309725D01*
X1312630Y164620D01*
Y170978D01*
X1316836Y175184D01*
X1412774D01*
X1434875Y197285D01*
X1446331D01*
G01X1437400Y244150D02*
X1432554D01*
X1429152Y247552D01*
X1405899D01*
X1403347Y245000D01*
X1314233D01*
X1309462Y240229D01*
G01X1378200Y346900D02*
Y346750D01*
X1379200Y345750D01*
X1380930D01*
X1381760Y346580D01*
Y352370D01*
X1380710Y353420D01*
X1343440D01*
X1338780Y358080D01*
Y362320D01*
X1342570Y366110D01*
Y368220D01*
G01X1318054Y460507D02*
Y465248D01*
X1327647Y474841D01*
X1348067D01*
X1352771Y470137D01*
X1359016D01*
X1359569Y470690D01*
X1445122D01*
X1458581Y484149D01*
Y486341D01*
X1459367Y487127D01*
Y491677D01*
X1460246Y492556D01*
Y495095D01*
X1467851Y502700D01*
X1472700D01*
X1474052Y504052D01*
X1492194D01*
X1494800Y506658D01*
Y507732D01*
X1498070Y511002D01*
X1503297D01*
X1505040Y512745D01*
X1512244D01*
X1533451Y533952D01*
X1572920D01*
X1575843Y531029D01*
X1580626D01*
X1594415Y517252D01*
X1606968D01*
X1617616Y527900D01*
X1623701D01*
X1625730Y529929D01*
X1632434D01*
X1634000Y528363D01*
Y522987D01*
X1636553Y520434D01*
X1648552D01*
X1667186Y501800D01*
X1673615D01*
X1676283Y499132D01*
Y490900D01*
X1686377Y480806D01*
X1704139D01*
X1705767Y482434D01*
G01X1472758Y216495D02*
X1463353Y207090D01*
Y204172D01*
X1447026Y187843D01*
X1442303D01*
X1404060Y149600D01*
X1401300D01*
G01X1452699Y404060D02*
X1450750Y402111D01*
Y378300D01*
X1450024Y377574D01*
Y368680D01*
X1437601Y356257D01*
Y331635D01*
X1434946Y328980D01*
Y314068D01*
X1436874Y304419D01*
Y290812D01*
X1430199Y284137D01*
Y272884D01*
X1434700Y268383D01*
Y267366D01*
X1442352Y259714D01*
Y250892D01*
X1440140Y248680D01*
Y242133D01*
X1437583Y239576D01*
X1427527D01*
X1407023Y219072D01*
X1401002D01*
X1400141Y219933D01*
X1393167D01*
X1390899Y217665D01*
X1387254D01*
X1384729Y215140D01*
Y214890D01*
X1384671Y214832D01*
G01X1382200Y606300D02*
Y601801D01*
X1386300Y597701D01*
Y579225D01*
X1382816Y575741D01*
Y575716D01*
X1382500Y575400D01*
G01D02*
X1382280Y575180D01*
Y571219D01*
X1393371Y560128D01*
X1400216D01*
G01X1470382Y188372D02*
X1467712Y185702D01*
Y183170D01*
X1461229Y176687D01*
Y134961D01*
X1460088Y133820D01*
Y111721D01*
X1466184Y105625D01*
Y85593D01*
X1501399Y50378D01*
X1574094D01*
X1580804Y43668D01*
X1657568D01*
X1658600Y44700D01*
G01X1455600Y254826D02*
Y252676D01*
X1450076Y247152D01*
Y239976D01*
X1437504Y227404D01*
X1428206D01*
X1422281Y221479D01*
G01X1503400Y524663D02*
X1502128D01*
X1499291Y527500D01*
X1490550D01*
X1484695Y521645D01*
X1480626D01*
X1478483Y519502D01*
X1473421D01*
X1467019Y513100D01*
X1459565D01*
X1458935Y512470D01*
G01X1476761Y157400D02*
Y167240D01*
X1471388Y172613D01*
Y173700D01*
G01D02*
Y174016D01*
X1478089Y180717D01*
Y182650D01*
G01X1533838Y288706D02*
X1535194D01*
X1536300Y287600D01*
Y283846D01*
X1527175Y274721D01*
Y255651D01*
X1532500Y250326D01*
Y248113D01*
X1532188Y247801D01*
X1532237D01*
G01X1579100Y69000D02*
Y65800D01*
X1586856Y58044D01*
X1613856D01*
X1631412Y75600D01*
X1646756D01*
X1657803Y64553D01*
X1701449D01*
X1702190Y63812D01*
X1726847D01*
X1727722Y62937D01*
X1742402D01*
X1746328Y59011D01*
G01X1535300Y78490D02*
Y97739D01*
X1542274Y104713D01*
X1549187D01*
G01X1543700Y322600D02*
Y320700D01*
X1538450Y315450D01*
Y314300D01*
G01X1534968Y597268D02*
X1535312D01*
X1536848Y595732D01*
X1547732D01*
X1551907Y599907D01*
Y603093D01*
X1549500Y605500D01*
Y609000D01*
X1551500Y611000D01*
X1557000D01*
X1559500Y613500D01*
X1576350D01*
X1579671Y610179D01*
X1579680D01*
Y610279D01*
G01X1617500Y-14500D02*
X1621500Y-10500D01*
X1755500D01*
X1766322Y-21322D01*
X1836966D01*
X1841076Y-17212D01*
Y-2884D01*
X1849714Y5754D01*
X1851882D01*
X1852786Y6658D01*
X1859408D01*
X1867498Y14748D01*
X1868919D01*
X1874685Y20514D01*
Y22914D01*
X1878559Y26788D01*
Y32365D01*
X1876682Y34242D01*
Y40748D01*
X1876683Y40749D01*
Y46087D01*
X1871836Y50934D01*
Y67786D01*
X1878000Y73950D01*
G01X1634500Y113500D02*
X1636000Y112000D01*
Y105500D01*
X1658000Y83500D01*
X1664500D01*
X1665500Y82500D01*
Y81600D01*
G01X1616848Y115449D02*
X1618731Y113566D01*
Y109747D01*
X1617983Y108999D01*
Y100570D01*
X1620324Y98229D01*
Y89730D01*
X1614997Y84403D01*
G01X1598449Y120760D02*
X1592538Y114849D01*
Y108311D01*
X1602949Y97900D01*
X1605300D01*
X1608607Y94593D01*
Y92107D01*
X1604500Y88000D01*
Y83500D01*
X1603600Y82600D01*
X1598399D01*
X1596087Y80288D01*
Y78287D01*
X1594150Y76350D01*
Y74612D01*
X1595340Y73422D01*
X1596731D01*
X1599481Y70672D01*
X1611688D01*
X1612000Y70984D01*
G01X1624292Y106458D02*
Y114491D01*
X1625292Y115491D01*
X1626339D01*
G01X1620900Y81300D02*
Y86955D01*
X1622124Y88179D01*
Y112483D01*
X1620540Y114067D01*
Y119956D01*
X1622349Y121765D01*
X1626364D01*
G01X1720350Y202850D02*
X1711857D01*
X1707566Y198559D01*
Y197498D01*
X1707562Y197494D01*
Y195724D01*
X1705288Y193450D01*
X1702400D01*
G01X1738216Y548239D02*
X1740821Y550844D01*
X1760801D01*
X1768976Y542669D01*
Y539846D01*
X1768977Y539845D01*
Y538335D01*
X1770112Y537200D01*
X1780700D01*
X1781300Y537800D01*
G01X1834100Y523900D02*
X1828700D01*
X1827800Y523000D01*
Y522712D01*
X1826688Y521600D01*
X1826400D01*
X1822610Y517810D01*
X1794790D01*
X1790250Y522350D01*
G01X1903150Y217250D02*
Y216337D01*
X1894855Y208042D01*
X1893238D01*
G54D16*
X3937Y204370D03*
X-3937D03*
X-11811D03*
X35433D03*
X27559D03*
X19685D03*
X3937Y227992D03*
X-3937D03*
X-11811D03*
X35433D03*
X27559D03*
X19685D03*
X3937Y313504D03*
X-3937D03*
X-11811D03*
X3937Y337126D03*
X-3937D03*
X-11811D03*
X35433D03*
X27559D03*
X19685D03*
X35433Y313504D03*
X27559D03*
X19685D03*
G54D35*
G01X1664253Y-43317D02*
X1470600D01*
G03Y-45768I0J-1226D01*
G01X1663765D01*
G02Y-51521I0J-2876D01*
G01X1462786D01*
X1459348Y-48083D01*
X1436432D01*
X1432258Y-52257D01*
G01X1664253Y-41666D02*
X1470600D01*
G03Y-47419I0J-2876D01*
G01X1663765D01*
G02Y-49870I0J-1226D01*
G01X1463470D01*
X1460032Y-46432D01*
X1436433D01*
X1432258Y-42257D01*
G54D26*
G01X716710Y323470D02*
X730700Y309480D01*
Y298300D01*
X735400Y293600D01*
Y267470D01*
X743460Y259410D01*
Y250776D01*
X751576Y242660D01*
Y226339D01*
X754900Y223015D01*
Y213600D01*
X767866Y200634D01*
X779566D01*
X793200Y187000D01*
Y179100D01*
X768584Y154484D01*
Y110884D01*
X765400Y107700D01*
G54D17*
X20512Y467244D03*
X30512D03*
X40512D03*
G54D36*
G01X22835Y101221D02*
X23700D01*
X24890Y100031D01*
Y97683D01*
X26013Y96560D01*
X35525D01*
X45675Y106710D01*
X50770D01*
X51381Y106099D01*
Y104750D01*
G01X-15354Y109095D02*
X-13995D01*
X-13210Y108310D01*
Y106569D01*
X-10884Y104243D01*
X33742D01*
X43149Y113650D01*
X46400D01*
X46900Y113150D01*
Y111750D01*
G01X23228Y109095D02*
X21405D01*
X20920Y109580D01*
Y110579D01*
X22798Y112457D01*
X31055D01*
X31705Y111807D01*
X33055D01*
X33705Y112457D01*
X35055D01*
X37491Y114893D01*
Y117763D01*
X38141Y118413D01*
Y119763D01*
X37491Y120413D01*
Y121763D01*
X40550Y124822D01*
X41469D01*
X42423Y125776D01*
Y126695D01*
X43378Y127650D01*
X46150D01*
X46900Y126900D01*
Y125750D01*
G01X28346Y116969D02*
X26931D01*
X25983Y117917D01*
Y118798D01*
X27816Y120631D01*
X31231D01*
X33746Y123146D01*
Y127341D01*
X34701Y128296D01*
X35620D01*
X36574Y129250D01*
Y130169D01*
X39950Y133545D01*
Y134895D01*
X40600Y135545D01*
Y136895D01*
X39950Y137545D01*
Y139949D01*
X41831Y141830D01*
X46276D01*
X46900Y141206D01*
Y139750D01*
G01X28346Y101221D02*
X27221D01*
X26040Y100040D01*
Y98160D01*
X26490Y97710D01*
X35048D01*
X36713Y99375D01*
Y100294D01*
X37667Y101249D01*
X38587D01*
X39541Y102203D01*
Y103122D01*
X40496Y104077D01*
X41415D01*
X42370Y105032D01*
Y105951D01*
X43324Y106905D01*
X44243D01*
X45198Y107860D01*
X50760D01*
X51381Y108481D01*
Y109750D01*
G01X-9843Y109095D02*
X-11274D01*
X-12060Y108309D01*
Y107046D01*
X-10407Y105393D01*
X33265D01*
X34187Y106315D01*
Y107234D01*
X35141Y108189D01*
X36061D01*
X37015Y109143D01*
Y110062D01*
X37970Y111017D01*
X38889D01*
X39844Y111972D01*
Y112891D01*
X40798Y113845D01*
X41717D01*
X42672Y114800D01*
X46400D01*
X46900Y115300D01*
Y116750D01*
G01X17716Y109095D02*
X19294D01*
X19770Y109571D01*
Y111056D01*
X22321Y113607D01*
X34578D01*
X36341Y115370D01*
Y122240D01*
X42901Y128800D01*
X46160D01*
X46900Y129540D01*
Y130750D01*
G01X22835Y116969D02*
X24269D01*
X24833Y117533D01*
Y119275D01*
X27339Y121781D01*
X30754D01*
X32596Y123623D01*
Y127818D01*
X38800Y134022D01*
Y140426D01*
X41354Y142980D01*
X46280D01*
X46900Y143600D01*
Y144750D01*
G01X251213Y646784D02*
X253638Y649209D01*
X255379D01*
X259834Y648852D01*
X263505Y650019D01*
X264486Y651327D01*
X264730Y652288D01*
X265066Y654198D01*
X265587Y654563D01*
X266621Y654381D01*
X266986Y653859D01*
X265502Y645452D01*
X266415Y644148D01*
X268388Y643799D01*
X269688Y644709D01*
X271373Y654259D01*
X271896Y654626D01*
X272929Y654444D01*
X273293Y653921D01*
X271801Y645467D01*
X272711Y644164D01*
X274685Y643818D01*
X275989Y644728D01*
X277668Y654262D01*
X278190Y654627D01*
X279223Y654446D01*
X279588Y653924D01*
X278097Y645468D01*
X279007Y644165D01*
X280981Y643819D01*
X282285Y644729D01*
X283967Y654281D01*
X284489Y654645D01*
X285522Y654464D01*
X285888Y653944D01*
X284388Y645435D01*
X285298Y644132D01*
X287272Y643785D01*
X288572Y644696D01*
X290263Y654278D01*
X290786Y654646D01*
X291820Y654463D01*
X292185Y653942D01*
X290685Y645434D01*
X291594Y644133D01*
X293567Y643785D01*
X294870Y644695D01*
X296539Y654165D01*
X297062Y654532D01*
X298095Y654351D01*
X298459Y653829D01*
X296982Y645452D01*
X297892Y644149D01*
X299865Y643804D01*
X301168Y644713D01*
X302837Y654169D01*
X303358Y654533D01*
X304390Y654351D01*
X304755Y653829D01*
X303277Y645454D01*
X304188Y644150D01*
X306162Y643804D01*
X307465Y644713D01*
X309132Y654185D01*
X309656Y654550D01*
X310688Y654370D01*
X311053Y653846D01*
X309567Y645421D01*
X310478Y644117D01*
X312452Y643771D01*
X313755Y644680D01*
X315421Y654137D01*
X315981Y654529D01*
X316949Y654359D01*
X317340Y653799D01*
X315863Y645421D01*
X316773Y644118D01*
X318746Y643771D01*
X320049Y644681D01*
X320908Y649553D01*
X321687Y653941D01*
X322209Y654306D01*
X323243Y654124D01*
X323607Y653602D01*
X322130Y645224D01*
X323067Y643882D01*
X324975Y643547D01*
X326315Y644486D01*
X327981Y653942D01*
X328503Y654306D01*
X329538Y654124D01*
X329903Y653602D01*
X328417Y645178D01*
X329328Y643871D01*
X331299Y643527D01*
X332605Y644436D01*
X334271Y653909D01*
X334793Y654273D01*
X335828Y654091D01*
X336193Y653569D01*
X334715Y645194D01*
X335626Y643890D01*
X337597Y643543D01*
X338899Y644453D01*
X340568Y653909D01*
X341090Y654273D01*
X342124Y654092D01*
X342488Y653571D01*
X341011Y645195D01*
X341921Y643890D01*
X343895Y643544D01*
X345198Y644458D01*
X346866Y653927D01*
X347388Y654292D01*
X348422Y654109D01*
X348785Y653587D01*
X347285Y645080D01*
X348197Y643779D01*
X350171Y643430D01*
X351474Y644346D01*
X353164Y653927D01*
X353684Y654291D01*
X354718Y654109D01*
X355082Y653588D01*
X353582Y645077D01*
X354497Y643777D01*
X356466Y643432D01*
X357769Y644341D01*
X359452Y653893D01*
X359975Y654258D01*
X361009Y654076D01*
X361373Y653555D01*
X359882Y645099D01*
X360794Y643795D01*
X362766Y643450D01*
X364069Y644360D01*
X365747Y653894D01*
X366270Y654259D01*
X367305Y654077D01*
X367669Y653556D01*
X366177Y645103D01*
X367086Y643798D01*
X369060Y643450D01*
X370364Y644364D01*
X372048Y653914D01*
X372567Y654277D01*
X373601Y654094D01*
X373968Y653570D01*
X372484Y645164D01*
X373395Y643860D01*
X375369Y643513D01*
X376671Y644425D01*
X377082Y646762D01*
X377259Y647458D01*
X377881Y648288D01*
X380985Y649275D01*
X385260Y648933D01*
X387048D01*
X389473Y646508D01*
G01X251213Y652784D02*
X253638Y650359D01*
X255426D01*
X259701Y650017D01*
X262805Y651004D01*
X263427Y651834D01*
X263604Y652530D01*
X264015Y654867D01*
X265317Y655779D01*
X267291Y655432D01*
X268202Y654128D01*
X266718Y645722D01*
X267085Y645198D01*
X268119Y645015D01*
X268638Y645378D01*
X270322Y654928D01*
X271626Y655842D01*
X273600Y655494D01*
X274509Y654189D01*
X273017Y645736D01*
X273381Y645215D01*
X274416Y645033D01*
X274939Y645398D01*
X276617Y654932D01*
X277920Y655842D01*
X279892Y655497D01*
X280804Y654193D01*
X279313Y645737D01*
X279677Y645216D01*
X280711Y645034D01*
X281234Y645399D01*
X282917Y654951D01*
X284220Y655860D01*
X286189Y655515D01*
X287104Y654215D01*
X285604Y645704D01*
X285968Y645183D01*
X287002Y645001D01*
X287522Y645365D01*
X289212Y654946D01*
X290515Y655862D01*
X292489Y655513D01*
X293401Y654212D01*
X291901Y645705D01*
X292264Y645183D01*
X293298Y645000D01*
X293820Y645365D01*
X295488Y654834D01*
X296791Y655748D01*
X298765Y655402D01*
X299675Y654097D01*
X298198Y645721D01*
X298562Y645200D01*
X299596Y645019D01*
X300118Y645383D01*
X301787Y654839D01*
X303089Y655749D01*
X305060Y655402D01*
X305971Y654098D01*
X304493Y645723D01*
X304858Y645201D01*
X305893Y645019D01*
X306415Y645383D01*
X308081Y654856D01*
X309387Y655765D01*
X311358Y655421D01*
X312269Y654114D01*
X310783Y645690D01*
X311148Y645168D01*
X312183Y644986D01*
X312705Y645350D01*
X314371Y654806D01*
X315711Y655745D01*
X317619Y655410D01*
X318556Y654068D01*
X317079Y645690D01*
X317443Y645168D01*
X318477Y644986D01*
X318999Y645351D01*
X319759Y649663D01*
X320637Y654611D01*
X321940Y655521D01*
X323913Y655174D01*
X324823Y653871D01*
X323346Y645493D01*
X323737Y644933D01*
X324705Y644763D01*
X325265Y645155D01*
X326931Y654612D01*
X328234Y655521D01*
X330208Y655175D01*
X331119Y653871D01*
X329633Y645446D01*
X329998Y644922D01*
X331030Y644742D01*
X331554Y645107D01*
X333221Y654579D01*
X334524Y655488D01*
X336498Y655142D01*
X337409Y653838D01*
X335931Y645463D01*
X336296Y644941D01*
X337328Y644759D01*
X337849Y645123D01*
X339518Y654579D01*
X340821Y655488D01*
X342794Y655143D01*
X343704Y653840D01*
X342227Y645463D01*
X342591Y644941D01*
X343624Y644760D01*
X344147Y645127D01*
X345816Y654597D01*
X347119Y655507D01*
X349092Y655159D01*
X350001Y653858D01*
X348501Y645350D01*
X348866Y644829D01*
X349900Y644646D01*
X350423Y645014D01*
X352114Y654596D01*
X353414Y655507D01*
X355388Y655160D01*
X356298Y653857D01*
X354798Y645348D01*
X355164Y644828D01*
X356197Y644647D01*
X356719Y645011D01*
X358401Y654563D01*
X359705Y655473D01*
X361679Y655127D01*
X362589Y653824D01*
X361098Y645368D01*
X361463Y644846D01*
X362496Y644665D01*
X363018Y645030D01*
X364697Y654564D01*
X366001Y655474D01*
X367975Y655128D01*
X368885Y653825D01*
X367393Y645371D01*
X367757Y644848D01*
X368790Y644666D01*
X369313Y645033D01*
X370998Y654583D01*
X372298Y655493D01*
X374271Y655144D01*
X375184Y653840D01*
X373700Y645433D01*
X374065Y644911D01*
X375099Y644729D01*
X375620Y645094D01*
X375956Y647004D01*
X376200Y647965D01*
X377181Y649273D01*
X380852Y650440D01*
X385307Y650083D01*
X387048D01*
X389473Y652508D01*
G01X1109156Y-43700D02*
X914500D01*
G03Y-46250I0J-1275D01*
G01X1109035D01*
G02Y-51100I0J-2425D01*
G01X909373D01*
X905905Y-47632D01*
X883409D01*
X878984Y-52057D01*
G01X1109156Y-42550D02*
X914500D01*
G03Y-47400I0J-2425D01*
G01X1109035D01*
G02Y-49950I0J-1275D01*
G01X909850D01*
X906382Y-46482D01*
X883409D01*
X878984Y-42057D01*
G01X951795Y652234D02*
Y650259D01*
X952235Y649819D01*
X952713D01*
X953343Y650298D01*
X954105Y651314D01*
X954274Y651980D01*
X954686Y654317D01*
X955987Y655229D01*
X957961Y654882D01*
X958872Y653578D01*
X957388Y645172D01*
X957755Y644648D01*
X958789Y644465D01*
X959308Y644828D01*
X960992Y654378D01*
X962296Y655292D01*
X964270Y654944D01*
X965179Y653639D01*
X963687Y645186D01*
X964051Y644665D01*
X965086Y644483D01*
X965609Y644848D01*
X967287Y654382D01*
X968590Y655292D01*
X970562Y654947D01*
X971474Y653643D01*
X969983Y645187D01*
X970347Y644666D01*
X971381Y644484D01*
X971904Y644849D01*
X973587Y654401D01*
X974890Y655310D01*
X976859Y654965D01*
X977774Y653665D01*
X976274Y645154D01*
X976638Y644633D01*
X977672Y644451D01*
X978192Y644815D01*
X979882Y654396D01*
X981185Y655312D01*
X983159Y654963D01*
X984071Y653662D01*
X982571Y645155D01*
X982934Y644633D01*
X983968Y644450D01*
X984490Y644815D01*
X986158Y654284D01*
X987461Y655198D01*
X989435Y654852D01*
X990345Y653547D01*
X988868Y645171D01*
X989232Y644650D01*
X990266Y644469D01*
X990788Y644833D01*
X992457Y654289D01*
X993759Y655199D01*
X995730Y654852D01*
X996641Y653548D01*
X995163Y645173D01*
X995528Y644651D01*
X996563Y644469D01*
X997085Y644833D01*
X998751Y654306D01*
X1000057Y655215D01*
X1002028Y654871D01*
X1002939Y653564D01*
X1001453Y645140D01*
X1001818Y644618D01*
X1002853Y644436D01*
X1003375Y644800D01*
X1005041Y654256D01*
X1006381Y655195D01*
X1008289Y654860D01*
X1009226Y653518D01*
X1007749Y645140D01*
X1008113Y644618D01*
X1009147Y644436D01*
X1009669Y644801D01*
X1011307Y654060D01*
X1012610Y654971D01*
X1014583Y654623D01*
X1015493Y653319D01*
X1014067Y645234D01*
X1014457Y644674D01*
X1015426Y644504D01*
X1015986Y644896D01*
X1017601Y654062D01*
X1018904Y654971D01*
X1020878Y654625D01*
X1021789Y653321D01*
X1020357Y645204D01*
X1020722Y644680D01*
X1021754Y644500D01*
X1022278Y644865D01*
X1023891Y654029D01*
X1025194Y654938D01*
X1027168Y654592D01*
X1028079Y653288D01*
X1026652Y645204D01*
X1027017Y644682D01*
X1028049Y644500D01*
X1028570Y644864D01*
X1030188Y654029D01*
X1031491Y654938D01*
X1033464Y654593D01*
X1034374Y653290D01*
X1032948Y645204D01*
X1033312Y644682D01*
X1034345Y644501D01*
X1034868Y644868D01*
X1036486Y654047D01*
X1037789Y654957D01*
X1039762Y654609D01*
X1040671Y653308D01*
X1039225Y645108D01*
X1039590Y644587D01*
X1040624Y644404D01*
X1041147Y644772D01*
X1042784Y654046D01*
X1044084Y654957D01*
X1046058Y654610D01*
X1046968Y653307D01*
X1045536Y645186D01*
X1045902Y644666D01*
X1046935Y644485D01*
X1047457Y644849D01*
X1049071Y654013D01*
X1050375Y654923D01*
X1052349Y654577D01*
X1053259Y653274D01*
X1051836Y645206D01*
X1052201Y644684D01*
X1053234Y644503D01*
X1053756Y644868D01*
X1055367Y654014D01*
X1056671Y654924D01*
X1058645Y654578D01*
X1059555Y653275D01*
X1058131Y645208D01*
X1058496Y644685D01*
X1059528Y644504D01*
X1060052Y644871D01*
X1061668Y654033D01*
X1062968Y654943D01*
X1064941Y654594D01*
X1065854Y653290D01*
X1064421Y645174D01*
X1064786Y644652D01*
X1065820Y644470D01*
X1066341Y644835D01*
X1067956Y654001D01*
X1069259Y654910D01*
X1071233Y654564D01*
X1072144Y653260D01*
X1070712Y645143D01*
X1071077Y644619D01*
X1072109Y644439D01*
X1072633Y644804D01*
X1074246Y653968D01*
X1075549Y654877D01*
X1077523Y654531D01*
X1078434Y653227D01*
X1077007Y645143D01*
X1077372Y644621D01*
X1078404Y644439D01*
X1078925Y644803D01*
X1080543Y653968D01*
X1081846Y654877D01*
X1083819Y654532D01*
X1084729Y653229D01*
X1083303Y645143D01*
X1083667Y644621D01*
X1084700Y644440D01*
X1085223Y644807D01*
X1086841Y653986D01*
X1088144Y654896D01*
X1090117Y654548D01*
X1091026Y653247D01*
X1089594Y645127D01*
X1089959Y644606D01*
X1090993Y644423D01*
X1091517Y644791D01*
X1093139Y653985D01*
X1094439Y654896D01*
X1096413Y654549D01*
X1097323Y653246D01*
X1095891Y645125D01*
X1096257Y644605D01*
X1097290Y644424D01*
X1097812Y644788D01*
X1099426Y653952D01*
X1100730Y654862D01*
X1102704Y654516D01*
X1103614Y653213D01*
X1102194Y645162D01*
X1102559Y644640D01*
X1103592Y644459D01*
X1104114Y644824D01*
X1105722Y653953D01*
X1107026Y654863D01*
X1109000Y654517D01*
X1109910Y653214D01*
X1108486Y645147D01*
X1108851Y644624D01*
X1109883Y644443D01*
X1110407Y644810D01*
X1112023Y653972D01*
X1113323Y654882D01*
X1115296Y654533D01*
X1116209Y653229D01*
X1114794Y645210D01*
X1115159Y644687D01*
X1116192Y644506D01*
X1116714Y644871D01*
X1118330Y654033D01*
X1119630Y654943D01*
X1121603Y654594D01*
X1122516Y653290D01*
X1121103Y645288D01*
X1121468Y644766D01*
X1122502Y644584D01*
X1123023Y644949D01*
X1124637Y654094D01*
X1125937Y655004D01*
X1127910Y654655D01*
X1128823Y653351D01*
X1127390Y645235D01*
X1127755Y644713D01*
X1128789Y644531D01*
X1129310Y644896D01*
X1130944Y654155D01*
X1132244Y655065D01*
X1134217Y654716D01*
X1135130Y653412D01*
X1133697Y645296D01*
X1134062Y644774D01*
X1135096Y644592D01*
X1135617Y644957D01*
X1137270Y654303D01*
X1138576Y655216D01*
X1140549Y654868D01*
X1141459Y653564D01*
X1139983Y645191D01*
X1140374Y644631D01*
X1141342Y644461D01*
X1141902Y644853D01*
X1143568Y654310D01*
X1144871Y655219D01*
X1146845Y654873D01*
X1147756Y653569D01*
X1146270Y645144D01*
X1146635Y644620D01*
X1147667Y644440D01*
X1148191Y644805D01*
X1149858Y654277D01*
X1151161Y655186D01*
X1153135Y654840D01*
X1154046Y653536D01*
X1152568Y645161D01*
X1152933Y644639D01*
X1153965Y644457D01*
X1154486Y644821D01*
X1156155Y654277D01*
X1157458Y655186D01*
X1159431Y654841D01*
X1160341Y653538D01*
X1158864Y645161D01*
X1159228Y644639D01*
X1160261Y644458D01*
X1160784Y644825D01*
X1162453Y654295D01*
X1163756Y655205D01*
X1165729Y654857D01*
X1166638Y653556D01*
X1165138Y645048D01*
X1165503Y644527D01*
X1166537Y644344D01*
X1167060Y644712D01*
X1168751Y654294D01*
X1170051Y655205D01*
X1172025Y654858D01*
X1172935Y653555D01*
X1171435Y645046D01*
X1171801Y644526D01*
X1172834Y644345D01*
X1173356Y644709D01*
X1175038Y654261D01*
X1176342Y655171D01*
X1178316Y654825D01*
X1179226Y653522D01*
X1177735Y645066D01*
X1178100Y644544D01*
X1179133Y644363D01*
X1179655Y644728D01*
X1181334Y654262D01*
X1182638Y655172D01*
X1184612Y654826D01*
X1185522Y653523D01*
X1184030Y645069D01*
X1184394Y644546D01*
X1185427Y644364D01*
X1185950Y644731D01*
X1187635Y654281D01*
X1188935Y655191D01*
X1190908Y654842D01*
X1191821Y653538D01*
X1190337Y645131D01*
X1190702Y644609D01*
X1191736Y644427D01*
X1192258Y644792D01*
X1192593Y646702D01*
X1192968Y648179D01*
X1193545Y648948D01*
X1194673Y649879D01*
X1195793Y649827D01*
X1196198Y650231D01*
Y652206D01*
G01Y646206D02*
Y648181D01*
X1195700Y648679D01*
X1195063Y648709D01*
X1194384Y648148D01*
X1194027Y647672D01*
X1193719Y646460D01*
X1193308Y644123D01*
X1192006Y643211D01*
X1190032Y643558D01*
X1189121Y644862D01*
X1190605Y653268D01*
X1190238Y653792D01*
X1189204Y653975D01*
X1188685Y653612D01*
X1187001Y644062D01*
X1185697Y643148D01*
X1183723Y643496D01*
X1182814Y644801D01*
X1184306Y653254D01*
X1183942Y653775D01*
X1182907Y653957D01*
X1182384Y653592D01*
X1180706Y644058D01*
X1179403Y643148D01*
X1177431Y643493D01*
X1176519Y644797D01*
X1178010Y653253D01*
X1177646Y653774D01*
X1176612Y653956D01*
X1176089Y653591D01*
X1174406Y644039D01*
X1173103Y643130D01*
X1171134Y643475D01*
X1170219Y644775D01*
X1171719Y653286D01*
X1171355Y653807D01*
X1170321Y653989D01*
X1169801Y653625D01*
X1168111Y644044D01*
X1166808Y643128D01*
X1164834Y643477D01*
X1163922Y644778D01*
X1165422Y653285D01*
X1165059Y653807D01*
X1164025Y653990D01*
X1163503Y653625D01*
X1161835Y644156D01*
X1160532Y643242D01*
X1158558Y643588D01*
X1157648Y644893D01*
X1159125Y653269D01*
X1158761Y653790D01*
X1157727Y653971D01*
X1157205Y653607D01*
X1155536Y644151D01*
X1154234Y643241D01*
X1152263Y643588D01*
X1151352Y644892D01*
X1152830Y653267D01*
X1152465Y653789D01*
X1151430Y653971D01*
X1150908Y653607D01*
X1149242Y644134D01*
X1147936Y643225D01*
X1145965Y643569D01*
X1145054Y644876D01*
X1146540Y653300D01*
X1146175Y653822D01*
X1145140Y654004D01*
X1144618Y653640D01*
X1142952Y644184D01*
X1141612Y643245D01*
X1139704Y643580D01*
X1138767Y644922D01*
X1140243Y653296D01*
X1139879Y653818D01*
X1138845Y654000D01*
X1138320Y653633D01*
X1136667Y644287D01*
X1135366Y643376D01*
X1133392Y643723D01*
X1132481Y645027D01*
X1133914Y653142D01*
X1133547Y653666D01*
X1132513Y653849D01*
X1131994Y653486D01*
X1130361Y644227D01*
X1129059Y643315D01*
X1127085Y643662D01*
X1126174Y644966D01*
X1127607Y653081D01*
X1127240Y653605D01*
X1126206Y653788D01*
X1125687Y653425D01*
X1124074Y644280D01*
X1122772Y643368D01*
X1120798Y643715D01*
X1119887Y645019D01*
X1121300Y653020D01*
X1120933Y653544D01*
X1119899Y653727D01*
X1119380Y653364D01*
X1117764Y644202D01*
X1116462Y643290D01*
X1114488Y643637D01*
X1113577Y644940D01*
X1114993Y652959D01*
X1114626Y653483D01*
X1113592Y653666D01*
X1113073Y653303D01*
X1111457Y644141D01*
X1110153Y643227D01*
X1108179Y643575D01*
X1107270Y644879D01*
X1108694Y652945D01*
X1108330Y653466D01*
X1107295Y653648D01*
X1106772Y653283D01*
X1105165Y644154D01*
X1103862Y643244D01*
X1101890Y643589D01*
X1100978Y644893D01*
X1102398Y652944D01*
X1102034Y653465D01*
X1101000Y653647D01*
X1100477Y653282D01*
X1098862Y644118D01*
X1097559Y643209D01*
X1095590Y643554D01*
X1094675Y644854D01*
X1096107Y652977D01*
X1095743Y653498D01*
X1094709Y653680D01*
X1094189Y653316D01*
X1092568Y644123D01*
X1091264Y643207D01*
X1089290Y643556D01*
X1088378Y644857D01*
X1089810Y652976D01*
X1089447Y653498D01*
X1088413Y653681D01*
X1087891Y653316D01*
X1086274Y644138D01*
X1084971Y643224D01*
X1082997Y643570D01*
X1082087Y644875D01*
X1083513Y652960D01*
X1083149Y653481D01*
X1082115Y653662D01*
X1081593Y653298D01*
X1079975Y644133D01*
X1078673Y643223D01*
X1076702Y643570D01*
X1075791Y644874D01*
X1077218Y652958D01*
X1076853Y653480D01*
X1075818Y653662D01*
X1075296Y653298D01*
X1073684Y644133D01*
X1072378Y643224D01*
X1070407Y643568D01*
X1069496Y644875D01*
X1070928Y652991D01*
X1070563Y653513D01*
X1069528Y653695D01*
X1069006Y653331D01*
X1067391Y644166D01*
X1066090Y643254D01*
X1064116Y643601D01*
X1063205Y644905D01*
X1064638Y653020D01*
X1064271Y653544D01*
X1063237Y653727D01*
X1062718Y653364D01*
X1061102Y644202D01*
X1059798Y643288D01*
X1057824Y643636D01*
X1056915Y644940D01*
X1058339Y653006D01*
X1057975Y653527D01*
X1056940Y653709D01*
X1056417Y653344D01*
X1054807Y644198D01*
X1053504Y643288D01*
X1051532Y643633D01*
X1050620Y644937D01*
X1052043Y653005D01*
X1051679Y653526D01*
X1050645Y653708D01*
X1050122Y653343D01*
X1048507Y644179D01*
X1047204Y643270D01*
X1045235Y643615D01*
X1044320Y644915D01*
X1045752Y653038D01*
X1045388Y653559D01*
X1044354Y653741D01*
X1043834Y653377D01*
X1042198Y644104D01*
X1040895Y643188D01*
X1038921Y643537D01*
X1038009Y644838D01*
X1039455Y653037D01*
X1039092Y653559D01*
X1038058Y653742D01*
X1037536Y653377D01*
X1035919Y644199D01*
X1034616Y643285D01*
X1032642Y643631D01*
X1031732Y644936D01*
X1033158Y653021D01*
X1032794Y653542D01*
X1031760Y653723D01*
X1031238Y653359D01*
X1029620Y644194D01*
X1028318Y643284D01*
X1026347Y643631D01*
X1025436Y644935D01*
X1026863Y653019D01*
X1026498Y653541D01*
X1025463Y653723D01*
X1024941Y653359D01*
X1023329Y644194D01*
X1022023Y643285D01*
X1020052Y643629D01*
X1019141Y644936D01*
X1020573Y653052D01*
X1020208Y653574D01*
X1019173Y653756D01*
X1018651Y653392D01*
X1017036Y644227D01*
X1015696Y643288D01*
X1013788Y643623D01*
X1012851Y644965D01*
X1014277Y653051D01*
X1013913Y653573D01*
X1012879Y653755D01*
X1012357Y653390D01*
X1010719Y644131D01*
X1009416Y643221D01*
X1007443Y643568D01*
X1006533Y644871D01*
X1008010Y653249D01*
X1007619Y653809D01*
X1006651Y653979D01*
X1006091Y653587D01*
X1004425Y644130D01*
X1003122Y643221D01*
X1001148Y643567D01*
X1000237Y644871D01*
X1001723Y653296D01*
X1001358Y653820D01*
X1000326Y654000D01*
X999802Y653635D01*
X998135Y644163D01*
X996832Y643254D01*
X994858Y643600D01*
X993947Y644904D01*
X995425Y653279D01*
X995060Y653801D01*
X994028Y653983D01*
X993507Y653619D01*
X991838Y644163D01*
X990535Y643254D01*
X988562Y643599D01*
X987652Y644902D01*
X989129Y653279D01*
X988765Y653801D01*
X987732Y653982D01*
X987209Y653615D01*
X985540Y644145D01*
X984237Y643235D01*
X982264Y643583D01*
X981355Y644884D01*
X982855Y653392D01*
X982490Y653913D01*
X981456Y654096D01*
X980933Y653728D01*
X979242Y644146D01*
X977942Y643235D01*
X975968Y643582D01*
X975058Y644885D01*
X976558Y653394D01*
X976192Y653914D01*
X975159Y654095D01*
X974637Y653731D01*
X972955Y644179D01*
X971651Y643269D01*
X969677Y643615D01*
X968767Y644918D01*
X970258Y653374D01*
X969893Y653896D01*
X968860Y654077D01*
X968338Y653712D01*
X966659Y644178D01*
X965355Y643268D01*
X963381Y643614D01*
X962471Y644917D01*
X963963Y653371D01*
X963599Y653894D01*
X962566Y654076D01*
X962043Y653709D01*
X960358Y644159D01*
X959058Y643249D01*
X957085Y643598D01*
X956172Y644902D01*
X957656Y653309D01*
X957291Y653831D01*
X956257Y654013D01*
X955736Y653648D01*
X955400Y651738D01*
X955164Y650808D01*
X954167Y649479D01*
X953101Y648669D01*
X952255D01*
X951795Y648209D01*
Y646234D01*
G01X1420075Y388402D02*
Y389825D01*
X1419623Y390277D01*
X1417976D01*
X1415720Y388021D01*
X1414770Y386597D01*
X1411562Y370566D01*
X1412133Y367716D01*
X1414415Y364292D01*
X1416899Y362632D01*
X1420962Y356537D01*
X1422755Y347587D01*
X1420048Y334047D01*
X1420448Y332046D01*
X1419241Y326006D01*
X1423168Y306375D01*
X1423078Y305922D01*
X1422033Y300695D01*
X1419877Y297461D01*
X1411300Y295747D01*
X1404498Y297107D01*
X1395346Y295276D01*
X1386147Y297116D01*
X1371250Y294137D01*
X1360062Y296375D01*
X1348018Y293966D01*
X1343359Y294898D01*
X1333560Y298959D01*
X1323897Y313454D01*
X1301686Y328260D01*
X1265031Y335590D01*
X1225939Y327772D01*
X1225917Y327750D01*
X1214360D01*
G01X1213545Y330650D02*
X1224138D01*
X1224160Y330672D01*
X1263757Y338593D01*
X1340844Y323175D01*
X1352662Y325538D01*
X1361038Y323864D01*
X1367234Y325104D01*
X1370466Y324457D01*
X1381365Y326637D01*
X1382605Y326388D01*
X1387698Y322993D01*
X1392184Y322095D01*
X1400198Y323698D01*
X1410419Y330518D01*
X1413047Y334462D01*
X1414626Y342354D01*
X1411347Y358756D01*
X1407151Y368861D01*
X1409441Y380308D01*
X1408251Y386258D01*
X1409426Y392127D01*
X1410226Y392927D01*
X1412110D01*
X1413735Y391302D01*
G01X1221613Y321326D02*
X1224915D01*
X1265369Y329414D01*
X1298095Y322868D01*
X1321088Y307542D01*
X1328588Y296292D01*
X1328589Y296289D01*
X1328588D01*
X1331612Y289668D01*
X1333360Y288503D01*
X1333583Y288458D01*
Y288459D01*
X1337431Y287688D01*
X1341605Y288523D01*
X1346141Y287615D01*
X1359832Y290353D01*
X1371891Y287941D01*
X1387120Y290987D01*
X1394545Y289502D01*
X1405279Y291650D01*
X1412151Y290276D01*
X1423197Y292486D01*
X1425139Y295399D01*
Y295400D01*
X1426558Y297528D01*
X1427377Y301623D01*
X1428343Y306448D01*
X1424546Y325434D01*
X1426773Y336561D01*
X1426772Y336563D01*
X1428685Y346127D01*
X1425305Y363026D01*
X1427799Y375488D01*
X1424767Y380033D01*
X1423050Y381750D01*
X1420625D01*
X1420075Y382300D01*
Y383375D01*
G01X1420515Y368585D02*
Y369813D01*
X1419829Y370499D01*
X1417300D01*
X1416221Y369420D01*
X1415800Y368409D01*
Y366931D01*
X1417306Y365426D01*
X1417983Y365290D01*
X1418629Y365161D01*
X1423614Y357689D01*
X1425482Y348333D01*
X1422644Y334149D01*
X1423096Y331898D01*
X1421855Y325690D01*
X1424540Y312268D01*
X1425673Y306600D01*
X1425685Y306542D01*
X1425688Y306525D01*
X1425718Y306375D01*
X1425745Y306357D01*
Y306356D01*
X1425733Y306302D01*
X1425748Y306225D01*
X1425252Y303748D01*
X1424430Y299638D01*
X1421187Y294773D01*
X1411973Y292930D01*
X1404644Y294395D01*
X1394736Y292412D01*
X1387037Y293952D01*
X1371956Y290937D01*
X1360067Y293316D01*
X1348403Y290984D01*
X1343286Y292006D01*
X1331232Y297006D01*
X1330963Y297410D01*
X1321721Y311276D01*
X1300371Y325509D01*
X1264442Y332695D01*
X1225177Y324843D01*
X1225155Y324821D01*
X1213087D01*
G01X1420075Y393402D02*
Y392074D01*
X1419428Y391427D01*
X1417499D01*
X1414826Y388754D01*
X1413687Y387046D01*
X1410389Y370566D01*
X1411050Y367267D01*
X1413585Y363463D01*
X1416069Y361803D01*
X1419879Y356088D01*
X1421582Y347587D01*
X1418875Y334047D01*
X1419275Y332046D01*
X1418068Y326005D01*
X1421837Y307163D01*
X1421995Y306375D01*
X1420949Y301144D01*
X1419184Y298496D01*
X1411300Y296920D01*
X1404498Y298280D01*
X1395346Y296449D01*
X1386147Y298289D01*
X1371250Y295310D01*
X1360062Y297548D01*
X1348018Y295139D01*
X1343695Y296004D01*
X1334323Y299889D01*
Y299888D01*
X1324727Y314284D01*
X1302135Y329343D01*
X1265031Y336763D01*
X1225714Y328900D01*
X1214360D01*
G01X1213545Y331800D02*
X1223935D01*
X1263757Y339766D01*
X1340844Y324348D01*
X1352662Y326711D01*
X1361038Y325037D01*
X1367234Y326277D01*
X1370466Y325630D01*
X1381365Y327810D01*
X1383054Y327471D01*
X1383243Y327346D01*
Y327345D01*
X1388147Y324076D01*
X1392184Y323268D01*
X1399749Y324781D01*
X1409589Y331347D01*
X1411964Y334911D01*
X1413453Y342354D01*
X1410241Y358419D01*
X1405954Y368743D01*
X1408268Y380308D01*
X1407078Y386258D01*
X1408366Y392694D01*
X1409749Y394077D01*
X1411510D01*
X1413735Y396302D01*
G01X1221613Y322476D02*
X1224801D01*
X1265369Y330587D01*
X1298544Y323951D01*
X1305276Y319464D01*
X1306178Y319645D01*
X1307301Y318896D01*
X1307482Y317995D01*
X1308605Y317246D01*
Y317245D01*
X1309507Y317426D01*
X1310630Y316677D01*
X1310811Y315776D01*
X1311934Y315027D01*
X1312835Y315207D01*
X1313958Y314458D01*
X1314139Y313557D01*
X1315262Y312808D01*
X1316163Y312989D01*
X1317286Y312240D01*
X1317467Y311339D01*
X1318590Y310590D01*
X1319491Y310771D01*
X1320614Y310022D01*
X1320795Y309121D01*
X1321918Y308372D01*
X1329598Y296851D01*
X1329636Y296768D01*
X1332522Y290444D01*
X1333809Y289587D01*
X1337431Y288861D01*
X1341605Y289696D01*
X1346141Y288788D01*
X1359832Y291526D01*
X1371891Y289114D01*
X1387120Y292160D01*
X1394545Y290675D01*
X1405279Y292823D01*
X1412151Y291449D01*
X1422504Y293521D01*
X1423989Y295748D01*
Y295749D01*
X1425475Y297977D01*
X1426400Y302600D01*
X1427170Y306448D01*
X1423373Y325434D01*
X1425567Y336400D01*
X1425566Y336402D01*
X1427512Y346127D01*
X1425822Y354576D01*
X1424132Y363026D01*
X1426577Y375246D01*
X1423873Y379300D01*
X1422573Y380600D01*
X1420625D01*
X1420075Y380050D01*
Y378375D01*
G01X1213087Y325971D02*
X1224952D01*
X1264442Y333868D01*
X1300820Y326592D01*
X1322551Y312106D01*
X1331996Y297935D01*
X1343622Y293112D01*
X1348403Y292157D01*
X1360067Y294489D01*
X1371956Y292110D01*
X1387037Y295125D01*
X1394736Y293585D01*
X1404644Y295568D01*
X1411973Y294103D01*
X1420494Y295808D01*
X1423347Y300087D01*
X1424275Y304725D01*
X1424575Y306225D01*
X1424563Y306283D01*
X1424559Y306303D01*
X1424557Y306312D01*
X1424555Y306326D01*
X1424546Y306371D01*
X1423412Y312042D01*
X1420682Y325690D01*
X1421923Y331899D01*
X1421921Y331900D01*
X1421471Y334149D01*
X1424309Y348333D01*
X1422530Y357240D01*
X1417983Y364056D01*
X1417936Y364126D01*
X1416738Y364366D01*
X1414650Y366454D01*
Y368640D01*
X1414948Y369356D01*
X1414947D01*
X1415246Y370073D01*
X1415500Y370327D01*
X1416823Y371649D01*
X1419779D01*
X1420515Y372385D01*
Y373585D01*
G01X1448000Y431500D02*
Y433325D01*
X1447650Y433675D01*
X1442916D01*
X1442593Y433352D01*
X1441244D01*
X1440921Y433675D01*
X1438630D01*
X1434398Y430958D01*
X1434397Y430957D01*
X1423781Y407780D01*
X1411909Y399257D01*
X1406498Y395320D01*
X1404789Y386775D01*
X1404817Y386634D01*
Y386635D01*
X1405804Y381704D01*
X1403772Y368805D01*
X1405971Y363500D01*
X1406572Y362051D01*
X1409347Y348168D01*
X1406207Y340417D01*
X1404822Y333501D01*
X1402535Y330068D01*
X1396856Y326282D01*
X1392783Y325467D01*
X1388433Y326333D01*
X1383682Y329502D01*
X1381651Y329909D01*
X1370390Y327655D01*
X1366521Y328429D01*
X1361948Y327515D01*
X1353579Y329188D01*
X1352856Y329043D01*
X1340206Y326511D01*
X1263018Y341944D01*
X1226295Y334600D01*
X1216000D01*
G01X1431900Y437100D02*
X1432500Y437700D01*
Y438825D01*
X1432001Y439324D01*
X1426422D01*
X1424828Y436933D01*
X1423295Y429268D01*
X1425357Y418957D01*
X1425414Y418673D01*
X1425550Y418306D01*
X1421934Y410411D01*
X1421335Y409103D01*
X1404169Y396779D01*
X1402140Y386631D01*
X1402972Y382476D01*
X1400813Y368773D01*
X1404286Y360393D01*
X1404309Y360282D01*
X1404308D01*
X1406217Y350734D01*
X1401020Y338184D01*
X1393766Y333384D01*
X1390749Y332780D01*
X1373515Y336285D01*
X1370130Y334878D01*
X1366336Y335636D01*
X1359213Y334215D01*
X1357221Y332889D01*
X1339531Y329350D01*
X1262559Y344742D01*
X1224668Y337368D01*
X1215194D01*
G01X1447700Y442500D02*
Y444225D01*
X1447250Y444675D01*
X1429198D01*
X1425069Y443850D01*
X1422038Y439303D01*
X1421146Y434840D01*
Y434839D01*
X1420254Y430378D01*
X1422537Y418958D01*
X1422701Y418139D01*
X1419429Y411000D01*
X1401791Y398341D01*
X1399485Y386804D01*
X1400147Y383491D01*
X1397897Y369205D01*
X1401787Y359821D01*
X1403544Y350985D01*
X1398963Y339925D01*
X1393141Y336071D01*
X1390196Y335468D01*
X1376803Y338194D01*
X1373610Y340309D01*
X1371398Y340751D01*
X1369243Y340355D01*
X1360995Y341661D01*
X1352995Y339157D01*
X1348070Y340142D01*
X1329904Y336509D01*
X1319644Y340068D01*
X1309533Y338046D01*
X1261854Y347583D01*
X1234159Y342199D01*
X1234138Y342178D01*
X1226543D01*
G01X1448000Y437000D02*
Y435199D01*
X1447626Y434825D01*
X1438292D01*
X1433600Y431813D01*
X1433492Y431744D01*
X1422860Y408535D01*
X1411235Y400189D01*
X1405458Y395986D01*
X1403615Y386777D01*
X1404635Y381680D01*
X1402585Y368664D01*
X1405466Y361715D01*
X1408151Y348281D01*
X1405100Y340749D01*
X1403739Y333950D01*
X1401705Y330898D01*
X1396407Y327365D01*
X1392782Y326640D01*
X1388882Y327417D01*
X1384131Y330585D01*
X1381651Y331082D01*
X1370390Y328828D01*
X1366521Y329602D01*
X1361948Y328688D01*
X1353577Y330362D01*
X1352856Y330218D01*
X1340206Y327684D01*
X1263018Y343117D01*
X1226181Y335750D01*
X1216000D01*
G01X1431900Y442600D02*
X1432500Y442000D01*
Y440875D01*
X1432099Y440474D01*
X1425806D01*
X1423745Y437382D01*
X1422122Y429268D01*
X1424184Y418958D01*
X1424305Y418351D01*
X1420416Y409859D01*
X1403130Y397449D01*
X1403040Y397004D01*
X1403041D01*
X1400967Y386631D01*
X1401803Y382452D01*
X1399626Y368632D01*
X1403180Y360057D01*
X1405020Y350851D01*
X1400092Y338949D01*
X1393319Y334468D01*
X1390751Y333954D01*
X1373399Y337483D01*
X1370012Y336075D01*
X1366336Y336809D01*
X1358765Y335299D01*
X1356772Y333973D01*
X1339531Y330523D01*
X1262562Y345915D01*
X1224557Y338518D01*
X1215194D01*
G01X1447500Y448000D02*
Y446175D01*
X1447150Y445825D01*
X1429084D01*
X1424376Y444885D01*
X1420955Y439752D01*
X1419081Y430378D01*
X1419125Y430153D01*
X1419126D01*
X1421364Y418959D01*
X1421500Y418279D01*
X1421499D01*
X1418510Y411757D01*
X1417983Y411379D01*
X1400752Y399011D01*
X1400683Y398666D01*
X1398312Y386804D01*
X1398979Y383467D01*
X1396710Y369064D01*
X1400681Y359485D01*
X1402348Y351103D01*
X1398035Y340690D01*
X1392692Y337153D01*
X1390195Y336642D01*
X1377252Y339277D01*
X1374057Y341393D01*
X1371407Y341922D01*
X1369229Y341522D01*
X1360909Y342840D01*
X1352932Y340343D01*
X1352856Y340358D01*
X1348070Y341315D01*
X1330963Y337895D01*
X1329985Y337699D01*
X1319725Y341258D01*
X1309533Y339219D01*
X1261857Y348756D01*
X1233940Y343328D01*
X1226543D01*
G01X1431900Y448000D02*
X1432500Y448600D01*
Y449825D01*
X1432100Y450225D01*
X1428602D01*
X1424657Y449435D01*
X1419673Y441960D01*
Y441959D01*
X1417334Y430264D01*
X1417983Y427019D01*
X1419595Y418960D01*
X1419739Y418240D01*
X1417983Y414407D01*
X1417215Y412731D01*
X1399127Y399748D01*
X1398910Y398666D01*
X1396724Y387740D01*
X1397436Y384180D01*
X1394585Y369915D01*
X1399179Y358830D01*
X1399202Y358718D01*
X1399201D01*
X1400733Y351075D01*
X1397064Y342012D01*
X1394648Y340412D01*
Y340413D01*
X1392345Y338888D01*
X1389226Y338246D01*
X1378895Y340341D01*
X1370685Y345774D01*
X1369803Y345951D01*
X1367776Y345547D01*
Y345546D01*
X1365752Y345144D01*
X1358665Y346561D01*
X1356631Y346154D01*
X1354219Y344546D01*
X1335554Y340811D01*
X1326342Y344595D01*
X1308423Y341012D01*
X1256111Y351475D01*
X1233368Y346773D01*
X1233345Y346750D01*
X1214500D01*
G01X1431900Y453500D02*
X1432500Y452900D01*
Y451725D01*
X1432150Y451375D01*
X1428487D01*
X1423964Y450470D01*
X1418590Y442409D01*
X1416161Y430264D01*
X1417983Y421155D01*
X1418538Y418380D01*
X1416296Y413488D01*
X1398088Y400418D01*
X1397737Y398666D01*
X1395551Y387740D01*
X1396263Y384180D01*
X1393388Y369798D01*
X1398073Y358493D01*
X1399537Y351187D01*
X1396131Y342775D01*
X1391895Y339970D01*
X1389224Y339420D01*
X1379343Y341424D01*
X1371132Y346858D01*
X1369804Y347124D01*
X1365752Y346317D01*
X1358665Y347734D01*
X1356182Y347237D01*
X1353770Y345629D01*
X1344721Y343819D01*
X1344720D01*
X1335669Y342008D01*
X1326457Y345792D01*
X1308423Y342185D01*
X1256107Y352649D01*
X1233136Y347900D01*
X1214500D01*
G01X1204474Y394523D02*
X1205676Y395726D01*
X1226614Y405152D01*
X1251772Y430310D01*
X1265051D01*
X1282260Y447519D01*
Y455946D01*
X1295960Y469646D01*
X1302230D01*
X1316452Y483868D01*
X1337650D01*
X1345767Y485543D01*
X1355106Y483728D01*
X1359186Y479648D01*
X1366856D01*
X1374359Y481107D01*
X1381862Y479648D01*
X1383820D01*
X1388369Y480533D01*
X1394952Y484972D01*
X1401534Y489410D01*
X1404493Y493799D01*
X1414679Y498949D01*
X1424454D01*
X1446142Y507940D01*
X1457143Y518941D01*
X1463326D01*
X1469316Y522908D01*
X1476850Y524440D01*
X1482103Y527918D01*
X1486348Y528768D01*
X1502872Y539704D01*
X1527022Y544615D01*
X1538061D01*
X1552427Y548529D01*
X1573093Y544753D01*
X1595652D01*
X1621916Y539589D01*
X1634591Y542514D01*
X1640200Y541243D01*
X1642315Y541751D01*
X1642316D01*
X1655533Y535988D01*
X1664138Y520721D01*
X1668958Y517631D01*
X1682809Y514390D01*
X1697155Y504692D01*
X1702298Y490538D01*
X1738940Y475360D01*
X1745294Y474096D01*
X1745295Y474097D01*
X1751650Y472833D01*
X1752142Y473163D01*
X1753469Y472898D01*
X1753798Y472405D01*
X1755149Y472136D01*
X1755678Y472491D01*
X1757005Y472226D01*
X1757359Y471696D01*
X1760353Y471100D01*
X1762500D01*
X1763756Y472356D01*
Y474780D01*
X1762881Y475655D01*
X1761700D01*
G01X1201192Y395208D02*
X1204864Y398880D01*
X1224136Y406863D01*
X1251133Y433860D01*
X1264553D01*
X1279760Y449067D01*
Y456983D01*
X1295802Y473025D01*
X1301940D01*
X1315286Y486368D01*
X1336214D01*
X1357213Y490637D01*
X1379013D01*
X1382172Y491251D01*
X1384954Y490711D01*
X1387703Y491245D01*
X1391246Y490556D01*
X1394051Y491102D01*
X1400440Y495411D01*
X1414134Y501530D01*
X1423869D01*
X1444411Y510038D01*
X1455873Y521500D01*
X1461408D01*
X1464592Y522822D01*
X1473313Y531541D01*
Y534337D01*
X1476483Y537507D01*
X1494982D01*
X1502310Y542358D01*
X1525688Y547115D01*
X1537726D01*
X1552318Y551092D01*
X1573290Y547259D01*
X1595897D01*
X1621703Y542185D01*
X1634423Y545122D01*
X1640184Y543815D01*
X1642571Y544389D01*
X1657303Y537965D01*
X1666019Y522500D01*
X1669752Y520105D01*
X1683655Y516852D01*
X1695714Y508699D01*
X1707444Y505342D01*
X1715610Y487977D01*
X1736325Y479395D01*
X1744695Y477721D01*
X1760192Y480816D01*
Y480817D01*
X1761568Y480552D01*
X1762329Y481068D01*
X1763655Y480813D01*
X1764170Y480052D01*
X1768599Y479201D01*
X1770453Y477347D01*
Y475236D01*
X1770887Y474802D01*
Y473452D01*
X1770453Y473018D01*
Y471777D01*
X1771810Y470420D01*
X1775392D01*
X1776200Y471228D01*
Y474421D01*
X1775566Y475055D01*
X1774300D01*
G01X1200900Y410100D02*
X1206734D01*
X1218464Y414963D01*
X1247001Y443511D01*
X1255611D01*
X1282850Y470750D01*
Y481017D01*
X1285076Y483243D01*
Y484162D01*
X1286031Y485117D01*
X1286950D01*
X1287905Y486072D01*
Y486991D01*
X1288859Y487945D01*
X1289778D01*
X1290733Y488900D01*
X1297510Y490234D01*
X1315460Y495845D01*
X1342999D01*
X1350505Y497305D01*
X1353680Y502011D01*
X1358706Y505401D01*
X1366893Y506991D01*
X1371665Y505390D01*
X1386783Y508271D01*
X1394084Y506391D01*
Y506390D01*
X1401389Y504508D01*
X1411903Y509200D01*
X1421688D01*
X1436413Y515103D01*
X1445520Y524210D01*
X1450818Y537004D01*
X1465200Y548017D01*
X1492273Y553523D01*
X1503181Y551302D01*
X1519618Y554644D01*
X1536715D01*
X1551990Y558810D01*
X1574041Y554778D01*
X1596620D01*
X1621573Y549872D01*
X1634409Y552834D01*
X1640133Y551535D01*
X1643263Y552289D01*
X1674366Y538727D01*
X1675101Y538596D01*
X1694657Y544283D01*
X1702824Y542755D01*
X1715239Y545319D01*
X1721121Y541704D01*
X1726938Y527661D01*
X1742026Y512573D01*
X1771882Y494312D01*
X1774991Y486809D01*
X1781964Y479836D01*
X1782602D01*
X1783556Y478882D01*
Y478244D01*
X1784510Y477290D01*
X1785148D01*
X1786102Y476336D01*
Y475698D01*
X1787100Y474700D01*
X1790372D01*
X1791900Y476228D01*
Y478850D01*
X1791450Y479300D01*
X1789975D01*
G01X1801525Y473955D02*
X1803000D01*
X1803450Y474405D01*
Y476779D01*
X1800252Y479976D01*
X1795005Y482150D01*
X1782123D01*
X1776712Y487560D01*
X1773431Y495481D01*
X1743392Y513492D01*
X1728252Y528343D01*
X1725322Y538849D01*
X1717288Y548599D01*
X1715988Y548965D01*
X1715187Y548515D01*
X1713887Y548881D01*
X1713437Y549682D01*
X1712138Y550048D01*
X1711336Y549598D01*
X1710037Y549964D01*
X1709587Y550766D01*
X1708287Y551131D01*
X1707486Y550681D01*
X1706186Y551047D01*
X1705736Y551849D01*
X1699590Y553578D01*
X1694789Y552338D01*
X1686117Y553964D01*
X1681092Y552748D01*
X1677849Y553507D01*
X1672320Y552371D01*
X1662188Y554273D01*
X1654294Y552345D01*
X1646393Y554437D01*
X1640124Y552928D01*
X1634403Y554224D01*
X1621554Y551258D01*
X1596587Y556167D01*
X1574064D01*
X1551930Y560214D01*
X1536531Y556014D01*
X1519471D01*
X1503540Y552774D01*
X1492591Y555003D01*
X1464677Y549324D01*
X1449589Y537769D01*
X1444274Y524938D01*
X1435863Y516526D01*
X1424304Y511740D01*
X1415147D01*
X1408447Y514513D01*
X1406681Y514857D01*
X1400595Y513674D01*
X1393391Y508814D01*
X1387343Y509990D01*
X1374709Y507534D01*
X1371844Y508091D01*
X1369956Y510890D01*
X1362649Y512310D01*
X1355256Y510874D01*
X1353517Y509701D01*
X1350793Y505663D01*
X1348424Y504063D01*
X1336840Y501811D01*
X1336838D01*
X1320942Y504686D01*
X1320941Y504685D01*
X1311628Y503910D01*
X1311627Y503909D01*
Y503910D01*
X1305113Y498777D01*
Y498765D01*
X1302880Y496532D01*
X1294760D01*
X1279000Y480772D01*
Y469673D01*
X1273177Y463850D01*
X1268977D01*
X1254327Y449200D01*
X1242827D01*
X1217324Y423697D01*
Y422777D01*
X1216334Y421787D01*
X1215414D01*
X1214424Y420797D01*
Y419878D01*
X1213434Y418888D01*
X1212515D01*
X1211525Y417898D01*
Y416979D01*
X1210535Y415989D01*
X1209616D01*
X1208626Y414999D01*
Y414080D01*
X1207636Y413090D01*
X1206717D01*
X1205727Y412100D01*
X1193860D01*
X1191414Y411086D01*
X1189350Y409022D01*
Y407627D01*
G01X1185979Y411400D02*
X1191180Y416600D01*
X1203373D01*
X1249773Y463000D01*
X1254500D01*
X1261275Y469775D01*
X1273624D01*
X1275060Y471211D01*
Y482159D01*
X1293239Y500338D01*
X1300509D01*
X1306948Y506776D01*
X1325819Y514587D01*
X1330105Y522850D01*
X1346715Y528136D01*
X1399705D01*
X1409943Y517898D01*
X1415852Y515450D01*
X1423347D01*
X1433422Y519623D01*
X1439938Y526139D01*
X1442300Y531840D01*
Y544516D01*
X1444010Y548643D01*
X1445697Y549816D01*
X1491066Y559045D01*
X1497582Y557720D01*
X1518368Y566206D01*
X1530562D01*
X1535694Y568603D01*
X1537376Y571314D01*
X1540915Y572850D01*
X1552736Y574313D01*
X1559668Y579719D01*
X1560146Y579939D01*
X1563255Y580572D01*
X1588807Y575007D01*
X1600030Y577239D01*
X1603096Y575970D01*
X1608188D01*
X1612118Y579900D01*
X1623800D01*
X1627730Y575970D01*
X1644082D01*
X1646895Y574804D01*
X1648897Y572802D01*
X1650700Y568451D01*
Y561201D01*
X1652933Y558968D01*
X1657766Y557540D01*
X1660902Y558328D01*
X1672522Y556145D01*
X1677900Y557251D01*
X1681077Y556507D01*
X1686018Y557702D01*
X1694663Y556082D01*
X1699915Y557438D01*
X1719253Y551964D01*
X1728921Y540232D01*
X1734259Y528418D01*
X1754664Y518260D01*
X1774679Y503360D01*
X1780510Y489290D01*
X1783399Y486400D01*
X1796205D01*
X1799858Y484887D01*
X1800708Y485239D01*
X1801955Y484722D01*
X1802307Y483873D01*
X1803554Y483356D01*
X1804730Y482180D01*
X1805374D01*
X1806328Y481226D01*
Y480582D01*
X1807298Y479612D01*
X1807862D01*
X1808816Y478658D01*
Y478094D01*
X1810910Y476000D01*
X1813572D01*
X1814325Y476753D01*
Y477775D01*
X1813780Y478320D01*
X1812375D01*
G01X1183011Y411500D02*
X1189511Y418000D01*
X1202050D01*
X1249950Y465900D01*
Y474823D01*
X1251577Y476450D01*
X1261100D01*
X1266900Y482250D01*
Y486914D01*
X1268525Y488539D01*
X1270253D01*
X1270914Y489200D01*
X1273511D01*
X1274165Y488546D01*
X1279162D01*
X1292547Y501931D01*
X1300155D01*
X1306122Y507897D01*
X1324813Y515635D01*
X1329228Y524142D01*
X1346424Y529615D01*
X1400528D01*
X1411336Y518807D01*
X1416085Y516840D01*
X1421127D01*
X1424305Y518791D01*
X1425712Y521782D01*
X1425710Y521796D01*
X1429158Y526697D01*
X1432990Y527577D01*
X1436511Y532437D01*
X1437675Y535771D01*
X1435226Y543942D01*
X1438536Y551931D01*
X1444907Y553657D01*
X1448186Y553096D01*
X1476172Y558790D01*
X1483841Y564429D01*
X1493165Y566086D01*
X1499538Y564870D01*
X1513084Y567564D01*
X1529861D01*
X1534874Y569903D01*
X1536920Y573203D01*
X1540179Y574616D01*
X1540180D01*
X1552957Y576198D01*
X1558961Y580880D01*
X1559724Y581231D01*
X1563368Y581973D01*
X1572637Y580074D01*
X1586150Y582777D01*
X1591852Y581636D01*
X1599013Y584602D01*
X1606721D01*
X1614247Y581485D01*
X1617221D01*
X1625467Y589731D01*
X1643344D01*
X1655433Y584721D01*
X1655436Y584720D01*
X1655435Y584719D01*
X1661061Y580674D01*
X1670916Y576395D01*
X1694814Y572311D01*
X1705389Y575442D01*
X1708706Y575009D01*
X1710455Y573944D01*
X1710456D01*
X1712204Y572879D01*
X1715133Y563564D01*
X1719457Y556277D01*
X1722319Y555091D01*
X1729849Y542507D01*
X1735410Y529872D01*
X1759476Y517584D01*
X1766147Y512618D01*
X1766280Y511709D01*
X1767363Y510903D01*
X1768272Y511036D01*
X1775619Y505568D01*
X1793147Y502085D01*
X1793658Y501321D01*
X1794982Y501057D01*
X1795746Y501568D01*
X1797070Y501305D01*
Y501306D01*
X1797581Y500541D01*
X1798905Y500278D01*
X1799669Y500789D01*
X1800993Y500526D01*
X1801504Y499762D01*
X1802828Y499498D01*
X1803592Y500009D01*
X1804916Y499746D01*
X1806039Y498996D01*
X1806218Y498095D01*
X1807341Y497345D01*
X1808242Y497525D01*
X1809365Y496775D01*
X1809544Y495874D01*
X1810667Y495124D01*
X1811568Y495304D01*
X1815000Y493012D01*
Y486900D01*
X1817800Y484100D01*
X1821900D01*
X1826925Y479075D01*
Y477585D01*
X1826267Y476927D01*
X1825297D01*
G01X1203287Y406200D02*
X1207077D01*
X1208324Y406717D01*
X1208676Y407566D01*
X1209923Y408082D01*
X1210773Y407731D01*
X1212020Y408247D01*
X1212372Y409096D01*
X1213619Y409613D01*
X1214468Y409261D01*
X1218720Y411022D01*
X1248110Y440411D01*
X1256111D01*
X1297730Y482030D01*
X1303185D01*
X1312523Y491368D01*
X1335122D01*
X1353047Y495030D01*
X1357169Y501142D01*
X1359932Y503005D01*
X1366827Y504351D01*
X1371605Y502677D01*
X1386649Y505542D01*
X1394269Y503640D01*
X1394268Y503639D01*
X1401890Y501737D01*
X1412801Y506614D01*
X1422695D01*
X1441116Y514243D01*
X1455754Y528880D01*
X1463280D01*
X1466250Y531850D01*
Y540645D01*
X1468254Y543674D01*
X1472762Y546651D01*
X1493033Y550773D01*
X1503086Y548727D01*
X1519742Y552115D01*
X1537055D01*
X1552100Y556218D01*
X1573679Y552272D01*
X1596381D01*
X1621621Y547309D01*
X1634414Y550263D01*
X1640148Y548962D01*
X1643033Y549655D01*
X1665978Y539649D01*
X1672980Y534981D01*
X1677144Y534151D01*
X1682886Y530323D01*
X1700378Y526825D01*
X1703260Y524623D01*
X1708231Y511394D01*
Y511393D01*
X1710962Y509641D01*
X1719235Y492047D01*
X1720528Y491510D01*
X1721378Y491861D01*
X1722671Y491324D01*
X1723022Y490475D01*
X1724315Y489938D01*
X1725164Y490289D01*
X1726457Y489752D01*
X1726808Y488903D01*
X1735136Y485450D01*
X1738023D01*
X1738825Y486252D01*
Y487267D01*
X1738337Y487755D01*
X1736900D01*
G01X1199509Y397692D02*
X1202837Y401020D01*
X1220859Y408486D01*
X1249955Y437582D01*
X1264738D01*
X1277260Y450104D01*
Y458020D01*
X1298656Y479416D01*
X1304432D01*
X1313887Y488868D01*
X1335763D01*
X1355308Y492851D01*
X1360029Y499846D01*
X1361288Y500697D01*
X1366619Y501741D01*
X1371772Y499931D01*
X1386748Y502782D01*
X1402157Y498935D01*
X1413720Y504105D01*
X1423507D01*
X1442625Y512024D01*
X1456981Y526380D01*
X1464553D01*
X1469198Y531025D01*
Y535417D01*
X1472296Y540010D01*
X1476014Y542519D01*
X1476245Y542564D01*
Y542563D01*
X1481579Y543600D01*
X1491376Y541697D01*
X1498568Y543095D01*
X1501021Y544749D01*
X1525344Y549615D01*
X1537391D01*
X1552209Y553655D01*
X1573487Y549765D01*
X1596141D01*
X1621659Y544748D01*
X1634416Y547692D01*
X1634418D01*
X1640167Y546388D01*
X1642803Y547022D01*
X1659095Y539915D01*
X1667907Y524286D01*
X1670727Y522476D01*
X1684663Y519216D01*
X1696839Y510985D01*
X1709228Y507440D01*
X1717438Y489979D01*
X1734097Y483080D01*
X1738320Y482236D01*
X1739168Y482233D01*
X1739821Y482880D01*
X1741171Y482875D01*
X1741818Y482223D01*
X1743168Y482217D01*
X1743821Y482865D01*
X1745171Y482860D01*
X1745818Y482207D01*
X1747168Y482202D01*
X1750018Y482746D01*
X1751262Y483990D01*
Y486888D01*
X1750295Y487855D01*
X1749300D01*
G01X1205288Y393710D02*
X1206341Y394764D01*
X1227279Y404189D01*
X1252249Y429160D01*
X1265528D01*
X1283410Y447042D01*
Y455469D01*
X1296437Y468496D01*
X1302707D01*
X1316929Y482718D01*
X1337768D01*
X1345774Y484370D01*
X1354541Y482666D01*
X1358708Y478498D01*
X1366967D01*
X1374359Y479935D01*
X1381751Y478498D01*
X1383931D01*
X1388818Y479448D01*
X1402363Y488581D01*
X1405280Y492907D01*
X1414954Y497799D01*
X1424683D01*
X1446794Y506965D01*
X1457620Y517791D01*
X1463673D01*
X1469765Y521825D01*
X1477299Y523357D01*
X1479923Y525095D01*
X1479924D01*
X1482550Y526834D01*
X1486795Y527684D01*
X1503321Y538621D01*
X1527138Y543465D01*
X1538215D01*
X1552477Y547350D01*
X1572988Y543603D01*
X1595540D01*
X1621935Y538413D01*
X1634593Y541334D01*
X1640208Y540062D01*
X1642209Y540542D01*
X1642210D01*
X1654721Y535085D01*
X1656859Y531291D01*
Y531292D01*
X1663276Y519907D01*
X1668504Y516556D01*
X1682340Y513318D01*
X1696201Y503948D01*
X1701390Y489669D01*
X1738605Y474254D01*
X1760239Y469950D01*
X1762977D01*
X1764906Y471879D01*
Y474740D01*
X1765821Y475655D01*
X1766700D01*
G01X1202006Y394394D02*
X1205516Y397904D01*
X1224788Y405887D01*
X1251610Y432710D01*
X1265030D01*
X1280910Y448590D01*
Y456506D01*
X1296279Y471875D01*
X1302417D01*
X1315764Y485218D01*
X1336330D01*
X1357331Y489487D01*
X1379124D01*
X1382172Y490079D01*
X1384954Y489539D01*
X1387703Y490073D01*
X1391246Y489384D01*
X1394500Y490017D01*
X1397888Y492301D01*
X1397889Y492303D01*
X1401001Y494401D01*
X1414380Y500380D01*
X1424098D01*
X1445062Y509062D01*
X1456350Y520350D01*
X1461638D01*
X1465244Y521847D01*
X1474463Y531064D01*
Y533860D01*
X1476960Y536357D01*
X1495329D01*
X1502759Y541275D01*
X1525804Y545965D01*
X1537880D01*
X1552368Y549913D01*
X1573185Y546109D01*
X1595782D01*
X1621719Y541009D01*
X1621722D01*
X1634425Y543942D01*
X1634426Y543941D01*
Y543942D01*
X1640192Y542633D01*
X1642465Y543180D01*
X1656490Y537064D01*
X1665157Y521686D01*
X1669297Y519030D01*
X1683186Y515780D01*
X1695221Y507643D01*
X1706625Y504379D01*
X1714758Y487084D01*
X1735989Y478289D01*
X1744695Y476548D01*
X1760199Y479644D01*
X1768033Y478138D01*
X1768034D01*
X1769303Y476870D01*
Y471300D01*
X1771333Y469270D01*
X1775869D01*
X1777350Y470751D01*
Y474549D01*
X1777856Y475055D01*
X1779300D01*
G01X1200900Y408950D02*
X1206963D01*
X1219116Y413988D01*
X1247478Y442361D01*
X1256088D01*
X1284000Y470273D01*
Y480540D01*
X1291299Y487839D01*
X1297794Y489117D01*
X1297853Y489135D01*
Y489136D01*
X1315636Y494695D01*
X1343110D01*
X1351192Y496267D01*
X1354509Y501182D01*
X1359155Y504316D01*
X1366815Y505804D01*
X1371584Y504203D01*
X1386745Y507093D01*
X1401491Y503294D01*
X1412148Y508050D01*
X1421910D01*
X1437063Y514124D01*
X1446496Y523558D01*
X1451764Y536279D01*
X1465689Y546942D01*
X1492273Y552349D01*
X1503181Y550128D01*
X1519734Y553494D01*
X1536870D01*
X1552040Y557631D01*
X1573936Y553628D01*
X1596510D01*
X1596511Y553627D01*
X1621592Y548696D01*
X1621595D01*
X1634411Y551654D01*
X1640141Y550353D01*
X1643157Y551080D01*
X1674030Y537618D01*
X1675164Y537416D01*
X1694715Y543102D01*
X1702835Y541582D01*
X1715025Y544100D01*
X1720201Y540919D01*
X1725962Y527009D01*
X1741309Y511663D01*
X1770962Y493525D01*
X1774015Y486157D01*
X1786623Y473550D01*
X1790849D01*
X1793050Y475751D01*
Y478850D01*
X1793500Y479300D01*
X1794975D01*
G01X1806525Y473955D02*
X1805050D01*
X1804600Y474405D01*
Y477256D01*
X1800904Y480952D01*
X1795234Y483300D01*
X1782600D01*
X1777688Y488212D01*
X1774349Y496273D01*
X1744101Y514409D01*
X1729278Y528949D01*
X1726365Y539393D01*
X1717947Y549609D01*
X1699603Y554770D01*
X1694749Y553516D01*
X1686084Y555141D01*
X1681088Y553931D01*
X1677865Y554685D01*
X1672310Y553543D01*
X1662156Y555450D01*
X1654305Y553532D01*
X1646406Y555624D01*
X1640116Y554109D01*
X1634401Y555404D01*
X1621535Y552434D01*
X1596699Y557317D01*
X1574169D01*
X1551880Y561393D01*
X1536376Y557164D01*
X1519355D01*
X1503540Y553948D01*
X1492591Y556177D01*
X1464188Y550399D01*
X1448644Y538495D01*
X1443298Y525590D01*
X1435211Y517502D01*
X1424075Y512890D01*
X1415376D01*
X1408780Y515620D01*
X1406681Y516029D01*
X1400145Y514759D01*
X1393143Y510034D01*
X1387343Y511162D01*
X1374709Y508706D01*
X1372532Y509130D01*
X1370644Y511929D01*
X1362649Y513482D01*
X1354806Y511959D01*
X1352688Y510529D01*
X1349964Y506491D01*
X1347974Y505148D01*
X1336830Y502982D01*
X1320998Y505845D01*
X1311187Y505028D01*
X1304402Y499681D01*
X1302403Y497682D01*
X1294283D01*
X1277850Y481249D01*
Y470150D01*
X1272700Y465000D01*
X1268500D01*
X1253850Y450350D01*
X1242350D01*
X1205250Y413250D01*
X1193631D01*
X1190762Y412062D01*
X1188200Y409500D01*
Y407627D01*
G01X1186622Y410415D02*
X1191657Y415450D01*
X1203850D01*
X1250250Y461850D01*
X1254977D01*
X1261752Y468625D01*
X1274101D01*
X1276210Y470734D01*
Y481682D01*
X1293716Y499188D01*
X1300986D01*
X1307600Y505800D01*
X1326647Y513685D01*
X1330907Y521898D01*
X1346894Y526986D01*
X1399228D01*
X1409291Y516923D01*
X1415623Y514300D01*
X1423576D01*
X1434074Y518647D01*
X1440914Y525487D01*
X1443450Y531611D01*
Y544287D01*
X1444944Y547891D01*
X1446159Y548736D01*
X1491066Y557871D01*
X1497694Y556523D01*
X1518594Y565056D01*
X1530818D01*
X1536491Y567705D01*
X1538164Y570402D01*
X1541221Y571729D01*
X1553193Y573210D01*
X1560376Y578812D01*
X1563247Y579396D01*
X1588796Y573832D01*
X1599914Y576042D01*
X1602867Y574820D01*
X1608665D01*
X1612595Y578750D01*
X1623323D01*
X1627253Y574820D01*
X1643852D01*
X1643853Y574819D01*
X1646243Y573828D01*
X1647921Y572150D01*
X1649550Y568222D01*
Y560724D01*
X1652326Y557947D01*
X1657741Y556347D01*
X1660938Y557151D01*
X1672532Y554972D01*
X1677884Y556073D01*
X1681081Y555324D01*
X1686049Y556526D01*
X1694703Y554904D01*
X1699901Y556246D01*
X1718594Y550955D01*
X1727935Y539618D01*
X1733379Y527570D01*
X1754059Y517275D01*
X1773737Y502627D01*
X1779534Y488638D01*
X1782922Y485250D01*
X1795976D01*
X1802902Y482380D01*
X1810433Y474850D01*
X1814049D01*
X1815475Y476276D01*
Y477775D01*
X1816020Y478320D01*
X1817375D01*
G01X1182197Y412313D02*
X1189034Y419150D01*
X1201573D01*
X1248800Y466377D01*
Y475300D01*
X1251100Y477600D01*
X1260623D01*
X1265750Y482727D01*
Y487391D01*
X1268048Y489689D01*
X1269776D01*
X1270437Y490350D01*
X1273988D01*
X1274642Y489696D01*
X1278685D01*
X1292070Y503081D01*
X1299678D01*
X1305470Y508873D01*
X1323981Y516538D01*
X1323984Y516536D01*
X1328426Y525094D01*
X1346245Y530765D01*
X1401005D01*
X1411988Y519782D01*
X1416314Y517990D01*
X1420802D01*
X1423410Y519591D01*
X1424756Y522454D01*
X1424759Y522457D01*
X1424768Y522458D01*
X1424774Y522466D01*
X1428470Y527720D01*
X1432311Y528602D01*
X1435480Y532976D01*
X1436466Y535798D01*
X1434006Y544004D01*
X1437689Y552894D01*
X1444851Y554834D01*
X1448168Y554266D01*
X1475694Y559867D01*
X1483375Y565515D01*
X1493172Y567256D01*
X1499533Y566042D01*
X1512970Y568714D01*
X1529605D01*
X1534077Y570801D01*
X1536132Y574115D01*
X1539940Y575766D01*
X1540109D01*
X1552500Y577301D01*
X1558359Y581869D01*
X1559364Y582332D01*
X1563369Y583147D01*
X1572640Y581248D01*
X1586150Y583950D01*
X1591735Y582833D01*
X1598784Y585752D01*
X1606950D01*
X1614476Y582635D01*
X1616744D01*
X1624990Y590881D01*
X1643573D01*
X1655997Y585733D01*
X1661632Y581680D01*
X1671247Y577506D01*
X1694744Y573490D01*
X1705296Y576614D01*
X1709096Y576118D01*
X1713172Y573637D01*
X1716191Y564037D01*
X1720251Y557193D01*
X1723111Y556008D01*
X1730873Y543036D01*
X1736298Y530710D01*
X1760086Y518565D01*
X1776096Y506647D01*
X1805365Y500830D01*
X1816150Y493627D01*
Y487377D01*
X1818277Y485250D01*
X1822377D01*
X1828075Y479552D01*
Y477565D01*
X1828713Y476927D01*
X1829967D01*
G01X1203287Y405050D02*
X1207306D01*
X1219372Y410046D01*
X1248587Y439261D01*
X1256588D01*
X1298207Y480880D01*
X1303662D01*
X1313000Y490218D01*
X1335239D01*
X1353738Y493997D01*
X1357998Y500313D01*
X1360382Y501920D01*
X1366741Y503162D01*
X1371516Y501489D01*
X1386616Y504364D01*
X1401997Y500524D01*
X1413047Y505464D01*
X1422924D01*
X1441768Y513267D01*
X1456231Y527730D01*
X1463757D01*
X1467400Y531373D01*
Y540298D01*
X1469084Y542843D01*
X1473210Y545568D01*
X1493033Y549599D01*
X1503086Y547553D01*
X1519858Y550965D01*
X1537209D01*
X1552150Y555039D01*
X1573574Y551122D01*
X1596266D01*
X1621640Y546133D01*
X1634416Y549083D01*
X1640153Y547781D01*
X1640154Y547780D01*
X1640155D01*
X1642926Y548445D01*
Y548446D01*
X1642927D01*
X1665424Y538635D01*
X1672531Y533897D01*
X1676695Y533067D01*
X1682437Y529240D01*
X1699890Y525749D01*
X1702299Y523909D01*
X1707288Y510631D01*
X1710062Y508852D01*
X1718387Y491147D01*
X1734907Y484300D01*
X1738500D01*
X1739975Y485775D01*
Y487305D01*
X1740425Y487755D01*
X1741900D01*
G01X1200323Y396878D02*
X1203489Y400044D01*
X1221511Y407510D01*
X1250432Y436432D01*
X1265215D01*
X1278410Y449627D01*
Y457543D01*
X1299133Y478266D01*
X1304909D01*
X1314364Y487718D01*
X1335879D01*
X1355999Y491817D01*
X1360858Y499018D01*
X1361738Y499613D01*
X1366533Y500552D01*
X1371684Y498743D01*
X1386715Y501604D01*
X1402264Y497722D01*
X1413966Y502955D01*
X1423736D01*
X1443277Y511048D01*
X1457458Y525230D01*
X1465030D01*
X1470348Y530548D01*
Y535065D01*
X1473125Y539181D01*
X1476464Y541434D01*
X1481579Y542428D01*
X1491376Y540525D01*
X1499017Y542010D01*
X1501473Y543666D01*
X1525458Y548465D01*
X1537545D01*
X1552259Y552476D01*
X1573382Y548615D01*
X1596027D01*
X1621678Y543572D01*
X1634418Y546512D01*
X1640175Y545206D01*
X1642697Y545813D01*
X1658280Y539015D01*
X1667045Y523472D01*
X1670272Y521401D01*
X1684194Y518144D01*
X1696346Y509929D01*
X1708409Y506477D01*
X1716586Y489086D01*
X1716588Y489085D01*
Y489084D01*
X1733761Y481974D01*
X1738203Y481086D01*
X1738316D01*
X1747275Y481051D01*
X1750582Y481682D01*
X1752412Y483513D01*
Y486888D01*
X1753379Y487855D01*
X1754300D01*
G01X1221306Y377759D02*
X1225364Y381817D01*
X1228338Y387850D01*
X1242410Y405177D01*
X1245660Y406524D01*
X1246509Y406173D01*
X1247756Y406690D01*
X1248107Y407540D01*
X1249354Y408057D01*
X1250203Y407706D01*
X1251450Y408223D01*
X1251802Y409072D01*
X1292225Y425834D01*
X1294710Y431428D01*
X1306507Y439320D01*
X1356302D01*
X1363827Y444349D01*
X1363828Y444350D01*
X1397213D01*
X1400262Y447398D01*
X1405974Y449765D01*
X1408200Y451992D01*
Y454400D01*
X1408700Y454900D01*
X1409630D01*
X1410475Y454055D01*
Y453561D01*
G01X1409300Y434775D02*
Y433300D01*
X1408850Y432850D01*
X1407450D01*
X1407000Y433300D01*
Y436300D01*
X1404850Y438450D01*
X1398603D01*
X1396475Y440578D01*
X1363520D01*
X1361618Y439307D01*
Y439306D01*
X1356485Y435875D01*
X1309098D01*
X1307100Y433877D01*
Y426777D01*
X1305673Y425350D01*
X1296960D01*
X1242380Y402736D01*
X1230572Y388195D01*
X1226610Y380309D01*
X1217683Y371382D01*
X1211487Y368814D01*
X1209992D01*
G01X1401398Y434775D02*
Y433300D01*
X1400948Y432850D01*
X1399549D01*
X1396839Y435560D01*
X1383523D01*
X1365797Y430516D01*
X1354891D01*
X1348721Y427962D01*
X1345109Y425137D01*
X1339388Y415427D01*
X1337256Y413889D01*
X1330112Y412689D01*
X1324102Y413834D01*
X1317672Y412799D01*
X1270649Y393327D01*
X1258211Y377489D01*
Y377490D01*
X1240380Y370096D01*
X1220208Y366085D01*
X1209157D01*
G01X1415146Y421946D02*
Y420722D01*
X1414458Y420034D01*
X1412007D01*
X1410875Y421166D01*
Y423802D01*
X1407451Y427226D01*
X1400931D01*
X1399846Y427675D01*
X1396981Y430540D01*
X1383563D01*
X1359585Y422303D01*
X1353663Y424510D01*
X1346290Y421921D01*
X1341452Y413708D01*
X1338196Y411360D01*
X1330084Y409997D01*
X1330075Y409999D01*
X1324065Y411144D01*
X1318652Y410273D01*
X1274279Y391900D01*
X1261682Y375857D01*
X1250854Y371375D01*
Y371374D01*
X1240024Y366890D01*
X1217206Y362350D01*
X1208300D01*
G01X1407158Y421575D02*
X1405263Y419680D01*
X1403875D01*
X1402752Y420803D01*
Y423093D01*
X1401631Y424214D01*
X1399841Y424956D01*
X1391956D01*
X1350541Y416758D01*
X1343147Y411447D01*
X1339052Y401554D01*
X1336780Y398795D01*
X1331853Y396644D01*
X1327758Y397172D01*
X1323028Y396533D01*
X1313311Y398170D01*
X1305256Y396788D01*
X1271783Y382924D01*
X1271627Y382726D01*
X1263751Y372690D01*
X1243373Y364249D01*
X1218742Y359350D01*
X1214210D01*
G01X1213309Y355200D02*
X1214855D01*
X1246399Y361473D01*
X1264885Y369130D01*
X1273844Y380540D01*
X1305423Y393621D01*
X1313317Y394974D01*
X1322594Y393411D01*
X1327325Y394052D01*
X1332315Y393408D01*
X1338082Y395927D01*
X1340984Y399448D01*
X1344853Y408792D01*
X1352420Y414240D01*
X1352423Y414241D01*
X1392455Y422032D01*
X1398724Y420903D01*
X1400751Y418403D01*
Y412655D01*
X1402050Y411356D01*
X1404973D01*
X1405423Y411806D01*
Y413281D01*
G01X1395375Y457561D02*
Y456629D01*
X1394768Y456022D01*
X1392236D01*
X1391814Y455600D01*
X1346202D01*
X1341928Y451326D01*
X1340129Y450580D01*
X1333600D01*
X1320852Y448029D01*
X1315441Y449111D01*
X1307739Y447570D01*
X1302846Y448755D01*
X1299695Y448126D01*
X1293584Y445595D01*
X1291888Y443443D01*
X1291887Y443441D01*
X1290264Y441383D01*
X1286510Y431250D01*
X1270134Y424460D01*
X1270133D01*
X1237559Y410955D01*
X1213977Y381912D01*
G01X1402775Y453561D02*
Y454586D01*
X1402361Y455000D01*
X1401483D01*
X1401083Y454600D01*
Y452323D01*
X1399765Y451005D01*
X1396016Y449450D01*
X1348137D01*
X1345056Y446368D01*
X1340423Y444450D01*
X1326316D01*
X1322842Y443755D01*
X1315441Y445235D01*
X1307660Y443679D01*
X1302767Y444864D01*
X1300195Y444350D01*
X1296107Y442656D01*
X1293621Y439501D01*
X1290574Y431275D01*
X1290957Y430440D01*
X1290488Y429174D01*
X1289653Y428790D01*
X1289184Y427524D01*
X1240021Y407162D01*
X1226085Y390002D01*
X1222891Y384294D01*
X1220325Y381728D01*
G01X1410475Y457561D02*
Y456962D01*
X1409563Y456050D01*
X1408223D01*
X1407050Y454877D01*
Y452469D01*
X1405322Y450741D01*
X1399610Y448374D01*
X1396736Y445500D01*
X1363478D01*
X1355953Y440470D01*
X1306157D01*
X1293794Y432199D01*
X1291360Y426721D01*
X1241700Y406129D01*
X1227363Y388475D01*
X1224416Y382496D01*
X1220492Y378572D01*
G01X1409300Y429775D02*
Y431250D01*
X1408850Y431700D01*
X1406973D01*
X1405850Y432823D01*
Y435823D01*
X1404373Y437300D01*
X1398126D01*
X1395998Y439428D01*
X1363872D01*
X1356834Y434725D01*
X1309575D01*
X1308250Y433400D01*
Y426300D01*
X1306150Y424200D01*
X1297189D01*
X1243090Y401784D01*
X1231544Y387567D01*
X1227555Y379626D01*
X1218335Y370407D01*
X1211716Y367664D01*
X1209992D01*
G01X1401398Y429775D02*
Y431250D01*
X1400948Y431700D01*
X1399072D01*
X1396362Y434410D01*
X1383686D01*
X1366111Y429409D01*
X1365958Y429366D01*
X1355120D01*
X1349306Y426959D01*
X1345989Y424365D01*
X1340257Y414635D01*
X1337711Y412799D01*
X1330100Y411520D01*
X1324085Y412666D01*
X1317988Y411685D01*
X1271368Y392379D01*
X1258930Y376542D01*
X1240716Y368990D01*
X1220322Y364935D01*
X1209157D01*
G01X1414982Y417040D02*
Y418434D01*
X1414532Y418884D01*
X1411530D01*
X1409725Y420689D01*
Y423325D01*
X1406974Y426076D01*
X1400702D01*
X1399194Y426699D01*
X1397177Y428716D01*
Y428717D01*
X1396504Y429390D01*
X1383756D01*
X1359570Y421081D01*
X1353650Y423286D01*
X1347068Y420975D01*
X1342321Y412916D01*
X1338651Y410270D01*
X1330274Y408862D01*
Y408861D01*
X1330071Y408828D01*
Y408829D01*
X1329869Y408867D01*
X1329860Y408869D01*
X1324048Y409976D01*
X1318968Y409159D01*
X1274998Y390952D01*
X1262399Y374908D01*
X1240359Y365784D01*
X1217320Y361200D01*
X1208300D01*
G01X1407158Y416575D02*
X1405203Y418530D01*
X1403398D01*
X1401602Y420326D01*
Y422616D01*
X1400981Y423237D01*
X1400979Y423238D01*
X1399611Y423806D01*
X1392069D01*
X1351009Y415678D01*
X1344085Y410704D01*
X1340049Y400955D01*
X1337493Y397851D01*
X1332022Y395462D01*
X1327761Y396011D01*
X1323009Y395369D01*
X1313312Y397003D01*
X1305577Y395676D01*
X1272502Y381977D01*
X1264470Y371743D01*
X1243708Y363143D01*
X1218856Y358200D01*
X1214210D01*
G01X1213285Y354050D02*
X1214969D01*
X1246734Y360367D01*
X1265604Y368182D01*
X1274563Y379592D01*
X1305744Y392509D01*
X1313319Y393807D01*
X1322575Y392247D01*
X1327329Y392891D01*
X1332484Y392226D01*
X1338795Y394982D01*
X1341981Y398849D01*
X1345791Y408049D01*
X1352886Y413158D01*
X1352889Y413159D01*
X1392463Y420861D01*
X1398099Y419847D01*
X1399601Y417995D01*
Y412178D01*
X1401573Y410206D01*
X1404973D01*
X1405423Y409756D01*
Y408281D01*
G01X1395375Y453561D02*
Y454421D01*
X1394924Y454872D01*
X1392713D01*
X1392291Y454450D01*
X1346679D01*
X1342580Y450351D01*
X1340358Y449430D01*
X1333714D01*
X1320852Y446856D01*
X1315441Y447938D01*
X1307715Y446392D01*
X1302822Y447577D01*
X1300030Y447020D01*
Y447019D01*
X1294302Y444647D01*
X1291280Y440813D01*
X1287415Y430379D01*
X1254196Y416606D01*
X1253845Y415757D01*
X1252597Y415240D01*
X1251748Y415591D01*
X1250501Y415074D01*
X1250150Y414225D01*
X1248903Y413708D01*
X1248053Y414060D01*
X1238269Y410003D01*
X1214870Y381187D01*
G01X1219512Y382542D02*
X1221965Y384995D01*
X1225129Y390651D01*
X1239311Y408114D01*
X1288279Y428395D01*
X1292605Y440071D01*
X1295389Y443604D01*
X1299859Y445456D01*
X1302791Y446042D01*
X1307684Y444857D01*
X1315441Y446408D01*
X1322842Y444928D01*
X1326202Y445600D01*
X1340194D01*
X1344404Y447344D01*
X1347660Y450600D01*
X1395786D01*
X1399113Y451980D01*
X1399933Y452800D01*
Y455077D01*
X1401006Y456150D01*
X1402061D01*
X1402775Y456864D01*
Y457561D01*
G01X1377028Y458125D02*
X1375553D01*
X1375103Y458575D01*
Y459304D01*
X1375885Y460086D01*
X1381760D01*
X1382410Y459436D01*
X1383760D01*
X1384410Y460086D01*
X1385760D01*
X1386410Y459436D01*
X1387760D01*
X1388410Y460086D01*
X1398449D01*
X1399099Y459436D01*
X1400449D01*
X1401099Y460086D01*
X1413427D01*
X1414077Y459436D01*
X1415427D01*
X1416077Y460086D01*
X1417427D01*
X1418077Y459436D01*
X1419427D01*
X1420077Y460086D01*
X1421427D01*
X1422077Y459436D01*
X1423427D01*
X1424077Y460086D01*
X1425427D01*
X1426077Y459436D01*
X1427427D01*
X1428077Y460086D01*
X1441488D01*
X1451149Y450425D01*
X1454248D01*
X1460099Y444574D01*
Y433472D01*
X1459478Y432851D01*
G01X1372028Y458125D02*
X1373503D01*
X1373953Y458575D01*
Y459781D01*
X1375408Y461236D01*
X1441965D01*
X1451626Y451575D01*
X1454725D01*
X1461249Y445051D01*
Y433733D01*
X1462131Y432851D01*
G01X1500455Y110933D02*
X1501607Y112085D01*
X1502245D01*
X1504027Y110303D01*
Y100944D01*
X1504900Y100071D01*
Y77492D01*
X1510652Y71740D01*
X1542547D01*
X1564529Y93722D01*
Y114430D01*
X1568050Y117951D01*
Y122565D01*
X1569600Y124115D01*
Y130142D01*
X1572000Y132542D01*
Y145250D01*
X1569200Y148050D01*
Y154051D01*
X1573150Y158001D01*
Y160068D01*
X1580732Y167650D01*
Y171569D01*
X1588676Y179513D01*
Y183919D01*
X1590700Y185943D01*
Y192441D01*
X1593061Y194802D01*
X1599998D01*
X1604946Y199750D01*
X1616029D01*
X1627545Y211266D01*
X1629159D01*
X1629160Y211265D01*
X1631728D01*
X1650000Y229537D01*
Y274099D01*
X1652397Y276496D01*
Y314149D01*
X1656666Y318418D01*
Y366121D01*
X1651542Y371245D01*
Y372492D01*
X1648650Y375384D01*
Y424554D01*
X1650200Y426104D01*
Y453863D01*
X1650201Y453864D01*
Y454816D01*
X1637167Y467850D01*
X1632817D01*
X1630308Y470359D01*
Y473930D01*
X1618838Y485400D01*
X1585268D01*
X1573268Y497400D01*
X1561400D01*
G01X1544855Y511873D02*
Y513363D01*
X1546555Y515063D01*
X1557637D01*
X1560732Y511968D01*
X1572807D01*
X1578266Y506509D01*
Y497024D01*
X1586490Y488800D01*
X1589572D01*
X1590772Y490000D01*
X1607400D01*
X1609363Y488037D01*
X1620033D01*
X1630201Y477869D01*
X1632558D01*
X1653200Y457227D01*
Y431167D01*
X1655500Y428867D01*
Y406300D01*
X1651900Y402700D01*
Y375671D01*
X1654042Y373529D01*
Y372282D01*
X1659350Y366974D01*
Y317447D01*
X1654897Y312994D01*
Y274797D01*
X1652500Y272400D01*
Y228500D01*
X1632663Y208663D01*
X1628479D01*
X1613042Y193226D01*
X1603984D01*
X1598583Y187825D01*
X1596314D01*
X1591197Y182708D01*
Y178497D01*
X1583232Y170532D01*
Y166613D01*
X1575950Y159331D01*
Y157241D01*
X1571700Y152991D01*
Y149176D01*
X1574650Y146226D01*
Y131266D01*
X1572350Y128966D01*
Y123280D01*
X1570575Y121505D01*
Y116325D01*
X1567029Y112779D01*
Y92493D01*
X1541583Y67047D01*
X1509686D01*
X1502400Y74333D01*
Y98957D01*
X1500774Y100583D01*
X1500006D01*
X1498945Y99522D01*
X1498705D01*
G01X1548177Y516413D02*
X1558259D01*
X1561354Y513318D01*
X1573377D01*
X1585281Y501414D01*
Y494730D01*
X1587711Y492300D01*
X1591573D01*
X1592006Y491867D01*
X1618271D01*
X1630488Y479650D01*
X1639066D01*
X1640936Y477780D01*
Y474137D01*
X1643636Y471437D01*
Y470518D01*
X1644591Y469563D01*
X1645510D01*
X1646465Y468608D01*
Y467689D01*
X1647419Y466735D01*
X1648338D01*
X1649293Y465780D01*
Y464861D01*
X1650248Y463906D01*
X1651167D01*
X1652122Y462951D01*
Y462032D01*
X1653076Y461078D01*
X1653995D01*
X1654950Y460123D01*
Y431974D01*
X1657250Y429674D01*
Y394861D01*
X1655392Y393003D01*
Y372842D01*
X1660849Y367385D01*
Y317036D01*
X1656489Y312676D01*
Y307927D01*
X1659338Y305078D01*
Y297019D01*
X1660077Y296280D01*
Y256747D01*
X1653850Y250520D01*
Y227550D01*
X1641750Y215450D01*
Y210150D01*
X1637400Y205800D01*
X1629266D01*
X1621722Y198256D01*
Y193149D01*
X1620123Y191550D01*
X1604218D01*
X1599143Y186475D01*
X1596874D01*
X1592634Y182235D01*
Y177945D01*
X1584582Y169893D01*
Y166053D01*
X1580243Y161714D01*
Y137935D01*
X1576300Y133992D01*
Y119727D01*
X1569100Y112527D01*
Y111177D01*
X1568450Y110527D01*
Y109177D01*
X1569100Y108527D01*
Y107177D01*
X1568450Y106527D01*
Y105177D01*
X1569100Y104527D01*
Y103177D01*
X1568450Y102527D01*
Y101177D01*
X1569100Y100527D01*
Y91046D01*
X1568145Y90091D01*
X1567226D01*
X1566272Y89137D01*
Y88218D01*
X1565317Y87263D01*
X1564398D01*
X1563444Y86309D01*
Y85390D01*
X1562489Y84435D01*
X1561570D01*
X1560616Y83481D01*
Y82562D01*
X1559661Y81607D01*
X1558742D01*
X1557788Y80653D01*
Y79734D01*
X1542814Y64760D01*
X1539851D01*
X1539201Y65410D01*
X1537851D01*
X1537201Y64760D01*
X1535851D01*
X1535201Y65410D01*
X1533851D01*
X1533201Y64760D01*
X1531851D01*
X1531201Y65410D01*
X1529851D01*
X1529201Y64760D01*
X1527851D01*
X1527201Y65410D01*
X1525851D01*
X1525201Y64760D01*
X1509099D01*
X1499996Y73863D01*
Y80188D01*
X1497080Y83104D01*
Y87173D01*
X1497913Y88006D01*
X1498550D01*
X1499875Y86681D01*
G01X1500455Y114388D02*
X1501608Y113235D01*
X1502722D01*
X1505177Y110780D01*
Y101421D01*
X1506050Y100548D01*
Y77969D01*
X1511129Y72890D01*
X1542070D01*
X1563379Y94199D01*
Y114907D01*
X1566900Y118428D01*
Y123042D01*
X1568450Y124592D01*
Y130619D01*
X1570850Y133019D01*
Y144773D01*
X1568050Y147573D01*
Y154528D01*
X1572000Y158478D01*
Y160545D01*
X1579582Y168127D01*
Y172046D01*
X1587526Y179990D01*
Y184396D01*
X1589550Y186420D01*
Y192918D01*
X1592584Y195952D01*
X1599521D01*
X1604469Y200900D01*
X1615552D01*
X1627068Y212416D01*
X1629636D01*
X1629637Y212415D01*
X1631251D01*
X1648850Y230014D01*
Y274576D01*
X1651247Y276973D01*
Y314626D01*
X1655516Y318895D01*
Y337373D01*
X1654866Y338023D01*
Y339373D01*
X1655516Y340023D01*
Y341373D01*
X1654866Y342023D01*
Y343373D01*
X1655516Y344023D01*
Y345373D01*
X1654866Y346023D01*
Y347373D01*
X1655516Y348023D01*
Y349373D01*
X1654866Y350023D01*
Y351373D01*
X1655516Y352023D01*
Y365644D01*
X1650392Y370768D01*
Y372015D01*
X1647500Y374907D01*
Y425031D01*
X1649050Y426581D01*
Y454340D01*
X1648068Y455322D01*
X1647149D01*
X1646195Y456276D01*
Y457195D01*
X1645240Y458150D01*
X1644321D01*
X1643366Y459104D01*
Y460024D01*
X1636690Y466700D01*
X1632340D01*
X1629158Y469882D01*
Y473453D01*
X1618361Y484250D01*
X1584791D01*
X1572791Y496250D01*
X1566259D01*
X1565609Y495600D01*
X1564259D01*
X1563609Y496250D01*
X1561400D01*
G01X1546005Y511873D02*
Y512886D01*
X1547032Y513913D01*
X1551752D01*
X1552402Y513263D01*
X1553752D01*
X1554402Y513913D01*
X1557160D01*
X1560255Y510818D01*
X1572330D01*
X1577116Y506032D01*
Y505065D01*
X1576466Y504415D01*
Y503065D01*
X1577116Y502415D01*
Y500210D01*
X1576466Y499560D01*
Y498210D01*
X1577116Y497560D01*
Y496547D01*
X1586013Y487650D01*
X1590049D01*
X1591249Y488850D01*
X1606923D01*
X1608886Y486887D01*
X1619556D01*
X1629724Y476719D01*
X1632081D01*
X1637054Y471746D01*
Y470827D01*
X1638009Y469872D01*
X1638928D01*
X1639883Y468917D01*
Y467998D01*
X1640837Y467044D01*
X1641756D01*
X1642711Y466089D01*
Y465170D01*
X1643665Y464216D01*
X1644584D01*
X1645539Y463261D01*
Y462342D01*
X1646493Y461388D01*
X1647412D01*
X1648367Y460433D01*
Y459514D01*
X1649321Y458560D01*
X1650240D01*
X1652050Y456750D01*
Y430690D01*
X1654350Y428390D01*
Y406777D01*
X1650750Y403177D01*
Y375194D01*
X1652892Y373052D01*
Y371805D01*
X1658200Y366497D01*
Y317924D01*
X1653747Y313471D01*
Y275274D01*
X1651350Y272877D01*
Y228977D01*
X1632186Y209813D01*
X1628002D01*
X1612565Y194376D01*
X1603507D01*
X1598106Y188975D01*
X1595837D01*
X1590047Y183185D01*
Y178974D01*
X1582082Y171009D01*
Y167090D01*
X1574800Y159808D01*
Y157718D01*
X1570550Y153468D01*
Y148699D01*
X1573500Y145749D01*
Y131743D01*
X1571200Y129443D01*
Y123757D01*
X1569425Y121982D01*
Y116802D01*
X1565879Y113256D01*
Y92970D01*
X1541106Y68197D01*
X1519722D01*
X1519072Y68847D01*
X1517722D01*
X1517072Y68197D01*
X1515722D01*
X1515072Y68847D01*
X1513722D01*
X1513072Y68197D01*
X1510163D01*
X1503550Y74810D01*
Y99434D01*
X1501251Y101733D01*
X1499943D01*
X1498930Y102746D01*
X1498660D01*
G01X1548177Y517563D02*
X1558736D01*
X1561831Y514468D01*
X1573854D01*
X1586431Y501891D01*
Y495207D01*
X1588188Y493450D01*
X1592050D01*
X1592483Y493017D01*
X1618748D01*
X1630965Y480800D01*
X1639543D01*
X1642086Y478257D01*
Y474614D01*
X1656100Y460600D01*
Y432451D01*
X1658400Y430151D01*
Y394384D01*
X1656542Y392526D01*
Y373319D01*
X1661999Y367862D01*
Y316559D01*
X1657639Y312199D01*
Y308404D01*
X1660488Y305555D01*
Y297496D01*
X1661227Y296757D01*
Y256270D01*
X1655000Y250043D01*
Y227073D01*
X1642900Y214973D01*
Y209673D01*
X1637877Y204650D01*
X1629743D01*
X1622872Y197779D01*
Y192672D01*
X1620600Y190400D01*
X1604695D01*
X1599620Y185325D01*
X1597351D01*
X1593784Y181758D01*
Y177468D01*
X1585732Y169416D01*
Y165576D01*
X1581393Y161237D01*
Y137458D01*
X1577450Y133515D01*
Y119250D01*
X1570250Y112050D01*
Y90569D01*
X1543291Y63610D01*
X1508622D01*
X1498846Y73386D01*
Y79711D01*
X1495930Y82627D01*
Y87650D01*
X1497436Y89156D01*
X1498550D01*
X1499875Y90481D01*
G01X1526744Y93265D02*
Y94740D01*
X1526294Y95190D01*
X1521792D01*
X1520340Y96642D01*
Y125166D01*
X1522232Y127058D01*
Y130936D01*
X1520664Y132504D01*
Y140754D01*
X1535491Y155581D01*
Y158192D01*
X1539048Y161749D01*
Y172203D01*
X1539681Y173160D01*
X1553030Y186509D01*
X1558420D01*
X1564040Y192129D01*
Y207202D01*
X1586073Y229235D01*
X1602592D01*
X1614300Y240943D01*
Y262010D01*
X1615750Y263460D01*
Y269672D01*
X1614416Y271006D01*
Y277047D01*
X1619950Y282581D01*
Y287737D01*
X1627800Y295587D01*
Y311072D01*
X1612016Y326856D01*
Y347591D01*
X1616425Y352000D01*
Y381658D01*
X1618500Y383733D01*
Y395100D01*
X1616550Y397050D01*
Y401778D01*
X1614824Y403504D01*
Y423136D01*
X1612464Y425496D01*
X1611526D01*
X1608575Y428447D01*
Y441974D01*
X1599739Y450810D01*
X1596519D01*
X1591066Y456263D01*
Y459483D01*
X1587946Y462603D01*
G01X1560517Y491357D02*
X1573274D01*
X1583481Y481150D01*
X1605229D01*
X1605879Y480500D01*
X1607229D01*
X1607879Y481150D01*
X1610967D01*
X1613928Y478189D01*
X1620037D01*
X1625914Y472312D01*
Y468741D01*
X1631055Y463600D01*
X1633287D01*
X1636700Y460187D01*
Y451872D01*
X1642500Y446072D01*
Y442395D01*
X1641850Y441745D01*
Y440395D01*
X1642500Y439745D01*
Y429700D01*
X1644400Y427800D01*
Y404735D01*
X1643750Y404085D01*
Y402735D01*
X1644400Y402085D01*
Y400735D01*
X1643750Y400085D01*
Y398735D01*
X1644400Y398085D01*
Y396735D01*
X1643750Y396085D01*
Y394735D01*
X1644400Y394085D01*
Y392735D01*
X1643750Y392085D01*
Y390735D01*
X1644400Y390085D01*
Y373622D01*
X1647292Y370730D01*
Y355871D01*
X1648891Y354272D01*
Y338221D01*
X1646987Y336317D01*
Y320858D01*
X1648147Y319698D01*
Y278889D01*
X1645750Y276493D01*
Y231299D01*
X1629967Y215516D01*
X1625783D01*
X1614267Y204000D01*
X1603184D01*
X1598638Y199454D01*
X1590602D01*
X1584300Y193152D01*
Y181149D01*
X1576482Y173331D01*
Y169412D01*
X1568800Y161730D01*
Y159699D01*
X1564350Y155249D01*
Y128523D01*
X1565350Y127523D01*
Y125877D01*
X1563800Y124327D01*
Y119827D01*
X1560087Y116114D01*
Y95299D01*
X1556831Y92043D01*
X1555911D01*
X1554957Y91088D01*
Y90169D01*
X1554002Y89214D01*
X1553083D01*
X1552129Y88260D01*
Y87341D01*
X1541447Y76659D01*
X1515610D01*
X1509150Y83119D01*
Y101999D01*
X1508277Y102872D01*
Y112065D01*
X1501943Y118399D01*
X1497581D01*
X1497145Y118842D01*
X1496726Y119261D01*
Y120588D01*
G01X1560517Y492507D02*
X1573751D01*
X1583958Y482300D01*
X1611444D01*
X1614405Y479339D01*
X1620514D01*
X1627064Y472789D01*
Y469218D01*
X1631532Y464750D01*
X1633764D01*
X1637850Y460664D01*
Y452349D01*
X1643650Y446549D01*
Y430177D01*
X1645550Y428277D01*
Y374099D01*
X1648442Y371207D01*
Y356348D01*
X1650041Y354749D01*
Y337744D01*
X1648137Y335840D01*
Y321335D01*
X1649297Y320175D01*
Y278412D01*
X1647364Y276479D01*
X1647363D01*
X1646900Y276016D01*
Y230822D01*
X1630444Y214366D01*
X1626260D01*
X1614744Y202850D01*
X1603661D01*
X1599115Y198304D01*
X1591079D01*
X1585450Y192675D01*
Y180672D01*
X1577632Y172854D01*
Y168935D01*
X1569950Y161253D01*
Y159222D01*
X1565500Y154772D01*
Y129000D01*
X1566500Y128000D01*
Y125400D01*
X1564950Y123850D01*
Y119350D01*
X1561237Y115637D01*
Y94822D01*
X1541924Y75509D01*
X1515133D01*
X1508000Y82642D01*
Y101522D01*
X1507127Y102395D01*
Y111588D01*
X1501466Y117249D01*
X1497300D01*
X1496658Y116607D01*
Y115088D01*
G01X1591822Y442371D02*
X1593202D01*
X1594877Y441263D01*
X1599394Y434574D01*
X1600776Y427782D01*
X1599794Y422957D01*
X1600084Y421531D01*
Y421530D01*
X1600274Y420596D01*
X1605608Y417064D01*
X1605858Y416814D01*
Y403692D01*
X1610167Y399383D01*
Y385916D01*
X1609849Y385598D01*
X1609850D01*
X1607609Y383357D01*
X1606330D01*
X1604040Y381066D01*
Y353644D01*
X1599823Y332919D01*
X1599822D01*
X1595607Y312196D01*
X1593997Y309762D01*
X1592551Y301459D01*
X1592683Y300627D01*
X1593937Y294500D01*
X1595530Y286716D01*
X1596274Y285590D01*
X1596091Y284689D01*
X1596836Y283564D01*
X1597737Y283380D01*
X1598482Y282254D01*
X1598299Y281353D01*
X1599044Y280228D01*
X1599945Y280044D01*
X1600690Y278918D01*
X1600507Y278017D01*
X1601252Y276892D01*
X1602153Y276708D01*
X1602898Y275582D01*
X1602715Y274681D01*
X1603460Y273556D01*
X1604361Y273372D01*
X1605528Y271609D01*
X1606612Y266282D01*
X1604531Y256053D01*
X1603764Y255545D01*
X1603495Y254222D01*
X1604003Y253456D01*
X1603733Y252133D01*
X1602967Y251625D01*
X1602698Y250303D01*
X1603205Y249536D01*
X1602702Y247063D01*
X1600278Y243401D01*
X1590780Y241470D01*
X1567272Y225910D01*
X1553349Y204874D01*
X1554471Y199354D01*
X1551318Y194591D01*
X1545665Y193441D01*
X1532779Y173973D01*
X1522594Y171900D01*
X1515312Y160901D01*
X1510664Y159956D01*
X1508503Y156690D01*
X1509899Y149829D01*
X1510127Y148711D01*
X1502878Y137758D01*
X1498391Y136844D01*
X1492600Y128098D01*
X1490184Y126498D01*
X1486980Y121657D01*
Y120073D01*
X1485830Y118923D01*
X1485189D01*
X1483366Y120746D01*
G01X1591822Y443521D02*
X1593548D01*
X1595703Y442097D01*
X1600476Y435028D01*
X1601859Y428233D01*
X1601999Y428020D01*
X1600968Y422957D01*
X1601307Y421292D01*
X1606340Y417960D01*
X1607008Y417291D01*
Y404169D01*
X1611317Y399860D01*
Y385438D01*
X1608087Y382207D01*
X1606807D01*
X1605190Y380589D01*
Y353528D01*
X1596690Y311747D01*
X1595089Y309328D01*
X1593717Y301450D01*
X1593815Y300833D01*
X1595111Y294500D01*
X1596612Y287166D01*
X1606611Y272058D01*
X1607786Y266282D01*
X1603785Y246614D01*
X1600975Y242368D01*
X1591229Y240387D01*
X1568102Y225080D01*
X1554571Y204636D01*
X1555694Y199116D01*
X1552015Y193558D01*
X1546362Y192408D01*
X1533476Y172940D01*
X1523290Y170868D01*
X1516008Y159869D01*
X1511361Y158923D01*
X1509726Y156452D01*
X1511073Y149829D01*
X1511349Y148473D01*
X1511350D01*
X1503575Y136725D01*
X1499087Y135812D01*
X1493430Y127268D01*
X1491014Y125668D01*
X1488130Y121310D01*
Y119596D01*
X1486307Y117773D01*
X1485237D01*
X1483366Y115902D01*
G01X1576943Y444525D02*
Y442720D01*
X1577569Y441559D01*
X1579392Y440353D01*
X1591753Y437837D01*
X1595722Y435209D01*
X1596789Y433598D01*
X1598062Y427341D01*
X1597092Y422573D01*
X1598098Y417629D01*
X1600254Y416201D01*
X1601354Y410798D01*
X1600319Y405707D01*
X1596388Y399771D01*
X1595679Y396283D01*
X1596525Y392122D01*
X1593677Y378122D01*
X1596027Y366580D01*
X1598836Y364721D01*
X1601259Y352805D01*
X1593390Y314118D01*
X1591524Y311303D01*
X1589739Y302763D01*
X1590269Y299447D01*
X1589368Y296123D01*
X1589940Y294356D01*
X1597012Y262211D01*
X1595303Y253809D01*
X1587919Y242655D01*
X1565356Y227720D01*
X1565192Y227472D01*
X1550285Y204951D01*
X1542857Y203440D01*
X1540085Y199252D01*
X1541582Y191894D01*
X1532973Y178889D01*
X1522420Y176742D01*
X1513453Y163192D01*
X1509015Y162289D01*
X1499067Y147257D01*
X1498060Y142312D01*
X1489202Y128931D01*
X1487588Y128602D01*
X1486551D01*
X1485738Y129025D01*
X1485735Y129027D01*
X1484113Y128513D01*
G01X1575793Y444525D02*
Y442429D01*
X1576693Y440758D01*
X1578944Y439270D01*
X1580963Y438859D01*
X1580967Y438858D01*
X1591304Y436753D01*
X1594892Y434379D01*
X1595706Y433149D01*
X1596888Y427341D01*
X1595918Y422573D01*
X1597066Y416933D01*
X1599222Y415505D01*
X1600180Y410798D01*
X1599236Y406156D01*
X1595305Y400220D01*
X1594505Y396283D01*
X1595351Y392122D01*
X1592503Y378122D01*
X1594994Y365883D01*
X1597803Y364024D01*
X1600085Y352806D01*
X1596196Y333687D01*
X1596197D01*
X1592307Y314567D01*
X1590443Y311754D01*
X1588569Y302791D01*
X1589094Y299509D01*
X1588168Y296094D01*
X1588559Y294886D01*
X1588560Y294884D01*
X1588828Y294054D01*
X1592376Y277929D01*
X1591881Y277155D01*
X1592171Y275836D01*
X1592945Y275341D01*
X1593235Y274023D01*
X1592740Y273248D01*
X1593030Y271930D01*
X1593805Y271435D01*
X1594095Y270116D01*
X1593600Y269342D01*
X1593890Y268023D01*
X1594664Y267528D01*
X1594954Y266210D01*
X1594459Y265435D01*
X1594749Y264117D01*
X1595524Y263621D01*
X1595836Y262202D01*
X1595519Y260643D01*
X1595518D01*
X1594220Y254258D01*
X1587089Y243485D01*
X1564526Y228550D01*
X1549588Y205984D01*
X1542160Y204473D01*
X1538863Y199490D01*
X1540360Y192132D01*
X1532277Y179921D01*
X1521723Y177775D01*
X1512756Y164225D01*
X1508318Y163322D01*
X1497984Y147706D01*
X1496977Y142761D01*
X1488506Y129963D01*
X1487471Y129752D01*
X1486833D01*
X1486269Y130046D01*
X1485755Y131671D01*
G01X1526513Y115769D02*
Y117244D01*
X1526963Y117694D01*
X1530665D01*
X1534701Y121730D01*
Y141194D01*
X1538351Y144844D01*
X1542580D01*
X1545248Y147512D01*
Y158446D01*
X1543132Y160562D01*
Y170641D01*
X1554477Y181986D01*
X1554715D01*
X1554716Y181987D01*
X1559527D01*
X1568150Y190610D01*
Y205707D01*
X1583768Y221325D01*
X1599852D01*
X1618150Y239623D01*
Y259454D01*
X1620543Y261847D01*
Y273982D01*
X1621938Y275377D01*
X1624086D01*
X1626250Y277541D01*
Y282349D01*
X1629070Y285169D01*
Y291343D01*
X1631615Y293888D01*
Y314601D01*
X1617124Y329092D01*
Y345163D01*
X1623373Y351412D01*
Y363435D01*
X1624926Y364988D01*
Y398228D01*
X1625775Y399077D01*
Y404572D01*
X1622200Y408147D01*
Y410700D01*
X1618474Y414426D01*
Y424650D01*
X1615925Y427199D01*
Y447373D01*
X1613623Y449675D01*
X1608717D01*
X1592054Y466338D01*
G01X1526513Y103958D02*
Y104857D01*
X1527554Y105898D01*
X1531083D01*
X1538362Y113177D01*
Y139574D01*
X1540655Y141867D01*
X1543140D01*
X1548204Y146931D01*
Y170904D01*
X1556139Y178839D01*
X1560660D01*
X1570650Y188829D01*
Y202510D01*
X1580872Y212732D01*
X1587018D01*
X1588900Y210850D01*
X1593176D01*
X1620860Y238534D01*
Y244669D01*
X1624302Y248111D01*
Y265075D01*
X1629450Y270223D01*
Y281250D01*
X1631600Y283400D01*
Y290200D01*
X1634115Y292715D01*
Y316012D01*
X1629030Y321097D01*
Y330963D01*
X1623426Y336567D01*
Y347928D01*
X1625873Y350375D01*
Y360570D01*
X1627462Y362159D01*
Y397227D01*
X1628275Y398040D01*
Y406044D01*
X1625092Y409227D01*
Y428484D01*
X1622743Y430833D01*
X1619603D01*
X1618460Y431976D01*
Y448375D01*
X1614660Y452175D01*
X1610361D01*
X1608899Y453637D01*
Y456041D01*
X1595103Y469837D01*
X1586693D01*
G01X1526513Y120769D02*
Y119294D01*
X1526963Y118844D01*
X1530188D01*
X1533551Y122207D01*
Y141671D01*
X1537874Y145994D01*
X1542103D01*
X1544098Y147989D01*
Y157969D01*
X1541982Y160085D01*
Y171118D01*
X1554000Y183136D01*
X1554715D01*
X1554716Y183137D01*
X1559050D01*
X1567000Y191087D01*
Y206184D01*
X1583291Y222475D01*
X1599375D01*
X1617000Y240100D01*
Y259931D01*
X1619393Y262324D01*
Y274459D01*
X1621461Y276527D01*
X1623609D01*
X1625100Y278018D01*
Y282826D01*
X1627920Y285646D01*
Y291820D01*
X1630465Y294365D01*
Y314124D01*
X1629510Y315079D01*
X1628591D01*
X1627637Y316033D01*
Y316952D01*
X1626682Y317907D01*
X1625763D01*
X1624809Y318861D01*
Y319780D01*
X1615974Y328615D01*
Y345640D01*
X1622223Y351889D01*
Y363912D01*
X1623776Y365465D01*
Y398705D01*
X1624625Y399554D01*
Y404095D01*
X1621050Y407670D01*
Y410223D01*
X1617324Y413949D01*
Y424173D01*
X1614775Y426722D01*
Y446896D01*
X1613146Y448525D01*
X1608240D01*
X1607231Y449534D01*
X1606312D01*
X1605357Y450488D01*
Y451408D01*
X1604403Y452362D01*
X1603483D01*
X1602529Y453317D01*
Y454236D01*
X1601574Y455191D01*
X1600655D01*
X1599700Y456145D01*
Y457065D01*
X1598746Y458019D01*
X1597827D01*
X1596872Y458974D01*
Y459893D01*
X1591241Y465524D01*
G01X1526813Y108958D02*
Y108015D01*
X1527780Y107048D01*
X1530606D01*
X1537212Y113654D01*
Y140051D01*
X1540178Y143017D01*
X1542663D01*
X1547054Y147408D01*
Y171381D01*
X1555662Y179989D01*
X1560183D01*
X1569500Y189306D01*
Y202987D01*
X1580395Y213882D01*
X1587495D01*
X1589377Y212000D01*
X1592699D01*
X1619710Y239011D01*
Y245146D01*
X1623152Y248588D01*
Y249705D01*
X1622502Y250355D01*
Y251705D01*
X1623152Y252355D01*
Y253705D01*
X1622502Y254355D01*
Y255705D01*
X1623152Y256355D01*
Y265552D01*
X1624579Y266979D01*
Y267387D01*
X1624577Y267389D01*
Y267797D01*
X1625604Y268824D01*
X1626012D01*
X1626014Y268822D01*
X1626422D01*
X1628300Y270700D01*
Y281727D01*
X1630450Y283877D01*
Y290677D01*
X1632965Y293192D01*
Y315535D01*
X1627880Y320620D01*
Y330486D01*
X1622276Y336090D01*
Y348405D01*
X1624723Y350852D01*
Y361047D01*
X1626312Y362636D01*
Y397704D01*
X1627125Y398517D01*
Y405567D01*
X1623942Y408750D01*
Y428007D01*
X1622266Y429683D01*
X1619126D01*
X1617309Y431500D01*
Y432452D01*
X1617310Y432453D01*
Y447898D01*
X1614183Y451025D01*
X1609884D01*
X1607749Y453159D01*
Y455564D01*
X1605940Y457373D01*
X1605020D01*
X1604066Y458328D01*
Y459247D01*
X1603111Y460202D01*
X1602192D01*
X1601237Y461156D01*
Y462076D01*
X1600283Y463030D01*
X1599364D01*
X1598409Y463985D01*
Y464904D01*
X1597454Y465859D01*
X1596535D01*
X1595581Y466813D01*
Y467732D01*
X1594626Y468687D01*
X1586693D01*
G01X1526744Y98265D02*
Y96790D01*
X1526294Y96340D01*
X1522269D01*
X1521490Y97119D01*
Y124689D01*
X1523382Y126581D01*
Y131413D01*
X1521814Y132981D01*
Y140277D01*
X1536641Y155104D01*
Y157715D01*
X1540198Y161272D01*
Y171857D01*
X1540577Y172428D01*
X1553507Y185359D01*
X1558897D01*
X1565190Y191652D01*
Y206725D01*
X1586550Y228085D01*
X1603069D01*
X1615450Y240466D01*
Y261533D01*
X1616900Y262983D01*
Y270149D01*
X1615566Y271483D01*
Y276570D01*
X1621100Y282104D01*
Y287260D01*
X1628950Y295110D01*
Y311549D01*
X1613166Y327333D01*
Y347114D01*
X1617575Y351523D01*
Y381181D01*
X1619650Y383256D01*
Y395577D01*
X1617700Y397527D01*
Y402255D01*
X1615974Y403981D01*
Y423613D01*
X1612941Y426646D01*
X1612003D01*
X1609725Y428924D01*
Y442452D01*
X1607190Y444987D01*
Y445906D01*
X1606235Y446861D01*
X1605316D01*
X1604361Y447816D01*
Y448791D01*
X1603407Y449746D01*
X1602431D01*
X1600217Y451960D01*
X1596996D01*
X1592216Y456740D01*
Y459960D01*
X1588759Y463417D01*
G01X1576929Y456839D02*
X1577724Y456043D01*
X1579669Y454099D01*
Y453036D01*
X1583017Y449688D01*
X1594010D01*
X1606625Y437073D01*
Y422293D01*
X1610237Y418681D01*
Y405333D01*
X1614600Y400970D01*
Y395227D01*
X1616480Y393347D01*
Y385179D01*
X1614200Y382899D01*
Y355702D01*
X1607418Y348920D01*
X1606848Y346123D01*
Y317103D01*
X1604836Y315091D01*
X1604837D01*
X1600647Y310901D01*
X1598530Y306620D01*
Y299668D01*
X1600745Y294045D01*
X1609959Y284834D01*
Y276736D01*
X1612466Y274229D01*
Y270198D01*
X1613400Y269264D01*
Y263892D01*
X1612050Y262542D01*
Y241451D01*
X1601951Y231352D01*
X1585109D01*
X1561260Y207503D01*
Y198376D01*
X1549100Y186216D01*
Y185641D01*
X1538757Y175298D01*
X1535370Y170181D01*
X1535366Y170180D01*
X1535087Y169758D01*
X1535086D01*
X1534497Y168866D01*
X1530014Y164384D01*
X1524788D01*
X1520196Y159792D01*
Y143628D01*
X1517960Y141392D01*
Y133219D01*
X1515077Y130336D01*
X1502647D01*
X1500700Y128389D01*
Y127250D01*
G01X1576116Y456025D02*
X1578519Y453622D01*
Y452559D01*
X1582540Y448538D01*
X1593533D01*
X1605475Y436596D01*
Y421816D01*
X1609087Y418204D01*
Y404856D01*
X1613450Y400493D01*
Y394750D01*
X1615330Y392870D01*
Y389248D01*
X1615329Y389247D01*
Y388295D01*
X1615330Y388294D01*
Y385656D01*
X1613050Y383376D01*
Y356179D01*
X1606360Y349489D01*
X1605698Y346239D01*
Y317580D01*
X1599699Y311581D01*
X1597380Y306889D01*
Y299449D01*
X1599762Y293400D01*
X1608809Y284354D01*
Y276259D01*
X1611316Y273752D01*
Y269721D01*
X1612250Y268787D01*
Y264369D01*
X1610900Y263019D01*
Y241928D01*
X1601474Y232502D01*
X1584632D01*
X1578020Y225890D01*
X1577101D01*
X1576147Y224936D01*
Y224017D01*
X1575192Y223062D01*
X1574273D01*
X1573318Y222107D01*
Y221188D01*
X1572363Y220233D01*
X1571444D01*
X1570490Y219279D01*
Y218360D01*
X1560110Y207980D01*
Y198853D01*
X1547950Y186693D01*
Y186118D01*
X1547457Y185626D01*
X1537861Y176030D01*
X1534657Y171189D01*
X1534653Y171188D01*
X1533601Y169598D01*
X1529537Y165534D01*
X1524311D01*
X1519046Y160269D01*
Y156742D01*
X1518396Y156092D01*
Y154742D01*
X1519046Y154092D01*
Y152742D01*
X1518396Y152092D01*
Y150742D01*
X1519046Y150092D01*
Y148742D01*
X1518396Y148092D01*
Y146742D01*
X1519046Y146092D01*
Y144105D01*
X1516810Y141869D01*
Y133696D01*
X1514600Y131486D01*
X1501256D01*
X1500806Y131936D01*
Y133339D01*
G01X1470262Y420711D02*
X1469359Y421614D01*
Y421996D01*
X1470345Y422982D01*
X1475357D01*
X1477043Y424668D01*
Y428042D01*
X1477825Y428824D01*
Y487257D01*
X1484268Y493700D01*
X1496503D01*
X1498353Y491850D01*
X1513617D01*
X1520313Y498546D01*
Y503934D01*
X1521279Y504900D01*
Y507210D01*
X1539182Y525113D01*
X1562124D01*
X1565047Y522190D01*
X1576902D01*
X1592292Y506800D01*
X1626343D01*
X1629172Y503971D01*
X1637897D01*
X1640499Y501369D01*
X1655748D01*
X1664000Y493117D01*
Y483573D01*
X1669773Y477800D01*
X1676723D01*
X1677902Y478979D01*
X1682968D01*
X1684713Y477234D01*
X1720267D01*
X1725601Y471900D01*
X1735419D01*
X1738882Y468437D01*
X1740336D01*
X1741154Y467619D01*
Y464298D01*
X1743177Y462275D01*
X1748645D01*
X1750668Y464298D01*
Y467819D01*
X1751118Y468269D01*
X1752268D01*
X1752718Y467819D01*
Y463789D01*
X1754741Y461766D01*
X1759183D01*
X1764145Y466728D01*
X1765295D01*
X1765745Y466278D01*
Y463851D01*
X1767768Y461828D01*
X1774364D01*
X1776387Y463851D01*
Y465546D01*
X1776837Y465996D01*
X1777987D01*
X1778437Y465546D01*
Y463850D01*
X1780460Y461827D01*
X1786149D01*
X1788172Y463850D01*
Y469471D01*
X1788622Y469921D01*
X1790172D01*
X1790622Y469471D01*
Y463789D01*
X1792645Y461766D01*
X1796342D01*
X1800887Y466311D01*
Y467400D01*
X1801337Y467850D01*
X1802887D01*
X1803337Y467400D01*
Y465512D01*
X1805360Y463489D01*
X1810664D01*
X1813029Y465854D01*
Y468386D01*
X1811435Y469980D01*
Y470614D01*
X1812253Y471432D01*
X1816173D01*
X1819988Y475247D01*
X1821538D01*
X1821988Y474797D01*
Y471789D01*
X1824011Y469766D01*
X1826555D01*
X1829895Y473106D01*
X1831416D01*
X1833915Y475605D01*
Y481589D01*
X1834565Y482239D01*
Y483589D01*
X1833915Y484239D01*
Y485589D01*
X1834565Y486239D01*
Y487589D01*
X1833915Y488239D01*
Y489589D01*
X1834565Y490239D01*
Y491589D01*
X1833915Y492239D01*
Y493589D01*
X1837698Y497372D01*
X1838617D01*
X1839572Y498327D01*
Y499246D01*
X1841675Y501349D01*
X1847477D01*
X1849700Y503572D01*
Y509732D01*
X1850733Y510765D01*
X1855587D01*
X1863575Y502777D01*
Y493412D01*
X1861393Y491230D01*
X1860474D01*
X1859520Y490276D01*
Y489357D01*
X1858565Y488402D01*
X1857646D01*
X1856691Y487447D01*
Y486528D01*
X1855736Y485573D01*
X1854817D01*
X1853863Y484619D01*
Y483700D01*
X1852776Y482613D01*
Y475429D01*
X1847746Y470399D01*
Y461429D01*
X1842600Y456283D01*
Y455291D01*
X1841630Y454321D01*
G01X1844630D02*
X1843750Y455201D01*
Y455806D01*
X1848896Y460952D01*
Y469922D01*
X1853926Y474952D01*
Y482136D01*
X1864725Y492935D01*
Y503254D01*
X1856064Y511915D01*
X1850256D01*
X1848550Y510209D01*
Y504049D01*
X1847000Y502499D01*
X1841198D01*
X1832765Y494066D01*
Y476082D01*
X1830939Y474256D01*
X1829418D01*
X1826078Y470916D01*
X1824488D01*
X1823138Y472266D01*
Y475274D01*
X1822015Y476397D01*
X1819511D01*
X1815696Y472582D01*
X1811776D01*
X1810285Y471091D01*
Y469503D01*
X1811879Y467909D01*
Y466331D01*
X1810187Y464639D01*
X1805837D01*
X1804487Y465989D01*
Y467877D01*
X1803364Y469000D01*
X1800860D01*
X1799737Y467877D01*
Y466788D01*
X1795865Y462916D01*
X1793122D01*
X1791772Y464266D01*
Y469948D01*
X1790649Y471071D01*
X1788145D01*
X1787022Y469948D01*
Y464327D01*
X1785672Y462977D01*
X1780937D01*
X1779587Y464327D01*
Y466023D01*
X1778464Y467146D01*
X1776360D01*
X1775237Y466023D01*
Y464328D01*
X1773887Y462978D01*
X1768245D01*
X1766895Y464328D01*
Y466755D01*
X1765772Y467878D01*
X1763668D01*
X1758706Y462916D01*
X1755218D01*
X1753868Y464266D01*
Y468296D01*
X1752745Y469419D01*
X1750641D01*
X1749518Y468296D01*
Y464775D01*
X1748168Y463425D01*
X1743654D01*
X1742304Y464775D01*
Y468096D01*
X1740813Y469587D01*
X1739359D01*
X1735896Y473050D01*
X1726078D01*
X1720744Y478384D01*
X1685190D01*
X1683445Y480129D01*
X1677425D01*
X1676246Y478950D01*
X1670250D01*
X1665150Y484050D01*
Y493594D01*
X1656225Y502519D01*
X1640976D01*
X1638374Y505121D01*
X1629649D01*
X1626820Y507950D01*
X1592769D01*
X1577379Y523340D01*
X1565524D01*
X1562601Y526263D01*
X1538705D01*
X1520129Y507687D01*
Y505377D01*
X1519163Y504411D01*
Y499023D01*
X1513140Y493000D01*
X1498830D01*
X1496980Y494850D01*
X1483791D01*
X1476675Y487734D01*
Y429301D01*
X1475893Y428519D01*
Y425145D01*
X1474880Y424132D01*
X1469868D01*
X1468209Y422473D01*
Y421658D01*
X1467262Y420711D01*
G01X1837857Y468630D02*
X1839332D01*
X1839782Y469080D01*
Y470194D01*
X1841565Y471977D01*
X1845061D01*
X1846016Y472932D01*
Y473851D01*
X1846970Y474805D01*
X1847889D01*
X1849480Y476396D01*
Y477746D01*
X1848830Y478396D01*
Y479746D01*
X1849480Y480396D01*
Y482588D01*
X1849130Y482938D01*
X1845106D01*
X1830663Y468495D01*
Y466143D01*
X1831563Y465243D01*
X1836693D01*
X1839680Y462256D01*
Y458278D01*
X1837957Y456555D01*
X1835434D01*
X1833711Y458278D01*
Y459501D01*
X1833261Y459951D01*
X1828511D01*
X1826213Y462249D01*
Y463435D01*
X1825863Y463785D01*
X1824113D01*
X1823763Y463435D01*
Y461951D01*
X1817763Y455951D01*
X1804740D01*
X1802360Y458331D01*
X1799737D01*
X1797357Y455951D01*
X1793776D01*
X1791396Y458331D01*
X1788773D01*
X1786393Y455951D01*
X1782812D01*
X1780432Y458331D01*
X1777809D01*
X1775429Y455951D01*
X1771848D01*
X1769468Y458331D01*
X1766845D01*
X1764465Y455951D01*
X1760884D01*
X1758504Y458331D01*
X1755881D01*
X1753499Y455949D01*
X1749922D01*
X1747540Y458331D01*
X1744917D01*
X1742535Y455949D01*
X1738802D01*
X1736292Y458459D01*
Y463115D01*
X1735531Y463876D01*
X1722901D01*
X1712229Y474548D01*
X1683737D01*
X1681867Y476418D01*
X1678878D01*
X1677710Y475250D01*
X1667323D01*
X1661500Y481073D01*
Y484080D01*
X1660850Y484730D01*
Y486080D01*
X1661500Y486730D01*
Y488080D01*
X1660850Y488730D01*
Y490080D01*
X1661500Y490730D01*
Y492080D01*
X1660461Y493119D01*
X1659542D01*
X1658588Y494073D01*
Y494992D01*
X1657633Y495947D01*
X1656714D01*
X1655760Y496901D01*
Y497820D01*
X1654805Y498775D01*
X1651332D01*
X1650682Y498125D01*
X1649332D01*
X1648682Y498775D01*
X1647332D01*
X1646682Y498125D01*
X1645332D01*
X1644682Y498775D01*
X1643332D01*
X1642682Y498125D01*
X1641332D01*
X1640682Y498775D01*
X1637706D01*
X1635112Y501369D01*
X1628173D01*
X1625242Y504300D01*
X1591185D01*
X1575967Y519518D01*
X1564181D01*
X1561086Y522613D01*
X1540303D01*
X1523799Y506109D01*
Y503723D01*
X1522882Y502806D01*
Y496942D01*
X1515300Y489360D01*
X1496693D01*
X1494625Y491428D01*
X1485470D01*
X1480226Y486184D01*
Y427141D01*
X1479379Y426294D01*
Y417850D01*
X1479895Y417334D01*
X1480887D01*
G01X1842857Y468630D02*
X1841382D01*
X1840932Y469080D01*
Y469717D01*
X1842042Y470827D01*
X1845538D01*
X1850630Y475919D01*
Y483065D01*
X1849607Y484088D01*
X1844629D01*
X1829513Y468972D01*
Y465666D01*
X1831086Y464093D01*
X1836216D01*
X1838530Y461779D01*
Y458755D01*
X1837480Y457705D01*
X1835911D01*
X1834861Y458755D01*
Y459978D01*
X1833738Y461101D01*
X1828988D01*
X1827363Y462726D01*
Y463912D01*
X1826340Y464935D01*
X1823636D01*
X1822613Y463912D01*
Y462428D01*
X1817286Y457101D01*
X1805217D01*
X1802837Y459481D01*
X1799260D01*
X1796880Y457101D01*
X1794253D01*
X1791873Y459481D01*
X1788296D01*
X1785916Y457101D01*
X1783289D01*
X1780909Y459481D01*
X1777332D01*
X1774952Y457101D01*
X1772325D01*
X1769945Y459481D01*
X1766368D01*
X1763988Y457101D01*
X1761361D01*
X1758981Y459481D01*
X1755404D01*
X1753022Y457099D01*
X1750399D01*
X1748017Y459481D01*
X1744440D01*
X1742058Y457099D01*
X1739279D01*
X1737442Y458936D01*
Y463592D01*
X1736008Y465026D01*
X1723378D01*
X1712706Y475698D01*
X1684214D01*
X1682344Y477568D01*
X1678401D01*
X1677233Y476400D01*
X1667800D01*
X1662650Y481550D01*
Y492557D01*
X1655282Y499925D01*
X1638183D01*
X1635589Y502519D01*
X1628650D01*
X1625719Y505450D01*
X1591662D01*
X1576444Y520668D01*
X1564658D01*
X1561563Y523763D01*
X1539826D01*
X1522649Y506586D01*
Y504200D01*
X1521732Y503283D01*
Y497419D01*
X1514823Y490510D01*
X1497170D01*
X1495102Y492578D01*
X1484993D01*
X1479076Y486661D01*
Y427618D01*
X1478229Y426771D01*
Y417373D01*
X1479418Y416184D01*
X1480887D01*
G01X1622248Y185060D02*
X1621364Y185944D01*
Y187241D01*
X1620266Y188339D01*
X1607402D01*
X1605030Y185967D01*
Y183956D01*
X1604330Y183256D01*
Y179712D01*
X1601468Y176850D01*
X1595924D01*
X1587700Y168626D01*
Y164751D01*
X1583385Y160436D01*
Y115411D01*
X1579350Y111376D01*
Y108224D01*
X1582100Y105474D01*
Y92027D01*
X1580631Y90558D01*
Y85964D01*
X1583079Y83516D01*
X1583765D01*
X1585207Y82074D01*
Y80507D01*
X1584335Y79635D01*
Y74770D01*
X1581707Y72142D01*
Y67961D01*
X1584128Y65540D01*
X1597697D01*
X1600347Y62890D01*
X1608452D01*
G01X1619500Y184944D02*
X1620214Y185658D01*
Y186764D01*
X1619789Y187189D01*
X1607879D01*
X1606180Y185490D01*
Y183479D01*
X1605480Y182779D01*
Y179235D01*
X1601945Y175700D01*
X1596401D01*
X1588850Y168149D01*
Y164274D01*
X1584535Y159959D01*
Y148058D01*
X1585185Y147408D01*
Y146008D01*
X1584535Y145358D01*
Y143958D01*
X1585185Y143308D01*
Y141908D01*
X1584535Y141258D01*
Y139858D01*
X1585185Y139208D01*
Y137808D01*
X1584535Y137158D01*
Y131118D01*
X1585185Y130468D01*
Y129118D01*
X1584535Y128468D01*
Y127118D01*
X1585185Y126468D01*
Y125118D01*
X1584535Y124468D01*
Y123118D01*
X1585185Y122468D01*
Y121118D01*
X1584535Y120468D01*
Y119118D01*
X1585185Y118468D01*
Y117118D01*
X1584535Y116468D01*
Y114934D01*
X1580500Y110899D01*
Y108701D01*
X1583250Y105951D01*
Y99550D01*
X1583900Y98900D01*
Y97550D01*
X1583250Y96900D01*
Y95550D01*
X1583900Y94900D01*
Y93550D01*
X1583250Y92900D01*
Y91550D01*
X1581781Y90081D01*
Y86441D01*
X1583556Y84666D01*
X1584242D01*
X1586357Y82551D01*
Y80030D01*
X1585485Y79158D01*
Y74293D01*
X1582857Y71665D01*
Y68438D01*
X1584605Y66690D01*
X1585759D01*
X1586409Y67340D01*
X1587809D01*
X1588459Y66690D01*
X1589859D01*
X1590509Y67340D01*
X1591909D01*
X1592559Y66690D01*
X1598174D01*
X1600824Y64040D01*
X1605888D01*
X1606797Y64949D01*
G01X1558100Y128926D02*
X1556449Y127275D01*
X1550337D01*
X1547541Y130071D01*
Y141654D01*
X1551933Y146046D01*
Y154453D01*
X1551304Y155082D01*
Y165804D01*
X1554637Y169137D01*
X1560635D01*
X1564839Y173341D01*
Y176497D01*
X1565595Y177253D01*
X1567347D01*
X1569651Y179557D01*
Y182250D01*
X1573750Y186349D01*
Y200350D01*
X1575145Y201745D01*
X1576064D01*
X1577018Y202699D01*
Y203618D01*
X1577973Y204573D01*
X1578892D01*
X1579846Y205527D01*
Y206446D01*
X1582720Y209320D01*
X1585480D01*
X1587145Y207655D01*
X1595182D01*
X1619827Y232300D01*
X1628727D01*
X1632350Y235923D01*
Y255267D01*
X1633000Y255917D01*
Y257267D01*
X1632350Y257917D01*
Y259623D01*
X1634700Y261973D01*
Y284131D01*
X1635550Y284981D01*
X1638225D01*
X1639997Y286753D01*
Y306304D01*
X1637215Y309086D01*
Y317612D01*
X1633450Y321377D01*
Y325923D01*
X1634046Y326519D01*
Y330464D01*
X1626526Y337984D01*
Y345932D01*
X1633933Y353339D01*
Y405843D01*
X1628295Y411481D01*
Y431206D01*
X1624492Y435009D01*
Y452734D01*
X1620826Y456400D01*
X1615577D01*
X1612727Y459250D01*
X1610369D01*
X1607794Y461825D01*
Y464367D01*
X1608444Y465017D01*
Y466367D01*
X1607794Y467017D01*
Y468367D01*
X1610959Y471532D01*
X1615133D01*
X1616382Y472781D01*
Y474639D01*
X1617700Y475957D01*
G01X1558100Y124427D02*
X1556402Y126125D01*
X1549860D01*
X1546391Y129594D01*
Y142131D01*
X1550783Y146523D01*
Y153976D01*
X1550154Y154605D01*
Y166281D01*
X1554160Y170287D01*
X1560158D01*
X1563689Y173818D01*
Y176974D01*
X1565118Y178403D01*
X1566870D01*
X1568501Y180034D01*
Y182727D01*
X1572600Y186826D01*
Y200827D01*
X1582243Y210470D01*
X1585957D01*
X1587622Y208805D01*
X1594705D01*
X1619350Y233450D01*
X1628250D01*
X1631200Y236400D01*
Y260100D01*
X1633550Y262450D01*
Y284608D01*
X1635073Y286131D01*
X1637748D01*
X1638847Y287230D01*
Y305827D01*
X1636065Y308609D01*
Y317135D01*
X1632300Y320900D01*
Y326400D01*
X1632896Y326996D01*
Y329987D01*
X1625376Y337507D01*
Y346409D01*
X1632783Y353816D01*
Y405366D01*
X1627145Y411004D01*
Y430729D01*
X1623342Y434532D01*
Y452257D01*
X1620349Y455250D01*
X1615100D01*
X1612250Y458100D01*
X1609892D01*
X1606644Y461348D01*
Y468844D01*
X1610482Y472682D01*
X1614656D01*
X1615232Y473258D01*
Y474738D01*
X1614000Y475970D01*
G01X1623749Y464213D02*
Y464902D01*
X1624160Y465313D01*
X1624867D01*
X1629780Y460400D01*
X1631861D01*
X1633500Y458761D01*
Y438873D01*
X1635425Y436948D01*
Y429775D01*
X1640650Y424550D01*
Y372932D01*
X1641825Y371757D01*
Y371112D01*
X1643951Y368982D01*
Y353998D01*
X1645525Y352424D01*
Y342342D01*
X1643473Y340290D01*
Y319979D01*
X1645047Y318405D01*
Y280175D01*
X1642650Y277778D01*
Y249977D01*
X1640500Y247827D01*
Y240528D01*
X1637650Y237678D01*
Y227584D01*
X1632616Y222550D01*
X1626431D01*
X1623779Y219898D01*
Y217898D01*
X1612982Y207100D01*
X1601899D01*
X1597353Y202554D01*
X1587932D01*
X1578800Y193422D01*
Y180135D01*
X1564813Y166148D01*
Y160140D01*
X1560533Y155860D01*
Y148870D01*
X1559883Y148220D01*
Y146870D01*
X1560533Y146220D01*
Y144870D01*
X1559883Y144220D01*
Y142870D01*
X1560533Y142220D01*
Y136794D01*
X1560133Y136394D01*
Y122449D01*
X1560325Y122257D01*
Y120743D01*
X1559257Y119675D01*
X1558676D01*
X1554400Y115399D01*
Y112973D01*
X1553750Y112323D01*
Y110973D01*
X1554400Y110323D01*
Y108973D01*
X1553750Y108323D01*
Y106973D01*
X1554400Y106323D01*
Y104973D01*
X1555800Y103573D01*
Y102050D01*
X1554627Y100877D01*
G01X1623705Y467855D02*
Y467059D01*
X1624301Y466463D01*
X1625344D01*
X1630257Y461550D01*
X1632338D01*
X1634650Y459238D01*
Y439350D01*
X1636575Y437425D01*
Y430252D01*
X1641800Y425027D01*
Y373409D01*
X1642975Y372234D01*
Y371588D01*
X1645101Y369458D01*
Y354475D01*
X1646675Y352901D01*
Y341865D01*
X1644623Y339813D01*
Y320456D01*
X1646197Y318882D01*
Y279698D01*
X1643800Y277301D01*
Y249500D01*
X1641650Y247350D01*
Y240051D01*
X1638800Y237201D01*
Y227107D01*
X1633093Y221400D01*
X1626908D01*
X1624929Y219421D01*
Y217421D01*
X1613459Y205950D01*
X1602376D01*
X1597830Y201404D01*
X1588409D01*
X1579950Y192945D01*
Y179658D01*
X1565963Y165671D01*
Y159663D01*
X1561683Y155383D01*
Y136317D01*
X1561283Y135917D01*
Y122926D01*
X1561475Y122734D01*
Y120266D01*
X1559734Y118525D01*
X1559153D01*
X1555550Y114922D01*
Y105450D01*
X1556950Y104050D01*
Y102063D01*
X1558136Y100877D01*
G01X1619607Y469945D02*
X1618598Y468936D01*
Y462032D01*
X1620630Y460000D01*
X1622499D01*
X1627650Y454849D01*
Y436477D01*
X1633475Y430652D01*
Y428925D01*
X1637550Y424850D01*
Y418177D01*
X1638200Y417527D01*
Y416177D01*
X1637550Y415527D01*
Y414177D01*
X1638200Y413527D01*
Y412177D01*
X1637550Y411527D01*
Y410177D01*
X1638200Y409527D01*
Y408177D01*
X1637550Y407527D01*
Y353178D01*
X1637166Y352794D01*
Y348818D01*
X1639437Y346547D01*
Y330915D01*
X1641061Y329291D01*
Y319389D01*
X1643097Y317353D01*
Y281197D01*
X1640450Y278550D01*
Y251250D01*
X1635450Y246250D01*
Y234638D01*
X1629662Y228850D01*
X1620976D01*
X1609300Y217174D01*
Y213224D01*
X1605243Y209167D01*
X1601079D01*
X1596467Y204555D01*
X1596383D01*
X1596377Y204549D01*
X1587169D01*
X1576850Y194230D01*
Y180943D01*
X1556886Y160979D01*
Y158236D01*
X1557949Y157173D01*
Y149825D01*
X1555256Y147132D01*
Y145064D01*
X1555033Y144841D01*
Y144761D01*
X1550821Y140549D01*
Y138599D01*
X1552405Y137015D01*
X1555265D01*
X1555979Y136301D01*
X1557536D01*
X1558100Y136865D01*
Y138025D01*
G01X1616607Y469945D02*
X1617448Y469104D01*
Y461555D01*
X1620153Y458850D01*
X1622022D01*
X1626500Y454372D01*
Y436000D01*
X1632325Y430175D01*
Y428448D01*
X1636400Y424373D01*
Y353655D01*
X1636016Y353271D01*
Y348341D01*
X1638287Y346070D01*
Y330438D01*
X1639911Y328814D01*
Y318912D01*
X1641947Y316876D01*
Y281674D01*
X1639300Y279027D01*
Y251727D01*
X1634300Y246727D01*
Y235115D01*
X1629185Y230000D01*
X1620499D01*
X1608150Y217651D01*
Y213701D01*
X1604766Y210317D01*
X1600602D01*
X1595990Y205705D01*
X1595906D01*
X1595900Y205699D01*
X1586692D01*
X1575700Y194707D01*
Y181420D01*
X1555736Y161456D01*
Y157759D01*
X1556799Y156696D01*
Y150302D01*
X1554106Y147609D01*
Y145541D01*
X1553883Y145318D01*
Y145238D01*
X1549671Y141026D01*
Y138122D01*
X1551928Y135865D01*
X1554788D01*
X1555502Y135151D01*
X1557650D01*
X1558100Y134701D01*
Y133526D01*
G01X1531685Y499540D02*
X1530897Y500328D01*
X1529915D01*
X1529465Y499878D01*
Y497708D01*
X1530523Y496650D01*
X1534995D01*
X1536408Y498063D01*
Y515237D01*
X1541834Y520663D01*
X1560200D01*
X1563295Y517568D01*
X1575149D01*
X1590367Y502350D01*
X1624362D01*
X1627323Y499389D01*
X1632110D01*
X1636685Y494814D01*
X1639847D01*
X1640613Y494048D01*
X1645180D01*
X1647724Y491504D01*
Y483404D01*
X1649730Y481398D01*
Y477035D01*
X1667014Y459751D01*
Y449558D01*
X1662300Y444844D01*
Y435888D01*
X1665162Y433026D01*
Y411837D01*
X1668249Y408750D01*
Y313520D01*
X1667446Y312717D01*
Y264832D01*
X1673804Y258474D01*
Y253363D01*
X1670075Y249634D01*
Y241734D01*
X1669320Y240979D01*
Y240681D01*
X1667579Y238940D01*
X1667281D01*
X1663998Y235657D01*
Y221149D01*
X1657328Y214479D01*
Y212120D01*
X1641863Y196655D01*
Y194083D01*
X1639430Y191650D01*
X1631530D01*
X1630195Y192985D01*
Y194099D01*
X1628950Y195344D01*
G01X1531685Y502040D02*
X1531123Y501478D01*
X1529438D01*
X1528315Y500355D01*
Y497231D01*
X1530046Y495500D01*
X1535472D01*
X1537558Y497586D01*
Y514760D01*
X1542311Y519513D01*
X1559723D01*
X1562818Y516418D01*
X1574672D01*
X1589890Y501200D01*
X1623885D01*
X1626846Y498239D01*
X1631633D01*
X1636208Y493664D01*
X1639370D01*
X1640136Y492898D01*
X1644703D01*
X1646574Y491027D01*
Y482927D01*
X1648580Y480921D01*
Y476558D01*
X1665864Y459274D01*
Y450035D01*
X1661150Y445321D01*
Y435411D01*
X1664012Y432549D01*
Y411360D01*
X1667099Y408273D01*
Y313997D01*
X1666296Y313194D01*
Y264355D01*
X1672654Y257997D01*
Y253840D01*
X1668925Y250111D01*
Y242211D01*
X1668170Y241456D01*
Y241158D01*
X1667102Y240090D01*
X1666804D01*
X1662848Y236134D01*
Y221626D01*
X1656178Y214956D01*
Y212597D01*
X1652025Y208444D01*
X1651106D01*
X1650152Y207490D01*
Y206571D01*
X1649197Y205616D01*
X1648278D01*
X1647324Y204662D01*
Y203743D01*
X1646369Y202788D01*
X1645450D01*
X1644496Y201834D01*
Y200915D01*
X1643541Y199960D01*
X1642622D01*
X1641668Y199006D01*
Y198087D01*
X1640713Y197132D01*
Y194560D01*
X1638953Y192800D01*
X1632007D01*
X1631345Y193462D01*
Y194099D01*
X1632590Y195344D01*
G01X1635351Y185444D02*
X1636850Y183945D01*
Y182177D01*
X1635641Y180968D01*
X1634285D01*
X1632239Y183014D01*
Y187382D01*
X1625979Y193642D01*
Y196501D01*
X1630878Y201400D01*
X1639864D01*
X1651250Y212786D01*
Y218938D01*
X1658100Y225787D01*
Y248758D01*
X1664327Y254985D01*
Y306101D01*
X1662254Y308174D01*
Y311967D01*
X1665124Y314837D01*
Y369122D01*
X1659687Y374559D01*
Y381952D01*
X1664491Y386756D01*
Y407908D01*
X1661787Y410612D01*
Y431475D01*
X1659200Y434062D01*
Y461885D01*
X1659095Y461990D01*
Y462192D01*
X1645186Y476101D01*
Y479542D01*
X1640804Y483924D01*
X1632288D01*
X1620011Y496201D01*
X1612199D01*
X1611549Y496851D01*
X1610199D01*
X1609549Y496201D01*
X1608199D01*
X1605150Y499250D01*
X1590983D01*
X1589950Y498217D01*
Y497540D01*
X1589025Y496615D01*
Y495975D01*
G01X1639258Y185620D02*
X1638000Y184362D01*
Y181700D01*
X1636118Y179818D01*
X1633808D01*
X1631089Y182537D01*
Y186905D01*
X1624829Y193165D01*
Y196978D01*
X1630401Y202550D01*
X1639387D01*
X1650100Y213263D01*
Y219415D01*
X1656950Y226264D01*
Y249235D01*
X1663177Y255462D01*
Y305624D01*
X1661104Y307697D01*
Y312444D01*
X1663974Y315314D01*
Y368645D01*
X1658537Y374082D01*
Y382429D01*
X1663341Y387233D01*
Y407431D01*
X1660637Y410135D01*
Y430998D01*
X1658050Y433585D01*
Y461408D01*
X1657945Y461513D01*
Y461715D01*
X1644036Y475624D01*
Y479065D01*
X1640327Y482774D01*
X1631811D01*
X1619534Y495051D01*
X1607722D01*
X1604673Y498100D01*
X1591460D01*
X1591100Y497740D01*
Y497471D01*
X1592025Y496546D01*
Y495975D01*
G54D27*
G01X1775000Y53500D02*
X1771555Y56945D01*
X1765003D01*
X1763363Y58585D01*
Y66311D01*
X1761300Y68374D01*
X1752076D01*
X1750342Y70108D01*
X1730771D01*
X1726713Y74166D01*
X1714038D01*
X1710968Y71096D01*
X1674622D01*
X1668085Y77633D01*
X1656166D01*
X1648049Y85750D01*
X1629650D01*
X1624292Y91108D01*
Y106458D01*
G01X1733880Y232810D02*
X1720350Y219280D01*
Y202850D01*
G01D02*
X1727350Y195850D01*
X1730400D01*
G01X1758000Y250000D02*
X1755000Y253000D01*
X1734100D01*
X1732300Y251200D01*
Y241500D01*
X1730800Y240000D01*
Y235890D01*
X1733880Y232810D01*
G54D18*
X42724Y644684D03*
Y644656D03*
Y654684D03*
Y654656D03*
X67724Y644684D03*
Y644656D03*
Y654684D03*
Y654656D03*
X221656Y644656D03*
X196656D03*
X231446Y644756D03*
Y644784D03*
X221656Y644684D03*
X196656D03*
X221656Y654656D03*
X196656D03*
X231446Y654756D03*
Y654784D03*
X221656Y654684D03*
X196656D03*
X409240Y644564D03*
X418914Y644486D03*
Y644514D03*
X409240Y644536D03*
Y654564D03*
X418914Y654486D03*
Y654514D03*
X409240Y654536D03*
X443914Y644486D03*
Y644514D03*
Y654486D03*
Y654514D03*
X596707Y644293D03*
X571707D03*
X596708Y644266D03*
X571708D03*
X596707Y654293D03*
X571707D03*
X596708Y654266D03*
X571708D03*
X606462Y644245D03*
X631462D03*
X606462Y644217D03*
X631462D03*
X606462Y654245D03*
X631462D03*
X606462Y654217D03*
X631462D03*
X912351Y644245D03*
X887351D03*
X912351Y644273D03*
X887351D03*
X912351Y654245D03*
X887351D03*
X912351Y654273D03*
X887351D03*
X922116Y644206D03*
Y644234D03*
Y654206D03*
Y654234D03*
X1225877Y644262D03*
X1235614Y644236D03*
X1260614D03*
X1235614Y644264D03*
X1260614D03*
X1225877Y644234D03*
Y654262D03*
X1235614Y654236D03*
X1260614D03*
X1235614Y654264D03*
X1260614D03*
X1225877Y654234D03*
X1514375Y644292D03*
Y644264D03*
Y654292D03*
Y654264D03*
X1539375Y644292D03*
Y644264D03*
Y654292D03*
Y654264D03*
G54D37*
G01X23228Y124843D02*
X19667Y128404D01*
X-18395D01*
X-19300Y127499D01*
Y120464D01*
X-20644Y119120D01*
Y63850D01*
X-18148Y61354D01*
Y18263D01*
X-15417Y15532D01*
X6752D01*
X33817Y-11533D01*
X55603D01*
X61633Y-17563D01*
X63113D01*
X65006Y-19456D01*
X65164D01*
G01X12205Y124843D02*
Y124842D01*
X8645Y121282D01*
X-17418D01*
X-19892Y118808D01*
Y64432D01*
X-17396Y61936D01*
Y18575D01*
X-15105Y16284D01*
X7226D01*
X34289Y-10779D01*
X56054D01*
X59823Y-14548D01*
X65172D01*
X66031Y-13689D01*
X66061D01*
G01X63683Y-12866D02*
X60829Y-10012D01*
X34586D01*
X7538Y17036D01*
X-14793D01*
X-16644Y18887D01*
Y62426D01*
X-19140Y64922D01*
Y118496D01*
X-17106Y120530D01*
X13404D01*
X17716Y124842D01*
Y124843D01*
G01X67564Y-20745D02*
X66689Y-21620D01*
X62606D01*
X60610Y-19624D01*
Y-17802D01*
X55108Y-12300D01*
X33504D01*
X6424Y14780D01*
X-15729D01*
X-18900Y17951D01*
Y60950D01*
X-21396Y63446D01*
Y119432D01*
X-20052Y120776D01*
Y127811D01*
X-18708Y129155D01*
X19980D01*
X20135Y129000D01*
X24583D01*
X28740Y124843D01*
G01X30512Y467244D02*
X34631Y471363D01*
X42128D01*
X46098Y467393D01*
Y465941D01*
X49600Y462439D01*
Y442374D01*
X33811Y426585D01*
Y417180D01*
X37634Y413357D01*
Y355406D01*
X31328Y349100D01*
X-3905D01*
X-19776Y333229D01*
G01Y264124D02*
Y261965D01*
G01Y246665D02*
Y178541D01*
X-11036Y169801D01*
X40569D01*
X54919Y155451D01*
Y88628D01*
X47562Y81271D01*
Y18517D01*
X54330Y11749D01*
Y4575D01*
X56100Y2805D01*
Y-777D01*
X61056Y-5733D01*
X65334D01*
X76516Y-16915D01*
Y-17837D01*
X78775Y-20096D01*
X405515D01*
X408177Y-17434D01*
X463259D01*
X465666Y-19841D01*
X649327D01*
X653472Y-15696D01*
Y-2409D01*
X653471Y-2408D01*
Y-1124D01*
X662666Y8071D01*
X663395D01*
X663396Y8072D01*
X663951D01*
X663952Y8071D01*
X678303D01*
X683032Y12800D01*
X703880D01*
X709580Y7100D01*
X710800D01*
G01X20512Y467244D02*
X17218D01*
X13253Y463279D01*
X2181D01*
X-4669Y456429D01*
X-16189D01*
X-17014Y455604D01*
G01X47970Y359550D02*
Y358047D01*
X46672Y356749D01*
Y331888D01*
X50648Y327912D01*
Y319952D01*
X45828Y315132D01*
Y280820D01*
X47790Y278858D01*
Y265917D01*
X45828Y263955D01*
Y203940D01*
X65776Y183992D01*
Y169860D01*
X57972Y162056D01*
Y88379D01*
X59586Y86765D01*
X84443D01*
X87078Y84130D01*
Y23006D01*
X85140Y21068D01*
X59648D01*
X57362Y18782D01*
Y4994D01*
X61994Y362D01*
G01X64187Y176332D02*
X63776Y175921D01*
X59826D01*
X59051Y176696D01*
Y187571D01*
X45076Y201546D01*
Y264267D01*
X47038Y266229D01*
Y278502D01*
X44172Y281368D01*
Y316736D01*
X45687Y318251D01*
Y326184D01*
X43124Y328747D01*
Y423057D01*
X51997Y431930D01*
Y438437D01*
X64440Y450880D01*
Y468385D01*
X64188Y468637D01*
Y468767D01*
X62035Y470920D01*
X61905D01*
X58902Y473923D01*
X40342D01*
X31477Y482788D01*
G01X718975Y-4451D02*
X719180D01*
X722127Y-1504D01*
Y5251D01*
X713749Y13629D01*
X706673D01*
X704942Y15360D01*
X697420D01*
X694683Y18097D01*
Y21144D01*
X693183Y22644D01*
X688194D01*
X680254Y14704D01*
X676064D01*
X673914Y12554D01*
X661315D01*
X660626Y11865D01*
Y8446D01*
X651728Y-452D01*
Y-14277D01*
X647572Y-18433D01*
X466250D01*
X463843Y-16026D01*
X407593D01*
X405186Y-18433D01*
X112890D01*
X109995Y-15538D01*
X91732D01*
X88582Y-18688D01*
X79359D01*
X77924Y-17253D01*
Y-14977D01*
X66902Y-3955D01*
X61270D01*
X57400Y-85D01*
Y3893D01*
X56210Y5083D01*
Y19260D01*
X57400Y20450D01*
Y20884D01*
X58995Y22479D01*
X84192D01*
X85569Y23856D01*
Y83181D01*
X83639Y85111D01*
X59491D01*
X56403Y88199D01*
Y163734D01*
X57527Y164858D01*
Y187465D01*
X43924Y201068D01*
Y201634D01*
X43745Y201813D01*
Y264566D01*
X45886Y266707D01*
Y278024D01*
X42818Y281092D01*
Y317360D01*
X43984Y318526D01*
Y324305D01*
X41440Y326849D01*
Y423543D01*
X49394Y431497D01*
Y438955D01*
X56836Y446397D01*
Y468043D01*
X52108Y472771D01*
X34047D01*
X33551Y472275D01*
X4825D01*
X2350Y469800D01*
Y469650D01*
G01X47970Y359550D02*
Y360433D01*
X44842Y363561D01*
Y405780D01*
X49660Y410598D01*
Y410618D01*
X52516Y413474D01*
X53974D01*
X56464Y415964D01*
Y428579D01*
X68289Y440404D01*
Y469270D01*
X59821Y477738D01*
X47844D01*
X38673Y486909D01*
X28609D01*
X27940Y486240D01*
X17681D01*
X9970Y493951D01*
X459D01*
X-1820Y496230D01*
Y510316D01*
X75Y512211D01*
X2718D01*
X4520Y514013D01*
Y515977D01*
X3354Y517143D01*
G01X6748Y517021D02*
X5272Y515545D01*
Y513701D01*
X3030Y511459D01*
X651D01*
X-1068Y509740D01*
Y496542D01*
X771Y494703D01*
X10565D01*
X18076Y487192D01*
X27792D01*
X28461Y487861D01*
X38785D01*
X48156Y478490D01*
X60133D01*
X69969Y468654D01*
Y440757D01*
X60293Y431081D01*
X60269D01*
X59229Y430041D01*
Y430017D01*
X57416Y428204D01*
Y415415D01*
X54523Y412522D01*
X52911D01*
X45706Y405317D01*
Y364044D01*
X50510Y359240D01*
G01X1486926Y247834D02*
X1489076Y245684D01*
Y235505D01*
X1486390Y232819D01*
Y224169D01*
X1482748Y220527D01*
X1471369D01*
X1460021Y209179D01*
Y205554D01*
X1445642Y191175D01*
X1440921D01*
X1404598Y154852D01*
X1398541D01*
X1390840Y162553D01*
X1325489D01*
X1318508Y155572D01*
X1314344D01*
X1311140Y152368D01*
X1308911D01*
X1296292Y139749D01*
Y130162D01*
X1289704Y123574D01*
Y107938D01*
X1278273Y96507D01*
Y65997D01*
X1284064Y60206D01*
X1293494D01*
X1299478Y54222D01*
Y45875D01*
X1295362Y41759D01*
X1284430D01*
X1278970Y36299D01*
Y18610D01*
X1278968Y18608D01*
Y17364D01*
X1278970Y17362D01*
Y7729D01*
X1279160Y7539D01*
Y-10729D01*
X1276754Y-13135D01*
X1272144D01*
X1268145Y-17134D01*
X724122D01*
X723222Y-16234D01*
X723174D01*
X722251Y-15311D01*
Y-14005D01*
X723461Y-12795D01*
Y5547D01*
X714227Y14781D01*
X707151D01*
X705420Y16512D01*
X697898D01*
X695835Y18575D01*
Y21622D01*
X693539Y23918D01*
X687838D01*
X679790Y15870D01*
X674869D01*
X672705Y13706D01*
X660837D01*
X659329Y12198D01*
Y8908D01*
X650576Y155D01*
Y-13085D01*
X647085Y-16576D01*
X466832D01*
X465130Y-14874D01*
X407115D01*
X404708Y-17281D01*
X113814D01*
X110336Y-13803D01*
X78711D01*
X64430Y478D01*
Y7030D01*
X62008Y9452D01*
Y13249D01*
G01X62536Y-2379D02*
X63666Y-1249D01*
Y1035D01*
X58324Y6377D01*
Y18383D01*
X60047Y20106D01*
X85539D01*
X88040Y22607D01*
Y84529D01*
X84842Y87727D01*
X59985D01*
X58960Y88752D01*
Y110978D01*
X58924Y111014D01*
Y112486D01*
X58960Y112522D01*
Y115978D01*
X58924Y116014D01*
Y117486D01*
X58724Y117686D01*
Y161461D01*
X66728Y169465D01*
Y184387D01*
X46580Y204535D01*
Y263643D01*
X48542Y265605D01*
Y279328D01*
X46580Y281290D01*
Y314820D01*
X51400Y319640D01*
Y328224D01*
X47424Y332200D01*
Y356154D01*
X50510Y359240D01*
G01X701120Y19619D02*
X694506Y26233D01*
X687827D01*
X683755Y22161D01*
X678400D01*
X671449Y15210D01*
X660213D01*
X657390Y12387D01*
Y9097D01*
X649072Y779D01*
Y-12257D01*
X646277Y-15052D01*
X467436D01*
X465754Y-13370D01*
X406491D01*
X404084Y-15777D01*
X116198D01*
X102924Y-2503D01*
Y59761D01*
X105201Y62038D01*
Y82073D01*
X104228Y83046D01*
Y93729D01*
X100157Y97800D01*
X89843D01*
X82643Y105000D01*
G01X698470Y19669D02*
Y20331D01*
X693523Y25278D01*
X688092D01*
X684083Y21269D01*
X678940D01*
X672129Y14458D01*
X660525D01*
X658570Y12503D01*
Y9213D01*
X649824Y467D01*
Y-12569D01*
X646588Y-15805D01*
X467125D01*
X465442Y-14122D01*
X406803D01*
X404396Y-16529D01*
X114126D01*
X101921Y-4324D01*
Y59822D01*
X103676Y61577D01*
Y74814D01*
X102779Y75711D01*
Y93053D01*
X99832Y96000D01*
X86721D01*
X77721Y105000D01*
G01X104500Y-1850D02*
X104316Y-1666D01*
Y58883D01*
X107775Y62342D01*
Y80279D01*
X114300Y86804D01*
Y114300D01*
X105085Y123515D01*
Y171585D01*
X107750Y174250D01*
Y188250D01*
X111300Y191800D01*
Y204454D01*
X104707Y211047D01*
X102507D01*
G01X75660Y152380D02*
X76818Y153538D01*
Y167925D01*
X83418Y174525D01*
Y196264D01*
X87693Y200539D01*
Y202405D01*
X103510Y218222D01*
Y284428D01*
X96300Y291638D01*
Y306670D01*
X84870Y318100D01*
X73000D01*
X69648Y314748D01*
X64848D01*
X64000Y313900D01*
G01X78950Y152810D02*
X77770Y153990D01*
Y167530D01*
X84370Y174130D01*
Y195869D01*
X88645Y200144D01*
Y202010D01*
X104462Y217827D01*
Y284823D01*
X97252Y292033D01*
Y307065D01*
X85265Y319052D01*
X72605D01*
X69253Y315700D01*
X64800D01*
X64000Y316500D01*
G01X100550Y335140D02*
X97770Y332360D01*
X91639D01*
X87150Y327871D01*
Y320820D01*
X98500Y309470D01*
Y292762D01*
X105770Y285492D01*
Y217505D01*
X91400Y203135D01*
Y193817D01*
X86731Y189148D01*
G01X729600Y17991D02*
X711642D01*
X705582Y24051D01*
X699950D01*
X691201Y32800D01*
X681670D01*
X677040Y28170D01*
Y21950D01*
X671052Y15962D01*
X659901D01*
X656180Y12241D01*
Y8951D01*
X648169Y940D01*
X631840D01*
X616600Y-14300D01*
X467748D01*
X466066Y-12618D01*
X406179D01*
X403772Y-15025D01*
X117854D01*
X108527Y-5698D01*
Y79455D01*
X115053Y85981D01*
Y115047D01*
X114752Y115348D01*
Y167998D01*
X108502Y174248D01*
Y187938D01*
X112053Y191489D01*
Y206687D01*
X107700Y211040D01*
G01X74800Y338850D02*
Y343507D01*
X77348Y346055D01*
Y351330D01*
X72978Y355700D01*
X70880D01*
X67478Y359102D01*
X60596D01*
X52174Y367524D01*
Y390703D01*
X53597Y392126D01*
X56436D01*
X62666Y385896D01*
X68932D01*
X73067Y390031D01*
Y395911D01*
X73064Y395914D01*
Y398796D01*
X73066Y398798D01*
Y425339D01*
X77662Y429935D01*
Y439073D01*
X105596Y467007D01*
Y504212D01*
X102916Y506892D01*
Y517752D01*
X103540Y518376D01*
Y610560D01*
X103867Y610887D01*
Y612536D01*
X102236Y614167D01*
G01X91150Y618250D02*
X90210D01*
X85245Y613285D01*
Y532275D01*
X83302Y530332D01*
Y511261D01*
X89955Y504608D01*
X100281D01*
X102192Y502697D01*
Y468417D01*
X74258Y440483D01*
Y431345D01*
X72525Y429612D01*
X72524D01*
X69662Y426750D01*
Y400208D01*
X69660Y400206D01*
Y394504D01*
X69663Y394501D01*
Y391441D01*
X67522Y389300D01*
X64076D01*
X57845Y395531D01*
X52188D01*
X48628Y391971D01*
Y366042D01*
X56802Y357868D01*
Y356836D01*
X59664Y353974D01*
X67792D01*
X69470Y352296D01*
X71568D01*
X73936Y349928D01*
Y347457D01*
X69000Y342521D01*
Y338800D01*
G01X93800Y618111D02*
X92237Y616548D01*
X90915D01*
X86947Y612580D01*
Y531550D01*
X85004Y529607D01*
Y511966D01*
X90660Y506310D01*
X101030D01*
X103894Y503446D01*
Y467712D01*
X75960Y439778D01*
Y430640D01*
X73230Y427910D01*
X73229D01*
X71364Y426045D01*
Y399503D01*
X71362Y399501D01*
Y395209D01*
X71365Y395206D01*
Y390736D01*
X68227Y387598D01*
X63371D01*
X57140Y393829D01*
X52893D01*
X50330Y391266D01*
Y366961D01*
X59891Y357400D01*
X66773D01*
X70175Y353998D01*
X72273D01*
X75646Y350625D01*
Y346760D01*
X72000Y343114D01*
Y338800D01*
G01X726857Y610871D02*
X728727Y609001D01*
Y606074D01*
X727605Y604952D01*
X725105D01*
X722105Y601952D01*
X717105D01*
X714048Y598895D01*
Y596395D01*
X712705Y595052D01*
X703205D01*
X697506Y589353D01*
X685194D01*
X679895Y594652D01*
X656171D01*
X648931Y601892D01*
X634905D01*
X624766Y612031D01*
Y614729D01*
X618878Y620617D01*
X618853D01*
X618822Y620648D01*
X444724D01*
X444324Y621048D01*
X308952D01*
X306750Y623250D01*
X119123D01*
X107970Y612097D01*
Y518767D01*
X108570Y518167D01*
Y512521D01*
X108952Y512139D01*
Y502680D01*
X107648Y501376D01*
Y494623D01*
X109803Y492468D01*
Y446227D01*
X89731Y426155D01*
Y397855D01*
X84472Y392596D01*
Y388894D01*
X86983Y386383D01*
Y386372D01*
X87696Y385659D01*
Y358144D01*
X80976Y351424D01*
Y346224D01*
X77348Y342596D01*
Y338595D01*
X75248Y336495D01*
Y329466D01*
X71734Y325952D01*
X66404D01*
X61548Y321096D01*
Y317605D01*
X62424Y316729D01*
Y315476D01*
X64000Y313900D01*
G01Y316500D02*
X62500Y318000D01*
Y320701D01*
X66799Y325000D01*
X72129D01*
X76200Y329071D01*
Y336100D01*
X78300Y338200D01*
Y342201D01*
X81928Y345829D01*
Y351029D01*
X88648Y357749D01*
Y386247D01*
X85424Y389471D01*
Y392201D01*
X90683Y397460D01*
Y425760D01*
X110755Y445832D01*
Y492590D01*
X108400Y494945D01*
Y501064D01*
X109904Y502568D01*
Y512456D01*
X109522Y512838D01*
Y518562D01*
X108922Y519162D01*
Y611702D01*
X119518Y622298D01*
X306355D01*
X308557Y620096D01*
X443929D01*
X444360Y619665D01*
X618483D01*
X623814Y614334D01*
Y611636D01*
X634510Y600940D01*
X648536D01*
X655776Y593700D01*
X679500D01*
X684799Y588401D01*
X697901D01*
X703600Y594100D01*
X713100D01*
X715000Y596000D01*
Y598500D01*
X717500Y601000D01*
X722500D01*
X725500Y604000D01*
X728000D01*
X729679Y605679D01*
Y610800D01*
X729616Y610863D01*
G01X732500Y611000D02*
Y606500D01*
X731456Y605456D01*
Y602544D01*
X732259Y601741D01*
Y591542D01*
X729217Y588500D01*
X725601D01*
X723325Y586224D01*
X661304D01*
X647408Y600120D01*
X634266D01*
X622662Y611724D01*
Y613093D01*
X616842Y618913D01*
X444048D01*
X444020Y618941D01*
X119765D01*
X109860Y609036D01*
Y519785D01*
X110310Y519335D01*
Y513840D01*
X110656Y513494D01*
Y502256D01*
X109152Y500752D01*
Y495329D01*
X111507Y492974D01*
Y443134D01*
X92134Y423761D01*
Y396987D01*
X86824Y391677D01*
Y389670D01*
X89400Y387094D01*
Y351527D01*
X79217Y341344D01*
Y337387D01*
X77600Y335770D01*
Y320800D01*
G01X1382331Y543818D02*
X1381765Y544384D01*
X1329093D01*
X1328449Y543740D01*
X1322457D01*
X1321297Y544900D01*
X1318216D01*
X1314716Y548400D01*
X1300871D01*
X1298400Y550871D01*
Y556100D01*
X1295800Y558700D01*
Y576400D01*
X1290500Y581700D01*
X1285600D01*
X1283200Y579300D01*
X1281800D01*
X1280600Y580500D01*
Y589300D01*
X1278396Y591504D01*
Y610603D01*
X1267542Y621457D01*
X1046070D01*
X1045937Y621590D01*
X1045913D01*
X1045853Y621650D01*
X1045844D01*
X1045452Y622042D01*
X740643D01*
X731601Y613000D01*
X714597D01*
X710100Y608503D01*
Y604536D01*
X696912Y591348D01*
X685252D01*
X680800Y595800D01*
X672900D01*
X663352Y605348D01*
X652119D01*
X641111Y616356D01*
X634569D01*
X632813Y614600D01*
X632811D01*
X632394Y614183D01*
X631088D01*
X630671Y614600D01*
X629901D01*
X623332Y621169D01*
X619390D01*
X619190Y621369D01*
X619165D01*
X619134Y621400D01*
X445036D01*
X444636Y621800D01*
X310102D01*
X307500Y624402D01*
X87072D01*
X84040Y621370D01*
Y617660D01*
X83393Y617013D01*
Y533043D01*
X80820Y530470D01*
Y510670D01*
X83910Y507580D01*
Y500725D01*
X81996Y498811D01*
Y451302D01*
X71590Y440896D01*
Y434740D01*
X66248Y429398D01*
Y422148D01*
X54820Y410720D01*
X53991D01*
X46776Y403505D01*
Y365216D01*
X54205Y357787D01*
Y354345D01*
X58553Y349997D01*
X62403D01*
X63800Y348600D01*
G01X148901Y-50496D02*
X445510D01*
G02Y-53848I0J-1676D01*
G01X147382D01*
X145030Y-56200D01*
X124450D01*
X120500Y-52250D01*
G01X734256Y17991D02*
Y24245D01*
X728338Y30163D01*
X696638D01*
X693201Y33600D01*
X681300D01*
X675860Y28160D01*
Y22730D01*
X669890Y16760D01*
X659635D01*
X655280Y12405D01*
Y9610D01*
X647600Y1930D01*
X630173D01*
X614695Y-13548D01*
X468060D01*
X466378Y-11866D01*
X405867D01*
X403460Y-14273D01*
X118884D01*
X111524Y-6913D01*
Y80700D01*
X117232Y86408D01*
Y125110D01*
X115730Y126612D01*
Y170714D01*
X120300Y175284D01*
Y193710D01*
X124340Y197750D01*
G01X121981Y405573D02*
X127830D01*
X129257Y407000D01*
X142842D01*
X145194Y404648D01*
Y400666D01*
X173669Y372191D01*
X188480D01*
X190937Y369734D01*
Y367926D01*
X196710Y362153D01*
X207386D01*
X240939Y328600D01*
X253500D01*
X264900Y317200D01*
G01X1288100Y562000D02*
X1286787D01*
X1279847Y568940D01*
Y588753D01*
X1277644Y590956D01*
Y609630D01*
X1266825Y620449D01*
X1046014D01*
X1045671Y620792D01*
X1045647D01*
X1045541Y620898D01*
X1045532D01*
X1045140Y621290D01*
X744772D01*
X734652Y611170D01*
Y610548D01*
X734653Y610547D01*
Y591868D01*
X727554Y584769D01*
X678685D01*
X676490Y582574D01*
X651097D01*
X650174Y583497D01*
Y588610D01*
X650508Y588944D01*
Y594012D01*
X645152Y599368D01*
X633954D01*
X621174Y612148D01*
Y613517D01*
X616531Y618160D01*
X443737D01*
X443708Y618189D01*
X120077D01*
X110612Y608724D01*
Y520097D01*
X111062Y519647D01*
Y514430D01*
X111814Y513678D01*
Y503430D01*
X114678Y500566D01*
Y448225D01*
X132167Y430736D01*
X134212D01*
X142193Y422754D01*
Y411905D01*
X148280Y405818D01*
Y402344D01*
X160838Y389786D01*
X168248D01*
X169400Y388634D01*
Y382155D01*
X175255Y376300D01*
X188928D01*
X195626Y369602D01*
Y369111D01*
X198393Y366344D01*
X208008D01*
X242492Y331860D01*
X260030D01*
X262260Y329630D01*
X265670D01*
X267200Y328100D01*
X268900D01*
X270600Y326400D01*
X272100D01*
X274000Y324500D01*
X275000D01*
X277300Y322200D01*
X278300D01*
X280500Y320000D01*
X282600D01*
X284300Y318300D01*
X285300D01*
X287300Y316300D01*
X289100D01*
X290610Y314790D01*
X292890D01*
X294800Y316700D01*
X295600D01*
X297100Y318200D01*
X298700D01*
X301134Y320634D01*
X302305D01*
X303571Y321900D01*
X305007D01*
X307407Y324300D01*
X309600D01*
X311785Y326485D01*
X312449D01*
X313373Y327409D01*
Y336673D01*
X315178Y338478D01*
Y349509D01*
G01X1285400Y561000D02*
X1279095Y567305D01*
Y588406D01*
X1276892Y590609D01*
Y609318D01*
X1266513Y619697D01*
X1045702D01*
X1045359Y620040D01*
X1045335D01*
X1045229Y620146D01*
X1045220D01*
X1044828Y620538D01*
X745084D01*
X735405Y610859D01*
Y591556D01*
X727866Y584017D01*
X678997D01*
X676802Y581822D01*
X650785D01*
X649422Y583185D01*
Y588922D01*
X649756Y589256D01*
Y593700D01*
X644840Y598616D01*
X633642D01*
X620306Y611952D01*
Y613321D01*
X616527Y617100D01*
X443733D01*
X443396Y617437D01*
X120389D01*
X111364Y608412D01*
Y520697D01*
X111814Y520247D01*
Y514830D01*
X112566Y514078D01*
Y504096D01*
X115438Y501224D01*
Y448677D01*
X132627Y431488D01*
X134524D01*
X142945Y423066D01*
Y412217D01*
X149090Y406072D01*
Y402598D01*
X161150Y390538D01*
X171759D01*
X172834Y389463D01*
Y382853D01*
X177025Y378662D01*
X187630D01*
X196378Y369914D01*
Y369423D01*
X198705Y367096D01*
X208320D01*
X242776Y332640D01*
X260600D01*
X262850Y330390D01*
X265867D01*
X267061Y331584D01*
G01X310800Y336700D02*
X313604Y339504D01*
Y351835D01*
X315178Y353409D01*
G01X644500Y594400D02*
X642540Y596360D01*
X628194D01*
X616953Y607601D01*
Y610904D01*
X617125Y611076D01*
Y613310D01*
X616113Y614322D01*
X443251D01*
X442392Y615181D01*
X123973D01*
X121800Y613008D01*
Y611100D01*
X118516Y607816D01*
Y601784D01*
X118568Y601732D01*
Y588844D01*
X117100Y587376D01*
Y559248D01*
X115351Y557499D01*
Y551389D01*
X117459Y549281D01*
Y521863D01*
X115351Y519755D01*
Y515055D01*
X118203Y512203D01*
Y512161D01*
X118245Y512119D01*
Y449062D01*
X133563Y433744D01*
X135460D01*
X145300Y423904D01*
Y415371D01*
X149121Y411550D01*
X151189D01*
X152226Y410513D01*
Y408912D01*
X151616Y408302D01*
Y403264D01*
X162086Y392794D01*
X180787D01*
X185961Y387620D01*
X190555D01*
X190575Y387640D01*
X205024Y373191D01*
Y371747D01*
X205947Y370824D01*
X207784D01*
X243464Y335144D01*
X261192D01*
X263568Y337520D01*
G01X648180Y590702D02*
X648336Y590858D01*
Y594056D01*
X644528Y597864D01*
X628818D01*
X618457Y608225D01*
Y610280D01*
X618629Y610452D01*
Y613934D01*
X616736Y615827D01*
X443874D01*
X443016Y616685D01*
X120701D01*
X112116Y608100D01*
Y522984D01*
X112566Y522534D01*
Y515670D01*
X116661Y511575D01*
Y448518D01*
X132939Y432240D01*
X134836D01*
X143697Y423379D01*
Y412529D01*
X149900Y406326D01*
Y402852D01*
X161462Y391290D01*
X176066D01*
X197130Y370226D01*
Y369735D01*
X199017Y367848D01*
X208632D01*
X242945Y333535D01*
X263936D01*
G01X310000Y337600D02*
X311798Y339398D01*
Y347560D01*
G01X263808Y334324D02*
X263591Y334392D01*
X243152D01*
X208944Y368600D01*
X199329D01*
X197882Y370047D01*
Y370538D01*
X176378Y392042D01*
X161774D01*
X150680Y403136D01*
Y406610D01*
X144450Y412840D01*
Y423690D01*
X135148Y432992D01*
X133251D01*
X117493Y448750D01*
Y511807D01*
X114599Y514701D01*
Y522015D01*
X116368Y523784D01*
Y544860D01*
X114307Y546921D01*
Y559787D01*
X116085Y561565D01*
Y588023D01*
X115351Y588757D01*
Y601010D01*
X116368Y602027D01*
Y611288D01*
X121013Y615933D01*
X442704D01*
X443563Y615074D01*
X616425D01*
X617877Y613622D01*
Y610764D01*
X617705Y610592D01*
Y607913D01*
X628506Y597112D01*
X644216D01*
X646760Y594568D01*
Y592992D01*
G01X265700Y323700D02*
X265200D01*
X263400Y325500D01*
X262100D01*
X257400Y330200D01*
X241602D01*
X207002Y364800D01*
X197779D01*
X194122Y368457D01*
Y368978D01*
X188404Y374696D01*
X174937D01*
X174936Y374695D01*
X174314D01*
X174313Y374696D01*
X174047D01*
X174046Y374695D01*
X173424D01*
X173423Y374696D01*
X173294D01*
X157950Y390040D01*
X157948D01*
X146698Y401290D01*
Y405272D01*
X143232Y408738D01*
X127123D01*
X124261Y411600D01*
X119100D01*
G01X263751Y326400D02*
X262398D01*
X257751Y331047D01*
X241953D01*
X207408Y365592D01*
X198051D01*
X194874Y368769D01*
Y369290D01*
X188715Y375449D01*
X188093D01*
X188092Y375448D01*
X173735D01*
X158391Y390792D01*
X158260D01*
X147450Y401602D01*
Y405584D01*
X143544Y409490D01*
X127435D01*
X122724Y414201D01*
X119016D01*
G01X119398Y406348D02*
X120950Y407900D01*
X143006D01*
X145946Y404960D01*
Y400978D01*
X157636Y389288D01*
X157638D01*
X172982Y373944D01*
X173111D01*
X173112Y373943D01*
X174002D01*
X174003Y373942D01*
X187793D01*
X191690Y370045D01*
Y368238D01*
X197015Y362913D01*
X207701D01*
X241254Y329360D01*
X253815D01*
X265438Y317739D01*
Y317738D01*
G01X122242Y419199D02*
X122156Y419285D01*
X120330D01*
X112372Y427243D01*
Y493223D01*
X110512Y495083D01*
Y498428D01*
X111961Y499877D01*
G01X123441Y421795D02*
X123234Y421588D01*
X119264D01*
X113419Y427433D01*
Y494330D01*
X112427Y495322D01*
Y497225D01*
G01X307675Y28014D02*
X309892Y30231D01*
Y34299D01*
X309292Y34899D01*
Y48900D01*
X309892Y49500D01*
Y52640D01*
X307675Y54857D01*
G01Y17057D02*
X309392Y18774D01*
Y26297D01*
X307675Y28014D01*
G01X308157Y-7180D02*
Y-3983D01*
X309404Y-2736D01*
Y10212D01*
X309692Y10500D01*
Y14812D01*
X307675Y16829D01*
Y17057D01*
G01Y54857D02*
X309292Y56474D01*
Y66438D01*
X307928Y67802D01*
G01D02*
X309663D01*
X310140Y68279D01*
Y78452D01*
X309292Y79300D01*
Y85690D01*
X309792Y86190D01*
Y88500D01*
X309092Y89200D01*
Y91240D01*
X307675Y92657D01*
G01X339209Y392729D02*
Y398498D01*
X339492Y398781D01*
Y418901D01*
X339092Y419301D01*
Y473944D01*
X313392Y499644D01*
Y510300D01*
X311092Y512600D01*
Y512700D01*
X308892Y514900D01*
Y516840D01*
X307675Y518057D01*
G01D02*
X309392Y519774D01*
Y527669D01*
X308198Y528863D01*
G01X307984Y566743D02*
X309697Y568456D01*
Y573794D01*
X309392Y574099D01*
Y586900D01*
X309667Y587175D01*
Y591665D01*
X307675Y593657D01*
G01Y555857D02*
X309392Y557574D01*
Y565335D01*
X307984Y566743D01*
G01X308198Y528863D02*
X309578Y530243D01*
Y535256D01*
X309292Y535542D01*
Y549400D01*
X309726Y549834D01*
Y553806D01*
X307675Y555857D01*
G01Y593657D02*
X309392Y595374D01*
Y605985D01*
X308157Y607220D01*
G01X460630Y278470D02*
Y314532D01*
X461912Y317627D01*
X463671Y319386D01*
G01X458400Y276400D02*
Y274400D01*
X459600Y273200D01*
X462500D01*
X463800Y271900D01*
Y268600D01*
X465500Y266900D01*
X467200D01*
X469200Y264900D01*
X470800D01*
X472417Y266517D01*
X473943D01*
X475560Y264900D01*
X477300D01*
X479100Y263100D01*
X480800D01*
X482265Y264565D01*
G01X458400Y276400D02*
X456838Y277962D01*
Y280777D01*
X459361Y283300D01*
Y327259D01*
X469402Y337300D01*
X471600D01*
X472100Y337800D01*
G01X547093Y393493D02*
Y396417D01*
X612543Y461867D01*
X613660D01*
X615907Y464114D01*
Y469970D01*
X618232Y472295D01*
X626750D01*
X638755Y484300D01*
X641150D01*
G01X465100Y280300D02*
Y275000D01*
X467700Y272400D01*
X471600D01*
X472800Y271200D01*
X474400D01*
X475800Y269800D01*
X477900D01*
X479700Y268000D01*
X483000D01*
X484700Y266300D01*
X486273D01*
X487271Y265302D01*
X488593D01*
X489832Y266541D01*
X492059D01*
X494010Y264590D01*
X495353D01*
X496590Y263353D01*
X499353D01*
X501302Y265302D01*
X502113D01*
X504064Y267253D01*
X505493D01*
X507442Y269202D01*
X508873D01*
X509806Y270135D01*
Y270961D01*
X511592Y272747D01*
G01X656050Y489500D02*
X648700Y482150D01*
X638235D01*
X626002Y469917D01*
Y465926D01*
X620791Y460715D01*
X613021D01*
X553900Y401594D01*
Y392800D01*
X550500Y389400D01*
G01X472800Y335500D02*
X469000D01*
X467135Y333635D01*
X463973Y326000D01*
X463671Y325271D01*
Y319386D01*
G01X466734Y287074D02*
X467660Y288000D01*
X472200D01*
X474872Y290672D01*
X477862D01*
G02X479807Y289509I-70J-2325D01*
G03X481128Y288721I1365J787D01*
G01X481257D01*
G02X483187Y287559I-85J-2325D01*
G03X484493Y286772I1365J788D01*
G01X484694D01*
X487932Y286396D01*
G01X756176Y-2567D02*
Y4724D01*
G01X753924Y6976D02*
X752099Y8801D01*
Y23892D01*
X753900Y25693D01*
Y33170D01*
X753176Y33894D01*
Y41653D01*
X752772Y42057D01*
Y52014D01*
X745956Y58830D01*
X730007D01*
X726928Y61909D01*
Y71055D01*
X722183Y75800D01*
X687969D01*
X678369Y85400D01*
X676851D01*
X671398Y90853D01*
X634347Y106200D01*
X622981Y117566D01*
X612003Y144068D01*
X547982Y208089D01*
X545273D01*
G01X662352Y89566D02*
X655980Y95938D01*
X633890Y105088D01*
X633882Y105091D01*
X633866Y105098D01*
X633528Y105237D01*
X622112Y116653D01*
X611374Y142574D01*
X547126Y206822D01*
X543100D01*
G01X508979Y253000D02*
X504832Y257147D01*
G01X667900Y87990D02*
X661695D01*
X660500Y89185D01*
Y89788D01*
X655328Y94960D01*
X633467Y104016D01*
X633449Y104023D01*
X633416Y104037D01*
X633301Y104084D01*
X632876Y104258D01*
X621135Y116000D01*
X610396Y141922D01*
X546818Y205500D01*
X542900D01*
X542341Y206059D01*
G01X694600Y85000D02*
X692922Y86678D01*
X677345D01*
X672108Y91915D01*
X669374Y93048D01*
X660356Y102066D01*
X628603Y115218D01*
X622982Y120839D01*
X613065Y144778D01*
X551842Y206000D01*
X550589Y207253D01*
X550448D01*
X548994Y208707D01*
X548429Y210071D01*
X546000Y212500D01*
X544220D01*
X542620Y214100D01*
X541100D01*
X539300Y215900D01*
X537900D01*
X535600Y218200D01*
X534400D01*
X532600Y220000D01*
X531100D01*
X528900Y222200D01*
X527800D01*
X526100Y223900D01*
X524600D01*
X522400Y226100D01*
X521200D01*
X520100Y227200D01*
Y234500D01*
X518352Y236248D01*
Y237647D01*
G01X560451Y261421D02*
X570479Y251393D01*
X618279D01*
G01X703845Y88830D02*
Y89955D01*
X699592Y94208D01*
X689349Y98451D01*
X687606Y100194D01*
X681600Y114694D01*
Y117913D01*
X680608Y120308D01*
X674539Y126377D01*
X664343Y130600D01*
X649719D01*
X625787Y140513D01*
X577721Y188579D01*
X571000Y204804D01*
Y210861D01*
X565486Y224174D01*
X564060Y225600D01*
X561300D01*
X559900Y224200D01*
X557700D01*
X556000Y225900D01*
X554800D01*
X553000Y227700D01*
X551500D01*
X549600Y229600D01*
X547900D01*
X545900Y231600D01*
X544800D01*
X542900Y233500D01*
X541300D01*
X538800Y236000D01*
X537800D01*
X536200Y237600D01*
X534700D01*
X533006Y239294D01*
G01X569625Y271800D02*
X605440D01*
X621165Y256075D01*
G01X569500Y270475D02*
X603791D01*
X620850Y253416D01*
G01X511592Y253247D02*
Y252308D01*
X514300Y249600D01*
X516453D01*
X516987Y250134D01*
G01X570700Y249400D02*
X573300D01*
X588000Y234700D01*
Y219240D01*
X586128Y217368D01*
Y204972D01*
X630600Y160500D01*
X669980D01*
X711286Y119194D01*
Y92314D01*
X713115Y90485D01*
Y88629D01*
G01X763544Y522236D02*
X763035Y522745D01*
X760695D01*
X757178Y519228D01*
Y512207D01*
X751081Y506110D01*
X730377D01*
X719950Y516537D01*
X697736D01*
X694944Y513745D01*
Y508427D01*
X686239Y499722D01*
Y490939D01*
X688821Y488357D01*
Y426910D01*
X679015Y417104D01*
X668854D01*
X661424Y409674D01*
Y393310D01*
X558965Y290851D01*
Y289935D01*
X554645Y285615D01*
G01X526809Y237803D02*
Y231091D01*
X528400Y229500D01*
X529400D01*
X531050Y227850D01*
X532350D01*
X534600Y225600D01*
X536200D01*
X538000Y223800D01*
X539200D01*
X540800Y222200D01*
X542400D01*
X544600Y220000D01*
X546000D01*
X547700Y218300D01*
X549200D01*
X551300Y216200D01*
X552600D01*
X553900Y214900D01*
Y209724D01*
X555443Y206000D01*
X555484Y205902D01*
X615189Y146198D01*
X625106Y122259D01*
X630021Y117344D01*
X661021Y104503D01*
X661776Y104190D01*
X670794Y95172D01*
X673528Y94039D01*
X678260Y89307D01*
X696164D01*
X698471Y87000D01*
X700000D01*
X701500Y85500D01*
G01X698300Y85300D02*
X695670Y87930D01*
X677865D01*
X672818Y92977D01*
X670084Y94110D01*
X661066Y103128D01*
X635569Y113689D01*
X629313Y116280D01*
X624044Y121549D01*
X614127Y145488D01*
X554383Y205231D01*
X551704Y211696D01*
X548800Y214600D01*
X547500D01*
X545800Y216300D01*
X544500D01*
X542700Y218100D01*
X541300D01*
X539500Y219900D01*
X538000D01*
X535800Y222100D01*
X534600D01*
X532400Y224300D01*
X530600D01*
X528700Y226200D01*
X527300D01*
X525700Y227800D01*
X524400D01*
X523500Y228700D01*
Y236500D01*
X521731Y238269D01*
Y239596D01*
G01X528576Y238021D02*
G02X530506Y236859I-85J-2325D01*
G03X531812Y236072I1365J788D01*
G01X533784Y234100D01*
X536000D01*
X538000Y232100D01*
X539000D01*
X541200Y229900D01*
X542400D01*
X544200Y228100D01*
X545800D01*
X548100Y225800D01*
X549300D01*
X551200Y223900D01*
X553000D01*
X554600Y222300D01*
X556100D01*
X558000Y220400D01*
X559900D01*
X561200Y221700D01*
X563500D01*
X566501Y218699D01*
X569800Y210734D01*
Y204663D01*
X576774Y187826D01*
X625116Y139484D01*
X649702Y129300D01*
X664413D01*
X673927Y125359D01*
X679303Y119983D01*
X680400Y117335D01*
Y114363D01*
X686526Y99574D01*
X688708Y97392D01*
X698609Y93291D01*
X702200Y89700D01*
Y87900D01*
X705451Y84649D01*
X709559D01*
X709560Y84648D01*
G01X528491Y262996D02*
G03X530506Y265734I-11227J10372D01*
G02X531827Y266522I1365J-787D01*
G01X531956D01*
G03X533886Y267684I-85J2325D01*
G02X535192Y268471I1365J-788D01*
G01X535321D01*
G03X537266Y269634I-70J2325D01*
G02X538587Y270422I1365J-787D01*
G01X538716D01*
G03X540646Y271584I-85J2325D01*
G02X541952Y272371I1365J-788D01*
G01X542081D01*
G03X544026Y273534I-70J2325D01*
G02X545320Y274321I1365J-787D01*
G01X545476D01*
G03X547406Y275483I-85J2325D01*
G02X548727Y276271I1365J-787D01*
G01X548856D01*
G03X550786Y277433I-85J2325D01*
G02X552107Y278221I1365J-787D01*
G01X552202D01*
G03X554166Y279384I-51J2326D01*
G02X555472Y280171I1365J-788D01*
G01X555983D01*
X558973Y278933D01*
X559529D01*
X560481Y279328D01*
X643724Y362571D01*
X678460D01*
X678730Y362841D01*
G01X568300Y248100D02*
X572900D01*
X585276Y235724D01*
Y231724D01*
X586752Y230248D01*
Y219622D01*
X584876Y217746D01*
Y204424D01*
X630000Y159300D01*
X669550D01*
X709986Y118864D01*
Y89430D01*
X713300Y86116D01*
Y86000D01*
G01X707329Y88955D02*
Y92351D01*
X702880Y96800D01*
X699746D01*
X690620Y100580D01*
X689740Y101460D01*
X684000Y115319D01*
Y118380D01*
X682430Y122170D01*
X676322Y128278D01*
X664682Y133100D01*
X663567D01*
X636289Y144400D01*
X626100D01*
X579096Y191404D01*
X573500Y204914D01*
Y211478D01*
X565068Y231832D01*
X562900Y234000D01*
X554600D01*
X552800Y235800D01*
X551100D01*
X549600Y237300D01*
X548000D01*
X545800Y239500D01*
X544400D01*
X542400Y241500D01*
X541000D01*
X539100Y243400D01*
X537600D01*
G01X696000Y496800D02*
Y489275D01*
X694996Y488271D01*
Y431246D01*
X679554Y415804D01*
X669830D01*
X663574Y409548D01*
Y384955D01*
X562509Y283890D01*
X559587Y282680D01*
X557932D01*
X556518Y284094D01*
X554963D01*
G01X524202Y266502D02*
X523000Y265300D01*
X520800D01*
X519204Y266896D01*
X508212D01*
G01X705972Y86660D02*
X705620Y87012D01*
Y89880D01*
X700180Y95320D01*
X689937Y99563D01*
X688552Y100948D01*
X682800Y114836D01*
Y118164D01*
X681681Y120865D01*
X675158Y127388D01*
X664506Y131800D01*
X650020D01*
X626770Y141430D01*
X578508Y189692D01*
X572200Y204921D01*
Y211061D01*
X565102Y228198D01*
X563800Y229500D01*
X561700D01*
X560400Y228200D01*
X557800D01*
X556400Y229600D01*
X554900D01*
X552900Y231600D01*
X551400D01*
X549500Y233500D01*
X547900D01*
X545600Y235800D01*
X544400D01*
X542700Y237500D01*
X541100D01*
X538900Y239700D01*
X537700D01*
X536100Y241300D01*
X533677D01*
X533470Y241093D01*
G01X561001Y276271D02*
X644773Y360043D01*
X678283D01*
X681402Y363162D01*
Y396496D01*
X697465Y412559D01*
Y419207D01*
X699852Y421594D01*
Y423463D01*
X699500Y423815D01*
X697175D01*
X696823Y424167D01*
Y425315D01*
X697175Y425667D01*
X699500D01*
X699852Y426019D01*
Y427167D01*
X699500Y427519D01*
X697175D01*
X696823Y427871D01*
Y429019D01*
X697175Y429371D01*
X699500D01*
X699852Y429723D01*
Y430871D01*
X699500Y431223D01*
X697175D01*
X696823Y431575D01*
Y432723D01*
X697175Y433075D01*
X699500D01*
X699852Y433427D01*
Y434575D01*
X699500Y434927D01*
X697175D01*
X696823Y435279D01*
Y436427D01*
X697175Y436779D01*
X699500D01*
X699852Y437131D01*
Y438279D01*
X699500Y438631D01*
X697175D01*
X696823Y438983D01*
Y440131D01*
X697175Y440483D01*
X699500D01*
X699852Y440835D01*
Y441983D01*
X699500Y442335D01*
X697175D01*
X696823Y442687D01*
Y443835D01*
X697175Y444187D01*
X699500D01*
X699852Y444539D01*
Y445687D01*
X699500Y446039D01*
X697175D01*
X696823Y446391D01*
Y447539D01*
X697175Y447891D01*
X699500D01*
X699852Y448243D01*
Y449391D01*
X699500Y449743D01*
X697175D01*
X696823Y450095D01*
Y451243D01*
X697175Y451595D01*
X699500D01*
X699852Y451947D01*
Y453095D01*
X699500Y453447D01*
X697175D01*
X696823Y453799D01*
Y454947D01*
X697175Y455299D01*
X699500D01*
X699852Y455651D01*
Y456799D01*
X699500Y457151D01*
X697175D01*
X696823Y457503D01*
Y458651D01*
X697175Y459003D01*
X699500D01*
X699852Y459355D01*
Y460503D01*
X699500Y460855D01*
X697175D01*
X696823Y461207D01*
Y462355D01*
X697175Y462707D01*
X699500D01*
X699852Y463059D01*
Y464207D01*
X699500Y464559D01*
X697175D01*
X696823Y464911D01*
Y466059D01*
X697175Y466411D01*
X699500D01*
X699852Y466763D01*
Y506452D01*
X704200Y510800D01*
X717371D01*
X720761Y507410D01*
X722067D01*
X722827Y508170D01*
X726431D01*
X738811Y495790D01*
X756544D01*
X761090Y500336D01*
Y511634D01*
X763706Y514250D01*
G01X481172Y329296D02*
X479602Y330866D01*
Y337747D01*
X481281Y339426D01*
X482710D01*
X483901Y340617D01*
X485332D01*
X487281Y342566D01*
X487866D01*
X490500Y345200D01*
X492775D01*
X494041Y346466D01*
X495470D01*
X497421Y348417D01*
X498617D01*
X501200Y351000D01*
X502864D01*
X504181Y352317D01*
X505612D01*
X508095Y354800D01*
X509595D01*
X510962Y356167D01*
X512322D01*
X514321Y358166D01*
X515750D01*
X518461Y360877D01*
X519891D01*
X521080Y362066D01*
X522509D01*
X524460Y364017D01*
X525891D01*
X527840Y365966D01*
X528866D01*
X531577Y368677D01*
X532522D01*
X534345Y370500D01*
X536300D01*
X538376Y372576D01*
X539282D01*
X540473Y373767D01*
X542791D01*
X545501Y376477D01*
X546931D01*
X548120Y377666D01*
X548766D01*
X551300Y380200D01*
X553000D01*
X553700Y380900D01*
Y381275D01*
X553721Y381296D01*
Y382598D01*
X553700Y382619D01*
Y390900D01*
X555200Y392400D01*
Y393494D01*
X561288Y399582D01*
Y407352D01*
X613499Y459563D01*
X628580D01*
X636847Y467830D01*
X641936D01*
X651644Y477538D01*
Y479894D01*
X659070Y487320D01*
Y488709D01*
G01X554400Y364022D02*
X559122D01*
X565000Y369900D01*
Y389028D01*
X566296Y390324D01*
Y392070D01*
X609820Y435594D01*
X611566D01*
X637206Y461234D01*
X654800D01*
X667881Y474315D01*
Y480809D01*
X664850Y483840D01*
Y489526D01*
X676600Y501276D01*
Y501300D01*
G01X494692Y317596D02*
X494696D01*
X495900Y318800D01*
Y319900D01*
X496400Y320400D01*
Y324400D01*
X497300Y325300D01*
X498400D01*
X500200Y327100D01*
X502100D01*
X504300Y329300D01*
X505300D01*
X507000Y331000D01*
X508600D01*
X510700Y333100D01*
X512000D01*
X514000Y335100D01*
X515500D01*
X517100Y336700D01*
X518600D01*
X520600Y338700D01*
X522300D01*
X524600Y341000D01*
X525900D01*
X527700Y342800D01*
X528800D01*
X530900Y344900D01*
X532400D01*
X534100Y346600D01*
X535700D01*
X537900Y348800D01*
X539200D01*
X541200Y350800D01*
X542700D01*
X544300Y352400D01*
X545800D01*
X547700Y354300D01*
X548900D01*
X550800Y356200D01*
X555300D01*
X568200Y369100D01*
Y391280D01*
X610610Y433690D01*
X653260D01*
X682560Y462990D01*
Y496258D01*
X679128Y499690D01*
Y503667D01*
X679049Y503746D01*
G01X483600Y337200D02*
X485400D01*
X487100Y338900D01*
X488300D01*
X490400Y341000D01*
X491800D01*
X494100Y343300D01*
X495900D01*
X497300Y344700D01*
X498300D01*
X500400Y346800D01*
X502000D01*
X503500Y348300D01*
X504064D01*
X504181Y348417D01*
X505417D01*
X507900Y350900D01*
X509200D01*
X511000Y352700D01*
X512300D01*
X513900Y354300D01*
X515200D01*
X517500Y356600D01*
X518800D01*
X520300Y358100D01*
X521014D01*
X521080Y358166D01*
X521566D01*
X522326Y358926D01*
X522382D01*
X523301Y359845D01*
Y359901D01*
X523700Y360300D01*
X525400D01*
X527400Y362300D01*
X529100D01*
X530600Y363800D01*
X531003D01*
X531220Y364017D01*
X532522D01*
X532670Y363870D01*
X533681Y364881D01*
Y365047D01*
X534600Y365966D01*
X535902D01*
X535934Y365934D01*
X538100Y368100D01*
X539200D01*
X541700Y370600D01*
X543000D01*
X544600Y372200D01*
X545700D01*
X547700Y374200D01*
X549200D01*
X551200Y376200D01*
X554000D01*
X557300Y379500D01*
Y393964D01*
X561624Y398288D01*
X569820D01*
X609030Y437498D01*
X609689D01*
X638088Y465897D01*
X656418D01*
X665976Y475455D01*
Y480020D01*
X661911Y484085D01*
Y489281D01*
X670400Y497770D01*
Y500200D01*
X671500Y501300D01*
G01X674000Y501200D02*
X672600Y499800D01*
Y498623D01*
X663020Y489043D01*
Y484323D01*
X666929Y480414D01*
Y474710D01*
X655352Y463133D01*
X636671D01*
X610084Y436546D01*
X609425D01*
X565344Y392465D01*
Y391806D01*
X562800Y389262D01*
Y374900D01*
X560100Y372200D01*
G01X1137540Y325396D02*
X1138837Y328395D01*
X1138904Y328510D01*
X1138923Y328544D01*
G03X1138904Y330083I-1383J753D01*
G02X1138879Y332368I2016J1165D01*
G01X1138904Y332410D01*
X1138923Y332444D01*
G03X1138904Y333983I-1383J753D01*
G02X1138879Y336268I2016J1165D01*
G01X1138904Y336310D01*
X1138923Y336344D01*
G03X1138904Y337883I-1383J753D01*
G02X1138879Y340168I2016J1165D01*
G01X1138904Y340210D01*
X1138923Y340244D01*
G03X1138904Y341783I-1383J753D01*
G02X1138879Y344068I2016J1165D01*
G01X1138904Y344110D01*
X1138923Y344144D01*
G03X1138904Y345683I-1383J753D01*
G02X1138879Y347968I2016J1165D01*
G01X1138904Y348010D01*
X1138923Y348044D01*
G03X1138904Y349583I-1383J753D01*
G02X1138879Y351868I2016J1165D01*
G01X1138904Y351910D01*
X1138923Y351944D01*
G03X1138904Y353483I-1383J753D01*
G02X1140839Y356973I2016J1164D01*
G01X1140968D01*
G03X1142284Y357760I-48J1574D01*
G02X1144205Y358922I2016J-1164D01*
G01X1144328D01*
G03X1145664Y359710I-28J1574D01*
G02X1147599Y360873I2016J-1163D01*
G01X1147728D01*
G03X1149044Y361660I-48J1574D01*
G02X1150965Y362822I2016J-1164D01*
G01X1151088D01*
G03X1152424Y365183I-28J1574D01*
G02X1152399Y367468I2016J1165D01*
G01X1152424Y367510D01*
X1152443Y367544D01*
G03X1152424Y369083I-1383J753D01*
G02X1152399Y371368I2016J1165D01*
G01X1152424Y371410D01*
G03X1152443Y372949I-1364J786D01*
G01X1152424Y372983D01*
G02Y375309I2016J1163D01*
G03Y376883I-1364J787D01*
G02X1152399Y379168I2016J1165D01*
G01X1152424Y379210D01*
X1152443Y379244D01*
G03X1152424Y380783I-1383J753D01*
G02X1152399Y383068I2016J1165D01*
G01X1152424Y383110D01*
X1152443Y383144D01*
G03X1152424Y384683I-1383J753D01*
G02X1152399Y386968I2016J1165D01*
G01X1152424Y387010D01*
X1152443Y387044D01*
G03X1152424Y388583I-1383J753D01*
G02X1154359Y392073I2016J1164D01*
G01X1154488D01*
G03X1155804Y394434I-48J1574D01*
G02Y396760I2016J1163D01*
G02X1156125Y397199I2183J-1259D01*
G02X1157908Y398959I17630J-16077D01*
G01X1159447Y400498D01*
Y401925D01*
X1165769Y408247D01*
X1172576D01*
X1187402Y423073D01*
X1190967D01*
X1249299Y481405D01*
X1258258D01*
X1261945Y485092D01*
Y488969D01*
X1266574Y493598D01*
X1268168D01*
X1268948Y494378D01*
X1272784D01*
X1279917Y501511D01*
X1282811D01*
X1286282Y504982D01*
X1298632D01*
X1310950Y517300D01*
Y520850D01*
X1308273Y523527D01*
Y535857D01*
X1300037Y544093D01*
X1283376D01*
X1275928Y551541D01*
Y585901D01*
X1273851Y587978D01*
Y608318D01*
X1265728Y616441D01*
X1045459D01*
X1044210Y617690D01*
X1044201D01*
X1043809Y618082D01*
X770073D01*
X761471Y609480D01*
Y590326D01*
X757725Y586580D01*
Y521702D01*
X755767Y519744D01*
Y512500D01*
X750587Y507320D01*
X730797D01*
X720398Y517719D01*
X697120D01*
X693792Y514391D01*
Y510507D01*
X688900Y505615D01*
X685016D01*
X685015Y505614D01*
X678688D01*
X677473Y504399D01*
Y502845D01*
X678176Y502142D01*
Y500647D01*
X674829Y497300D01*
X673971D01*
X671980Y495309D01*
Y487246D01*
X671704Y486970D01*
Y484170D01*
X671980Y483894D01*
Y476941D01*
X654145Y459106D01*
X636467D01*
X612003Y434642D01*
X610215D01*
X567248Y391675D01*
Y389887D01*
X567100Y389739D01*
Y369400D01*
G01X621165Y256075D02*
X622458Y254782D01*
Y246958D01*
X614600Y239100D01*
X603800D01*
X590600Y225900D01*
Y218200D01*
X588820Y216420D01*
Y205880D01*
X630900Y163800D01*
X670640D01*
X714400Y120040D01*
Y93400D01*
X716268Y91532D01*
Y88683D01*
G01X620850Y253416D02*
X621026Y253240D01*
Y247826D01*
X614100Y240900D01*
X603300D01*
X589300Y226900D01*
Y218800D01*
X587500Y217000D01*
Y205400D01*
X631000Y161900D01*
X670700D01*
X713000Y119600D01*
Y92500D01*
X714692Y90808D01*
Y87931D01*
X716894Y85729D01*
Y84047D01*
G01X1495651Y311350D02*
X1498985Y308016D01*
Y301802D01*
X1498147Y300964D01*
Y298746D01*
X1498476Y298417D01*
Y289412D01*
X1498411Y289347D01*
Y283409D01*
X1501257Y280563D01*
Y279257D01*
X1499004Y277004D01*
Y266432D01*
X1495572Y263000D01*
X1492195D01*
X1489284Y260089D01*
Y251156D01*
X1494028Y246412D01*
Y240049D01*
X1491621Y237642D01*
Y233044D01*
X1488646Y230069D01*
Y223233D01*
X1483684Y218271D01*
X1472305D01*
X1462277Y208243D01*
Y204618D01*
X1446578Y188919D01*
X1441857D01*
X1405486Y152548D01*
X1395952D01*
X1390948Y157552D01*
X1324188D01*
X1319784Y153148D01*
X1316541D01*
X1311065Y147672D01*
X1308931D01*
X1303577Y142318D01*
Y131570D01*
X1297724Y125717D01*
Y86998D01*
X1296846Y86120D01*
Y61753D01*
X1301734Y56865D01*
Y41611D01*
X1299752Y39629D01*
Y25642D01*
X1294488Y20378D01*
Y-8262D01*
X1288779Y-13971D01*
X1287641D01*
X1282974Y-18638D01*
X718817D01*
X713909Y-13730D01*
Y-11444D01*
X707724Y-5259D01*
Y3905D01*
X705103Y6526D01*
X703426D01*
X703424Y6524D01*
X700238D01*
X698159Y8603D01*
X683799D01*
X680165Y4969D01*
X672221D01*
X662700Y-4552D01*
Y-17900D01*
G01X648867Y31258D02*
X649500Y31891D01*
Y43198D01*
X646826Y45872D01*
Y77926D01*
X654545Y85645D01*
Y92054D01*
X652718Y93881D01*
G01X651442Y31225D02*
X650652Y32015D01*
Y43676D01*
X650500Y43828D01*
Y43894D01*
X648405Y45989D01*
Y77805D01*
X656661Y86061D01*
X664471D01*
G01X654950Y253446D02*
X655400Y252996D01*
Y247920D01*
X662783Y240537D01*
Y198417D01*
X741700Y119500D01*
Y102000D01*
G01X732734Y82626D02*
X728220Y87140D01*
Y122009D01*
X727690Y122539D01*
Y122610D01*
X639624Y210676D01*
Y249057D01*
X626153Y262528D01*
Y279065D01*
X627529Y280441D01*
G01X730038Y88408D02*
X728972Y89474D01*
Y122978D01*
X655462Y196488D01*
Y234849D01*
X627305Y263006D01*
Y277982D01*
X629259Y279936D01*
Y287098D01*
X628525Y287832D01*
G01X763350Y81220D02*
X761953Y82617D01*
Y86747D01*
X752800Y95900D01*
X740800D01*
X737200Y99500D01*
Y119640D01*
X659179Y197661D01*
Y237821D01*
X647150Y249850D01*
Y252828D01*
X640700Y259278D01*
Y263800D01*
X636842Y267658D01*
Y281783D01*
X639728Y284669D01*
Y287817D01*
X637560Y289985D01*
X636477D01*
X634407Y287915D01*
G01X720572Y88700D02*
X719262Y90010D01*
Y117338D01*
X671400Y165200D01*
X631299D01*
X628650Y167850D01*
X626486Y170014D01*
Y238514D01*
X624500Y240500D01*
G01X1468450Y252900D02*
X1468194D01*
X1462924Y247630D01*
Y243131D01*
X1441540Y221751D01*
X1434550D01*
X1419141Y206342D01*
X1413557D01*
X1405061Y197846D01*
X1293629D01*
X1271929Y176146D01*
X1260443D01*
X1254214Y169917D01*
Y142271D01*
X1261032Y135453D01*
X1265253D01*
X1275524Y125182D01*
Y112537D01*
X1273076Y110089D01*
Y100855D01*
X1272742Y100521D01*
Y98259D01*
X1273280Y97721D01*
Y-9449D01*
X1267099Y-15630D01*
X766174D01*
X760100Y-9556D01*
Y13900D01*
X762100Y15900D01*
Y22800D01*
X760100Y24800D01*
Y63100D01*
X750316Y72884D01*
X750145Y73297D01*
X746250Y77192D01*
X729491D01*
X723660Y83023D01*
Y119040D01*
X629027Y213673D01*
Y242889D01*
X625538Y246378D01*
Y256124D01*
X618500Y263162D01*
Y327531D01*
X647860Y356891D01*
X679021D01*
X684993Y362863D01*
Y368387D01*
X683947Y369433D01*
Y389928D01*
X686619Y392600D01*
G01X691240Y390039D02*
X690928Y389727D01*
Y363976D01*
X686699Y359747D01*
Y355500D01*
X684399Y353200D01*
X648676D01*
X647418Y351942D01*
Y351318D01*
X623901Y327801D01*
Y263150D01*
X634525Y252526D01*
Y248594D01*
X635085Y248034D01*
Y213514D01*
X727068Y121531D01*
Y86063D01*
X732131Y81000D01*
X749929D01*
X768250Y62679D01*
Y-10499D01*
X770373Y-12622D01*
X1261319D01*
X1263516Y-10425D01*
Y10645D01*
X1260185Y13976D01*
Y57755D01*
X1263516Y61086D01*
Y107188D01*
X1266126Y109798D01*
Y115323D01*
X1260811Y120638D01*
Y125003D01*
X1249948Y135866D01*
X1248209D01*
X1241902Y142173D01*
Y146508D01*
X1238237Y150173D01*
X1233910D01*
X1217660Y166423D01*
Y183528D01*
X1226146Y192014D01*
X1246035D01*
X1248868Y189181D01*
X1263321D01*
X1285067Y210927D01*
X1334227D01*
X1339956Y216656D01*
X1374824D01*
X1381575Y209905D01*
X1393509D01*
X1396933Y213329D01*
Y215763D01*
G01X636799Y285670D02*
X628457Y277328D01*
Y263484D01*
X656954Y234987D01*
Y196626D01*
X729724Y123856D01*
Y91283D01*
X732599Y88408D01*
G01X636985Y288264D02*
X638562Y286687D01*
Y285161D01*
X629609Y276208D01*
Y263962D01*
X658106Y235465D01*
Y197104D01*
X732866Y122344D01*
Y101453D01*
X736639Y97680D01*
Y94529D01*
X735241Y93131D01*
Y88329D01*
G01X701500Y505500D02*
X704500D01*
X707900Y508900D01*
X716729D01*
X717676Y507953D01*
Y504010D01*
X715745Y502079D01*
Y432635D01*
X701548Y418438D01*
Y412150D01*
X689576Y400178D01*
Y391669D01*
X685851Y387944D01*
Y370223D01*
X686897Y369177D01*
Y362073D01*
X679563Y354739D01*
X648087D01*
X621173Y327825D01*
Y263184D01*
X627698Y256659D01*
Y246913D01*
X630751Y243860D01*
Y214949D01*
X725564Y120136D01*
Y84873D01*
X731341Y79096D01*
X749705D01*
X761772Y67029D01*
Y34100D01*
X766700Y29172D01*
Y2900D01*
X761772Y-2028D01*
Y-9100D01*
X766798Y-14126D01*
X1265855D01*
X1271376Y-8605D01*
Y92888D01*
X1265420Y98844D01*
Y106398D01*
X1268031Y109009D01*
Y109631D01*
X1268030Y109632D01*
Y116105D01*
X1267000Y117135D01*
Y117143D01*
X1265475Y118668D01*
X1264909D01*
X1262315Y121262D01*
Y125957D01*
X1250556Y137716D01*
X1249111D01*
X1249110Y137715D01*
X1248488D01*
X1246516Y139687D01*
Y140933D01*
X1246517Y140934D01*
Y169464D01*
X1249238Y172185D01*
Y174115D01*
X1248968Y174385D01*
Y177589D01*
X1253901Y182522D01*
X1262930D01*
X1285007Y204599D01*
X1338725D01*
X1342852Y208726D01*
Y212091D01*
X1343809Y213048D01*
X1370324D01*
X1377030Y206342D01*
X1403962D01*
X1406970Y209350D01*
X1417367D01*
X1432841Y224824D01*
X1437497D01*
X1437498Y224823D01*
X1438120D01*
X1438121Y224824D01*
X1438603D01*
X1456000Y242221D01*
Y248642D01*
X1461128Y253770D01*
Y255564D01*
X1461664Y256100D01*
X1464700D01*
G01X710643Y505496D02*
Y505157D01*
X713550Y502250D01*
Y431504D01*
X700796Y418750D01*
Y412798D01*
X688824Y400826D01*
Y391981D01*
X685099Y388256D01*
Y369911D01*
X686145Y368865D01*
Y362385D01*
X679499Y355739D01*
X648023D01*
X620421Y328137D01*
Y262871D01*
X626691Y256601D01*
Y246855D01*
X629855Y243691D01*
Y214545D01*
X724812Y119588D01*
Y84561D01*
X731029Y78344D01*
X749393D01*
X760952Y66785D01*
Y32500D01*
X765700Y27752D01*
Y3300D01*
X760952Y-1448D01*
Y-9344D01*
X766486Y-14878D01*
X1266167D01*
X1272128Y-8917D01*
Y93200D01*
X1266172Y99156D01*
Y106086D01*
X1270655Y110569D01*
Y118360D01*
X1268842Y120173D01*
X1265676D01*
X1263819Y122030D01*
Y126581D01*
X1251180Y139220D01*
X1249111D01*
X1248021Y140310D01*
Y168840D01*
X1250742Y171561D01*
Y174739D01*
X1250472Y175009D01*
Y176965D01*
X1254525Y181018D01*
X1262930D01*
X1262931Y181017D01*
X1272544D01*
X1293470Y201943D01*
X1329821D01*
X1329822Y201942D01*
X1340596D01*
X1345418Y206764D01*
X1361831D01*
X1366611Y211544D01*
X1369700D01*
X1380651Y200593D01*
X1402961D01*
X1406671Y204303D01*
Y206923D01*
X1407594Y207846D01*
X1418099D01*
X1433573Y223320D01*
X1436873D01*
X1436874Y223319D01*
X1437496D01*
X1437497Y223318D01*
X1438743D01*
X1438745Y223320D01*
X1440979D01*
X1459976Y242311D01*
Y243493D01*
X1459736Y243733D01*
Y248217D01*
X1465063Y253544D01*
G01X1470556Y256900D02*
Y257000D01*
X1469856Y257700D01*
X1462200D01*
X1460376Y255876D01*
Y254082D01*
X1455248Y248954D01*
Y242533D01*
X1438291Y225576D01*
X1432251D01*
X1417104Y210429D01*
X1401618D01*
X1398377Y207188D01*
X1377248D01*
X1370636Y213800D01*
X1343497D01*
X1342100Y212403D01*
Y209038D01*
X1338413Y205351D01*
X1284695D01*
X1262619Y183275D01*
X1251306D01*
X1245079Y177048D01*
Y175742D01*
X1246002Y174819D01*
X1247470D01*
X1248486Y173803D01*
Y172497D01*
X1245764Y169775D01*
Y139375D01*
X1248176Y136963D01*
X1249915D01*
X1261563Y125315D01*
Y120950D01*
X1266878Y115635D01*
Y108920D01*
X1264668Y106710D01*
Y98532D01*
X1266733Y96467D01*
Y90001D01*
X1270230Y86504D01*
Y65170D01*
X1263544Y58484D01*
Y15451D01*
X1266733Y12262D01*
Y-10554D01*
X1263913Y-13374D01*
X770061D01*
X767498Y-10811D01*
Y-5227D01*
X764724Y-2453D01*
Y-1147D01*
X767498Y1627D01*
Y31901D01*
X764324Y35075D01*
Y36574D01*
X765676Y37926D01*
Y64189D01*
X750017Y79848D01*
X732219D01*
X726316Y85751D01*
Y120585D01*
X634177Y212724D01*
Y243797D01*
X633368Y244606D01*
X631069D01*
X628624Y247051D01*
Y256797D01*
X623149Y262272D01*
Y328737D01*
X648399Y353987D01*
X679875D01*
X690176Y364288D01*
Y368824D01*
X689664Y369336D01*
Y390693D01*
X690328Y391357D01*
Y399630D01*
X702300Y411602D01*
Y418126D01*
X716497Y432323D01*
Y501688D01*
X718428Y503619D01*
Y508265D01*
X716993Y509700D01*
X706400D01*
X703800Y507100D01*
G01X766824Y85943D02*
X753567Y99200D01*
X742100D01*
X740000Y101300D01*
Y120100D01*
X661483Y198617D01*
Y239417D01*
X653881Y247019D01*
Y251779D01*
X653120Y252540D01*
Y254480D01*
X650424Y257176D01*
Y273753D01*
X654348Y277677D01*
X662379D01*
X662786Y278084D01*
G01X655000Y284600D02*
Y280002D01*
X649249Y274251D01*
Y256681D01*
X652182Y253748D01*
Y251467D01*
X652951Y250698D01*
Y246149D01*
X660331Y238769D01*
Y198139D01*
X738700Y119770D01*
Y100200D01*
X741100Y97800D01*
X753200D01*
X763930Y87070D01*
Y85100D01*
G01X720300Y485800D02*
Y485292D01*
X722700Y482892D01*
Y424794D01*
X704528Y406622D01*
X702022D01*
X693310Y397910D01*
Y363653D01*
X689652Y359995D01*
Y350183D01*
X684221Y344752D01*
X647026D01*
X641070Y338796D01*
Y306723D01*
X644597Y303196D01*
X646770D01*
X649196Y300770D01*
Y292794D01*
X642396Y285994D01*
Y284717D01*
X639850Y282171D01*
Y270258D01*
X643125Y266983D01*
X643591D01*
G01X643500Y274868D02*
Y278233D01*
X645800Y280533D01*
Y284584D01*
X652600Y291384D01*
Y302180D01*
X648180Y306600D01*
X646280D01*
X644507Y308373D01*
Y337419D01*
X648436Y341348D01*
X684221D01*
X684222Y341347D01*
X685630D01*
X693056Y348773D01*
Y358585D01*
X696860Y362389D01*
Y396646D01*
X703414Y403200D01*
X706100D01*
X727103Y424203D01*
Y483303D01*
X723792Y486614D01*
Y489148D01*
G01X721301Y488200D02*
X722090Y487411D01*
Y485909D01*
X725146Y482853D01*
Y424833D01*
X705233Y404920D01*
X702727D01*
X695060Y397253D01*
Y362996D01*
X691354Y359290D01*
Y349478D01*
X684926Y343050D01*
X647731D01*
X642805Y338124D01*
Y338024D01*
X642772Y337991D01*
Y307428D01*
X645302Y304898D01*
X647475D01*
X650898Y301475D01*
Y292089D01*
X644098Y285289D01*
Y281238D01*
X641650Y278790D01*
Y270865D01*
X642855Y269660D01*
G01X661232Y287321D02*
X660400Y286489D01*
Y283498D01*
X663511Y280387D01*
Y278809D01*
X662786Y278084D01*
G01X690048Y281053D02*
Y281561D01*
X687025Y284584D01*
X678626D01*
X675302Y281260D01*
X665740D01*
X662200Y284800D01*
G01X646800Y326100D02*
X648500Y324400D01*
Y315100D01*
X646550Y313150D01*
Y309000D01*
X646700Y308850D01*
G01D02*
X648650D01*
Y308750D01*
X653200Y304200D01*
X685929D01*
X689676Y307947D01*
Y335476D01*
X694600Y340400D01*
X697100D01*
X698600Y338900D01*
G01X687300Y325200D02*
X680300Y332200D01*
X665850D01*
X658900Y339150D01*
G01D02*
X647850Y328100D01*
X647100D01*
X646400Y328800D01*
X646272D01*
G01X662238Y296146D02*
Y291406D01*
X656924Y286092D01*
Y283833D01*
X660901Y279856D01*
G01X1318500Y539900D02*
X1316769Y538169D01*
X1307308D01*
X1300432Y545045D01*
X1283771D01*
X1276880Y551936D01*
Y586990D01*
X1274919Y588951D01*
Y608597D01*
X1266123Y617393D01*
X1045854D01*
X1044605Y618642D01*
X1044596D01*
X1044204Y619034D01*
X769678D01*
X760518Y609874D01*
Y609086D01*
X760519Y609085D01*
Y590721D01*
X756773Y586975D01*
Y541237D01*
X754137Y538601D01*
Y529863D01*
X747531Y523257D01*
X738311D01*
X733890Y518836D01*
X696476D01*
X690950Y513310D01*
Y512000D01*
X686775Y507825D01*
X675525D01*
X662551Y494851D01*
Y491268D01*
X660646Y489363D01*
Y483807D01*
X657553Y480714D01*
X655884D01*
X642248Y467078D01*
X637254D01*
X625376Y455200D01*
X612937D01*
X609191Y451454D01*
G01X1316100Y543400D02*
X1315200Y544300D01*
X1303660D01*
X1295500Y552460D01*
Y554000D01*
X1290400Y559100D01*
X1281600D01*
X1278032Y562668D01*
Y587468D01*
X1276071Y589429D01*
Y609075D01*
X1266601Y618545D01*
X1045766D01*
X1044917Y619394D01*
X1044908D01*
X1044516Y619786D01*
X745396D01*
X736557Y610947D01*
Y590656D01*
X732500Y586599D01*
Y583000D01*
X726500Y577000D01*
X712000D01*
X709550Y579450D01*
X687930D01*
X684110Y575630D01*
X677740D01*
X673920Y579450D01*
X639429D01*
X634003Y577203D01*
X631579Y574779D01*
X630180Y571401D01*
X625800Y560827D01*
Y511616D01*
X647916Y489500D01*
X656050D01*
G01X755900Y593650D02*
Y587732D01*
X755621Y587453D01*
Y584172D01*
X753286Y581837D01*
X736566D01*
X730476Y575747D01*
Y570076D01*
X722500Y562100D01*
X656500D01*
X654500Y560100D01*
X632100D01*
X629200Y557200D01*
Y512606D01*
X645206Y496600D01*
X653800D01*
G01X605510Y517999D02*
Y528899D01*
G01X636500Y493924D02*
Y495480D01*
X622700Y509280D01*
Y514150D01*
X620480Y516370D01*
X607139D01*
X605510Y517999D01*
G01Y510157D02*
Y513025D01*
X603913Y514622D01*
Y535460D01*
X605510Y537057D01*
G01X627000Y478300D02*
X625100D01*
X623000Y480400D01*
Y492667D01*
X605510Y510157D01*
G01X659070Y488709D02*
X653768Y494011D01*
X646165D01*
X628049Y512127D01*
X628048Y512130D01*
Y557678D01*
X631670Y561300D01*
X639000D01*
X642576Y564876D01*
X723205D01*
X729251Y570922D01*
Y576152D01*
X736133Y583034D01*
X748134D01*
X753300Y588200D01*
Y593600D01*
G01X605510Y566699D02*
Y570578D01*
X607226Y572294D01*
Y591883D01*
X605510Y593599D01*
G01Y555799D02*
Y566699D01*
G01Y528899D02*
Y531801D01*
X607181Y533472D01*
Y554128D01*
X605510Y555799D01*
G01Y585757D02*
Y590399D01*
X603823Y592086D01*
Y610970D01*
X605510Y612657D01*
G01Y574857D02*
Y585757D01*
G01Y547957D02*
Y549830D01*
X603868Y551472D01*
Y573215D01*
X605510Y574857D01*
G01Y537057D02*
Y547957D01*
G01Y593599D02*
Y604499D01*
G01X1046500Y623500D02*
X1045779Y622779D01*
X1045764Y622794D01*
X739294D01*
X730252Y613752D01*
X714285D01*
X709348Y608815D01*
Y604848D01*
X696600Y592100D01*
X685600D01*
X681100Y596600D01*
X673200D01*
X663700Y606100D01*
X655300D01*
X643900Y617500D01*
X633482D01*
X631741Y615759D01*
G01X704150Y19650D02*
X707300Y16500D01*
X725000D01*
X729083Y12417D01*
X734217D01*
X751600Y29800D01*
Y41000D01*
G01X1355500Y83000D02*
X1356672D01*
X1357024Y82648D01*
Y80048D01*
X1353973Y76997D01*
X1343434D01*
X1339712Y73275D01*
Y57701D01*
X1330903Y48892D01*
X1321739D01*
X1308070Y35223D01*
X1303644D01*
X1302356Y33935D01*
Y22862D01*
X1297863Y18369D01*
Y5962D01*
X1295992Y4091D01*
Y-17817D01*
X1293667Y-20142D01*
X713404D01*
X711516Y-18254D01*
X708778D01*
X708330Y-17806D01*
G01X1359500Y83000D02*
X1358328D01*
X1357976Y82648D01*
Y79653D01*
X1354368Y76045D01*
X1343829D01*
X1340664Y72880D01*
Y57306D01*
X1331484Y48126D01*
X1322037D01*
X1308382Y34471D01*
X1303956D01*
X1303108Y33623D01*
Y22267D01*
X1298615Y17774D01*
Y5367D01*
X1296850Y3602D01*
Y-18023D01*
X1293979Y-20894D01*
X712940D01*
X711245Y-19199D01*
X710747D01*
X710107Y-19839D01*
G01X710327Y-11968D02*
X706269Y-16026D01*
Y-18230D01*
X709685Y-21646D01*
X1295438D01*
X1297738Y-19346D01*
Y2486D01*
X1299367Y4115D01*
Y16781D01*
X1304480Y21894D01*
Y29505D01*
X1322349Y47374D01*
X1331796D01*
X1331810Y47388D01*
X1332226D01*
X1341578Y56740D01*
Y72238D01*
X1343340Y74000D01*
X1351488D01*
G01X692400Y20800D02*
Y18750D01*
X696942Y14208D01*
X704464D01*
X706196Y12476D01*
X711942D01*
X715913Y8505D01*
Y-4810D01*
X715345Y-5378D01*
Y-9469D01*
X723762Y-17886D01*
X1278326D01*
X1280676Y-15536D01*
Y-11476D01*
X1280025Y-10825D01*
Y7738D01*
X1279722Y8041D01*
Y35987D01*
X1284435Y40700D01*
X1295367D01*
X1300230Y45563D01*
Y54534D01*
X1293406Y61358D01*
X1285108D01*
X1279825Y66641D01*
Y96429D01*
X1290856Y107460D01*
Y123096D01*
X1297444Y129684D01*
Y139837D01*
X1309223Y151616D01*
X1311452D01*
X1314656Y154820D01*
X1318820D01*
X1325576Y161576D01*
X1390753D01*
X1398229Y154100D01*
X1404910D01*
X1441233Y190423D01*
X1445954D01*
X1460773Y205242D01*
Y208867D01*
X1471681Y219775D01*
X1483060D01*
X1487142Y223857D01*
Y232009D01*
X1490063Y234930D01*
Y248228D01*
X1488078Y250213D01*
Y250234D01*
X1487780Y250532D01*
Y261038D01*
X1491246Y264504D01*
X1494704D01*
X1496300Y266100D01*
X1496544D01*
X1497500Y267056D01*
Y269000D01*
X1495285Y271215D01*
Y273024D01*
X1495242Y273067D01*
Y274369D01*
X1495285Y274412D01*
Y275446D01*
X1495242Y275489D01*
Y278368D01*
X1496698Y279824D01*
X1497253D01*
X1498176Y280747D01*
Y282053D01*
X1495058Y285171D01*
Y294279D01*
X1496939Y296160D01*
Y300820D01*
X1497509Y301390D01*
Y303120D01*
G01X727776Y188811D02*
X727628D01*
X725581Y186764D01*
X678078D01*
X663860Y200982D01*
Y234280D01*
X666146Y236566D01*
X674430D01*
X683774Y245910D01*
Y251001D01*
X681861Y252914D01*
Y273660D01*
X682871Y274670D01*
X691060D01*
X694400Y278010D01*
Y287850D01*
X691113Y291137D01*
Y307223D01*
X705908Y322018D01*
Y332338D01*
X719948Y346378D01*
Y410548D01*
X738200Y428800D01*
Y431850D01*
X747950Y441600D01*
G01X748500Y438900D02*
X739850Y430250D01*
Y429250D01*
X721100Y410500D01*
Y345900D01*
X707060Y331860D01*
Y321540D01*
X692265Y306745D01*
Y298095D01*
X696990Y293370D01*
Y283500D01*
X695330Y281840D01*
Y275750D01*
X692480Y272900D01*
X685539D01*
X683349Y270710D01*
Y253902D01*
X685019Y252232D01*
Y245525D01*
X674908Y235414D01*
X666624D01*
X664895Y233685D01*
Y201577D01*
X678556Y187916D01*
X723874D01*
X724888Y188930D01*
G01X752900Y101000D02*
Y109400D01*
X762504Y119004D01*
Y172704D01*
X773200Y183400D01*
Y193428D01*
X771080Y195548D01*
X744780D01*
X728952Y211376D01*
Y232742D01*
X730924Y234714D01*
Y244838D01*
X729056Y246706D01*
Y251110D01*
X728052Y252114D01*
Y252178D01*
X728000Y252230D01*
Y252400D01*
X725240Y255160D01*
X709960D01*
X707276Y257844D01*
X701044D01*
X700400Y257200D01*
G01X717420Y249920D02*
X717680D01*
X719541Y248059D01*
X724351D01*
X727394Y245016D01*
Y240993D01*
X725200Y238799D01*
Y213000D01*
X744956Y193244D01*
X769600D01*
X770800Y192044D01*
Y184400D01*
X760200Y173800D01*
Y124900D01*
X744200Y108900D01*
Y102800D01*
G01X756800Y99400D02*
X758000D01*
X759450Y100850D01*
Y108850D01*
X764800Y114200D01*
Y171600D01*
X775200Y182000D01*
Y194200D01*
X771948Y197452D01*
X745448D01*
X731003Y211897D01*
Y231718D01*
X733238Y233953D01*
Y248369D01*
X731919Y249688D01*
Y256442D01*
X730611Y257750D01*
X716350D01*
X715200Y258900D01*
G01X746600Y103900D02*
Y108700D01*
X761352Y123452D01*
Y173252D01*
X772000Y183900D01*
Y192496D01*
X770100Y194396D01*
X744868D01*
X728200Y211064D01*
Y233054D01*
X730172Y235026D01*
Y243666D01*
X727904Y245934D01*
Y250632D01*
X726900Y251636D01*
Y251700D01*
X724890Y253710D01*
X709620D01*
X707250Y256080D01*
X704090D01*
G01X756800Y102000D02*
Y109300D01*
X763656Y116156D01*
Y172056D01*
X774400Y182800D01*
Y187700D01*
X774448Y187748D01*
Y193552D01*
X771300Y196700D01*
X745136D01*
X730251Y211585D01*
Y232030D01*
X732486Y234265D01*
Y244497D01*
X730086Y246897D01*
Y252114D01*
X725680Y256520D01*
X714300D01*
X712800Y258020D01*
Y286600D01*
X708100Y291300D01*
Y300280D01*
X706780Y301600D01*
X705800D01*
G01X690048Y284053D02*
X689847Y283852D01*
X689348D01*
X687794Y285406D01*
X678384D01*
X674990Y282012D01*
X666052D01*
X665000Y283064D01*
Y284800D01*
G01X763450Y585200D02*
X763200Y584950D01*
Y582640D01*
X760839Y580279D01*
Y556668D01*
X765500Y552007D01*
Y546973D01*
X762300Y543773D01*
Y536328D01*
X767206Y531422D01*
Y522140D01*
X763868Y518802D01*
Y516764D01*
X765542Y515090D01*
Y497348D01*
X758352Y490158D01*
X735415D01*
X732744Y492829D01*
X728450D01*
X725834Y490213D01*
Y487192D01*
X731400Y481626D01*
Y425673D01*
X713900Y408173D01*
Y380873D01*
X704500Y371473D01*
Y340800D01*
X702700Y339000D01*
X701100D01*
G01X687400Y328200D02*
X688314Y329114D01*
Y337914D01*
X692300Y341900D01*
X698800D01*
X701100Y339600D01*
Y339000D01*
G01X674700Y339200D02*
X680100Y333800D01*
X681800D01*
X687400Y328200D01*
G01X765900Y587300D02*
Y583700D01*
X761591Y579391D01*
Y557189D01*
X766400Y552380D01*
Y546600D01*
X763200Y543400D01*
Y536700D01*
X768242Y531658D01*
Y522112D01*
X764901Y518771D01*
Y517111D01*
X766294Y515718D01*
Y497036D01*
X758516Y489258D01*
X735042D01*
X732371Y491929D01*
X728823D01*
X726734Y489840D01*
Y487565D01*
X732300Y481999D01*
Y425300D01*
X714800Y407800D01*
Y380500D01*
X705400Y371100D01*
Y338600D01*
X703900Y337100D01*
X700100D01*
X698600Y338600D01*
Y338900D01*
G01X688100Y308600D02*
Y308650D01*
X684650Y312100D01*
Y322450D01*
X687300Y325100D01*
Y325200D01*
G01X683100Y392200D02*
Y396732D01*
X699644Y413276D01*
Y419228D01*
X701052Y420636D01*
Y496353D01*
X704099Y499400D01*
X708700D01*
G01X1482004Y222483D02*
X1480800Y221279D01*
X1471057D01*
X1459269Y209491D01*
Y205866D01*
X1445330Y191927D01*
X1440571D01*
X1404248Y155604D01*
X1398853D01*
X1391152Y163305D01*
X1325177D01*
X1318196Y156324D01*
X1314032D01*
X1310828Y153120D01*
X1301983D01*
X1292059Y143196D01*
Y127559D01*
X1288552Y124052D01*
Y108416D01*
X1277121Y96985D01*
Y65519D01*
X1283586Y59054D01*
X1293546D01*
X1298726Y53874D01*
Y46187D01*
X1295461Y42922D01*
X1284528D01*
X1277900Y36294D01*
Y-9575D01*
X1277922Y-9597D01*
Y-10903D01*
X1276957Y-11868D01*
X1272347D01*
X1267833Y-16382D01*
X765862D01*
X758504Y-9024D01*
Y21627D01*
X759500Y22623D01*
Y24336D01*
X759348Y24488D01*
Y48330D01*
X744678Y63000D01*
X741700D01*
X737300Y67400D01*
Y71783D01*
X733671Y75412D01*
G01X731210Y-15134D02*
X748667D01*
X757752Y-6049D01*
Y21939D01*
X758290Y22477D01*
Y30410D01*
X754328Y34372D01*
Y42131D01*
X753924Y42535D01*
Y52690D01*
X746504Y60110D01*
X730357D01*
X728080Y62387D01*
Y72472D01*
X730923Y75315D01*
G01X1109200Y325100D02*
X1110300Y326200D01*
Y339900D01*
X1108300Y341900D01*
X1106900D01*
X1098100Y350700D01*
X1075300D01*
X1074500Y351500D01*
X1063300D01*
X1061300Y353500D01*
X1059500D01*
X1055890Y349890D01*
X1034810D01*
X1033300Y351400D01*
X1031800D01*
G01X1007274Y349816D02*
X1005920Y351170D01*
X1004300D01*
X1002900Y349770D01*
X1001800D01*
X1000300Y348270D01*
Y341200D01*
X998800Y339700D01*
X998000D01*
X996900Y338600D01*
Y335333D01*
X995857Y334290D01*
X994428D01*
X992477Y332339D01*
X991456D01*
X989503Y330386D01*
X987793D01*
X986596Y331583D01*
X984413D01*
X982930Y330100D01*
X981499D01*
X979499Y328100D01*
X977800D01*
X976100Y329800D01*
X974100D01*
X971984Y327684D01*
X970484D01*
X969286Y326486D01*
X968265D01*
X965979Y324200D01*
X964556D01*
X962556Y322200D01*
X960700D01*
X958600Y320100D01*
X957200D01*
X955500Y318400D01*
X953800D01*
X951900Y316500D01*
X950900D01*
X949000Y314600D01*
X946800D01*
X945300Y316100D01*
X943700D01*
X942100Y314500D01*
X940200D01*
X938400Y316300D01*
X937000D01*
X935100Y318200D01*
X933600D01*
X932000Y316600D01*
X930100D01*
X928500Y318200D01*
X927300D01*
X925800Y319700D01*
Y322900D01*
X924500Y324200D01*
X923300D01*
X921400Y326100D01*
X920100D01*
X918200Y328000D01*
X916500D01*
X914870Y329630D01*
X912830D01*
X909704Y326504D01*
X891320D01*
X852539Y365285D01*
X841628D01*
X833274Y373639D01*
Y376910D01*
X831000Y379184D01*
Y388000D01*
X830619Y388381D01*
X815119D01*
X802900Y400600D01*
Y404900D01*
X800000Y407800D01*
X785720D01*
X780430Y402510D01*
X774510D01*
X773500Y401500D01*
X766970D01*
X764880Y403590D01*
X758990D01*
X752000Y396600D01*
X743200D01*
X732000Y385400D01*
Y380000D01*
G01X766394Y414397D02*
X764624Y416167D01*
Y422287D01*
X766130Y423793D01*
Y451525D01*
X729299Y488356D01*
X728373D01*
G01X766200Y417005D02*
X765881Y417324D01*
Y421524D01*
X767558Y423201D01*
Y452117D01*
X731339Y488336D01*
Y489319D01*
G01X957283Y17057D02*
X959000Y18774D01*
Y26297D01*
X957283Y28014D01*
G01X957765Y-7180D02*
Y-3735D01*
X958900Y-2600D01*
Y10100D01*
X959300Y10500D01*
Y14400D01*
X957283Y16417D01*
Y17057D01*
G01Y28014D02*
X959500Y30231D01*
Y34299D01*
X958900Y34899D01*
Y48900D01*
X959500Y49500D01*
Y52640D01*
X957283Y54857D01*
G01D02*
X958900Y56474D01*
Y66438D01*
X957536Y67802D01*
G01D02*
X959271D01*
X959748Y68279D01*
Y78452D01*
X958900Y79300D01*
Y85900D01*
X959400Y86400D01*
Y88500D01*
X958700Y89200D01*
Y91240D01*
X957283Y92657D01*
G01Y518057D02*
X959000Y519774D01*
Y527669D01*
X957806Y528863D01*
G01X988817Y392729D02*
Y398498D01*
X989100Y398781D01*
Y418901D01*
X988700Y419301D01*
Y473944D01*
X963000Y499644D01*
Y510300D01*
X960700Y512600D01*
Y512700D01*
X958500Y514900D01*
Y516840D01*
X957283Y518057D01*
G01X957592Y566743D02*
X959305Y568456D01*
Y573794D01*
X959000Y574099D01*
Y586900D01*
X959275Y587175D01*
Y591665D01*
X957283Y593657D01*
G01Y555857D02*
X959000Y557574D01*
Y565335D01*
X957592Y566743D01*
G01X957806Y528863D02*
X959186Y530243D01*
Y535256D01*
X958900Y535542D01*
Y549400D01*
X959334Y549834D01*
Y553806D01*
X957283Y555857D01*
G01Y593657D02*
X959000Y595374D01*
Y605985D01*
X957765Y607220D01*
G01X1321600Y294700D02*
X1313674D01*
X1307439Y300935D01*
X1303529D01*
X1300059Y304405D01*
X1215172D01*
G01X1127656Y310160D02*
X1125720D01*
X1123730Y312150D01*
Y319950D01*
X1118250Y325430D01*
X1112880D01*
X1110105Y322655D01*
X1106255D01*
X1086931Y341979D01*
X1044979D01*
X1039150Y336150D01*
X1033450D01*
X1029200Y340400D01*
Y344730D01*
X1027980Y345950D01*
G01X1076435Y343595D02*
X1086986D01*
X1107051Y323530D01*
X1109851D01*
X1111200Y324879D01*
Y337600D01*
X1120447Y346847D01*
X1120641D01*
G01X1404286Y281729D02*
Y278406D01*
X1387705Y261825D01*
X1325966D01*
X1306146Y281645D01*
X1217036D01*
X1212508Y277117D01*
X1210698D01*
X1208785Y275204D01*
G03X1206873Y274393I47J-2770D01*
G03X1206503Y273910I1647J-1645D01*
G02X1203775I-1364J786D01*
G03X1201840Y275073I-2016J-1163D01*
G01X1201678D01*
G03X1199743Y273910I81J-2326D01*
G02X1197015I-1364J786D01*
G03X1195080Y275073I-2016J-1163D01*
G01X1194925D01*
G02X1193635Y275859I74J1573D01*
G03X1191700Y277022I-2016J-1163D01*
G01X1191571D01*
G02X1190255Y277809I48J1574D01*
G03X1186223I-2016J-1163D01*
G02X1183495I-1364J787D01*
G03X1179463I-2016J-1163D01*
G02X1176735I-1364J787D01*
G03X1172703I-2016J-1163D01*
G02X1171387Y277022I-1364J787D01*
G01X1171258D01*
G03X1169323Y275859I81J-2326D01*
G02X1168013Y275073I-1363J787D01*
G01X1167879D01*
G02X1166333Y275452I0J3343D01*
G03X1164661Y276270I-1672J-1300D01*
G01X1116999Y286826D02*
Y286408D01*
X1118670Y284737D01*
X1120700D01*
X1125355Y280082D01*
Y276145D01*
X1130900Y270600D01*
X1135300D01*
X1137000Y268900D01*
X1138400D01*
X1140500Y266800D01*
X1142169D01*
X1143349Y265620D01*
G01X1114340Y280560D02*
X1115786D01*
X1116155Y280191D01*
X1120759D01*
X1122884Y278066D01*
Y276116D01*
X1132780Y266220D01*
X1135680D01*
X1138800Y263100D01*
X1142142D01*
X1143614Y264572D01*
X1144986D01*
X1146458Y263100D01*
X1148324D01*
X1150521Y265297D01*
X1151723D01*
X1152659Y266233D01*
Y270279D01*
X1153360Y270980D01*
X1155610D01*
X1157377Y272747D01*
X1161200D01*
G01X1398926Y281582D02*
Y276293D01*
X1386362Y263729D01*
X1327231D01*
X1306816Y284144D01*
X1216103D01*
X1210910Y278951D01*
X1208466D01*
G03X1206583Y277948I0J-2270D01*
G01X1206503Y277809D01*
G02X1203775I-1364J787D01*
G03X1199743I-2016J-1163D01*
G02X1197015I-1364J787D01*
G03X1195043Y278973I-2016J-1163D01*
G01X1194951D01*
G02X1193635Y279760I48J1574D01*
G03X1191714Y280922I-2016J-1164D01*
G01X1191591D01*
G02X1190255Y281710I28J1574D01*
G03X1186223I-2016J-1163D01*
G02X1183495I-1364J786D01*
G03X1179463I-2016J-1163D01*
G02X1176735I-1364J786D01*
G03X1172703I-2016J-1163D01*
G02X1171367Y280922I-1364J786D01*
G01X1171244D01*
G03X1169323Y279760I95J-2326D01*
G01X1169314Y279745D01*
G02X1168187Y278990I-1354J803D01*
G02X1167912Y278973I-240J1645D01*
G02X1166596Y279760I48J1574D01*
G03X1165259Y280270I-982J-567D01*
G02X1164499Y280170I-678J2217D01*
G02X1164133Y280212I82J2326D01*
G03X1162812Y279484I-226J-1152D01*
G02X1161182Y278596I-1339J519D01*
G02X1159184Y279383I0J2930D01*
G03X1158089Y280148I-1364J-787D01*
G03X1156309Y279528I-290J-2034D01*
G02X1154440Y278596I-2214J2100D01*
G02X1152751Y279572I1J1951D01*
G01X1152750D01*
G03X1151139Y280546I-1690J-976D01*
G01X1150981D01*
G03X1149370Y279572I79J-1950D01*
G02X1145990I-1690J975D01*
G03X1144379Y280546I-1690J-976D01*
G01X1144252D01*
G02X1142610Y281522I48J1950D01*
G03X1140985Y282497I-1690J-975D01*
G01X1140919D01*
G02X1139230Y283472I0J1950D01*
G03X1137619Y284446I-1690J-976D01*
G01X1137540D01*
X1134160Y284447D01*
G01X1144300Y266896D02*
X1145453Y266232D01*
X1145805Y266327D01*
G02X1147599Y267273I1874J-1380D01*
G01X1147728D01*
G03X1149063Y269599I-48J1574D01*
G01X1149044Y269633D01*
X1149019Y269675D01*
G02X1150965Y273122I2041J1121D01*
G01X1151088D01*
G03X1152424Y273910I-28J1574D01*
G02X1153979Y275028I2016J-1163D01*
G02X1154468Y275073I453J-2240D01*
G03X1155804Y275861I-28J1574D01*
G02X1157359Y276979I2016J-1163D01*
G02X1159836Y275859I459J-2284D01*
G03X1161126Y275073I1364J787D01*
G01X1161274D01*
G03X1162564Y275859I-74J1573D01*
G02X1164499Y277022I2016J-1163D01*
G01X1164628D01*
G03X1165728Y277518I-48J1574D01*
G02X1167895Y278220I2167J-2994D01*
G01X1168100D01*
X1168217Y278233D01*
G03X1169976Y279383I-257J2314D01*
G01X1169985Y279398D01*
G02X1171339Y280170I1354J-801D01*
G01X1171420D01*
G03X1173355Y281333I-81J2326D01*
G02X1176083I1364J-786D01*
G03X1180115I2016J1163D01*
G02X1182843I1364J-786D01*
G03X1186875I2016J1163D01*
G02X1189603I1364J-786D01*
G03X1191538Y280170I2016J1163D01*
G01X1191667D01*
G02X1192983Y279383I-48J-1574D01*
G03X1194934Y278220I2016J1164D01*
G01X1195047D01*
G02X1196363Y277433I-48J-1574D01*
G03X1200395I2016J1163D01*
G02X1203123I1364J-787D01*
G03X1207155I2016J1163D01*
G01X1207217Y277540D01*
G02X1208436Y278182I1219J-837D01*
G01X1211732D01*
X1216650Y283100D01*
X1306583D01*
X1326706Y262977D01*
X1386674D01*
X1401295Y277598D01*
Y281442D01*
X1398714Y284023D01*
X1398347D01*
G01X1232765Y147845D02*
X1201000Y179610D01*
Y200672D01*
X1196149Y205523D01*
G01X1202500Y179954D02*
Y194343D01*
G01X1336074Y216500D02*
X1335050Y215476D01*
Y214583D01*
X1332567Y212100D01*
X1271249D01*
X1253049Y230300D01*
X1246005D01*
X1233580Y217875D01*
Y208869D01*
X1228708Y203997D01*
X1225721D01*
X1224024Y202300D01*
X1204987D01*
X1197943Y209344D01*
G01X1394881Y226997D02*
X1393965Y226081D01*
X1300969D01*
X1298198Y228852D01*
X1292502D01*
X1291600Y227950D01*
X1281848D01*
X1280800Y226902D01*
X1272175D01*
X1256939Y242138D01*
X1239019D01*
X1229151Y232270D01*
X1214970D01*
X1213640Y233600D01*
G01X1155804Y264160D02*
G03X1155823Y265699I-1364J786D01*
G01X1210240Y271275D02*
X1210242Y271277D01*
X1211240D01*
X1216265Y276302D01*
X1306955D01*
X1324645Y258612D01*
X1389731D01*
X1398761Y267642D01*
X1409128D01*
X1410979Y269493D01*
Y270473D01*
G01X1156456Y263783D02*
G03X1156481Y266068I-2016J1165D01*
G01X1210250Y270325D02*
X1211635D01*
X1216660Y275350D01*
X1306560D01*
X1324250Y257660D01*
X1389999D01*
X1399119Y266780D01*
X1409486D01*
X1410979Y268273D01*
X1412579D01*
G01X1113500Y323400D02*
X1110300Y320200D01*
Y294534D01*
X1113132Y291702D01*
G01D02*
X1117470D01*
X1117901Y292133D01*
X1122141D01*
X1123602Y290672D01*
X1127470D01*
G02X1128374Y290460I-68J-2325D01*
G01X1130113Y288721D01*
X1130865D01*
G01X1123415Y286700D02*
X1121615Y288500D01*
X1118300D01*
X1117548Y289252D01*
X1115230D01*
G01X1402092Y284022D02*
Y284321D01*
X1399310Y287103D01*
X1385639D01*
X1384371Y285835D01*
X1367635D01*
X1363750Y281950D01*
X1334078D01*
X1327610Y288418D01*
Y291528D01*
X1321724Y297414D01*
Y302212D01*
X1321700Y302236D01*
Y303120D01*
X1317427Y307393D01*
X1313869Y309488D01*
X1310455Y311498D01*
X1305751Y312759D01*
X1224465D01*
X1220414Y316810D01*
X1196060D01*
X1195649Y317221D01*
X1194904D01*
G02X1192983Y318383I95J2326D01*
G03X1191667Y319170I-1364J-787D01*
G01X1191538D01*
G02X1189603Y320333I81J2326D01*
G03X1188301Y321120I-1364J-786D01*
G01X1188158D01*
G02X1186223Y322283I81J2326D01*
G03X1184907Y323070I-1364J-787D01*
G01X1184811D01*
G03X1183495Y322283I48J-1574D01*
G02X1181560Y321120I-2016J1163D01*
G01X1181398D01*
G02X1179463Y322283I81J2326D01*
G03X1178147Y323070I-1364J-787D01*
G01X1178051D01*
G03X1176735Y322283I48J-1574D01*
G02X1174800Y321120I-2016J1163D01*
G01X1174657D01*
G03X1173355Y320333I62J-1573D01*
G02X1169323I-2016J1163D01*
G03X1166596I-1364J-786D01*
G02X1162564I-2016J1163D01*
G03X1161262Y321120I-1364J-786D01*
G01X1161138D01*
G03X1159836Y320333I62J-1573D01*
G02X1157901Y319170I-2016J1163D01*
G01X1157772D01*
G03X1156456Y318383I48J-1574D01*
G02X1154535Y317221I-2016J1164D01*
G01X1154412D01*
G03X1153076Y316433I28J-1574D01*
G02X1149044I-2016J1163D01*
G03X1146316I-1364J-786D01*
G02X1144381Y315270I-2016J1163D01*
G01X1143534D01*
X1142102Y313838D01*
X1140275D01*
X1138770Y315343D01*
X1136515D01*
X1135237Y314065D01*
X1133046D01*
X1131494Y315617D01*
X1130094D01*
X1128970Y316741D01*
Y335798D01*
X1128051Y336717D01*
X1126621D01*
X1123912Y339426D01*
X1123370D01*
X1122277Y340519D01*
Y345211D01*
X1120641Y346847D01*
G01X1277800Y497108D02*
X1274035Y493343D01*
X1269334D01*
X1268594Y492603D01*
X1266926D01*
X1262897Y488574D01*
Y484697D01*
X1258653Y480453D01*
X1249694D01*
X1191362Y422121D01*
X1187797D01*
X1172676Y407000D01*
X1167000D01*
X1166270Y406270D01*
Y404371D01*
G02Y403174I-1037J-598D01*
G01X1165945Y402609D01*
G02X1164624Y401821I-1365J787D01*
G01X1164482D01*
G03X1162565Y400660I98J-2325D01*
G01X1161848Y399419D01*
X1160843Y399196D01*
G03X1159648Y398189I364J-1645D01*
G02X1158066Y397230I-1439J589D01*
G03X1156456Y396383I-154J-1661D01*
G01X1156437Y396349D01*
G03X1156456Y394810I1383J-753D01*
G01X1156481Y394768D01*
G02X1154535Y391321I-2041J-1121D01*
G01X1154412D01*
G03X1153076Y388960I28J-1574D01*
G02X1153101Y386675I-2016J-1165D01*
G01X1153076Y386633D01*
X1153057Y386599D01*
G03X1153076Y385060I1383J-753D01*
G02X1153101Y382775I-2016J-1165D01*
G01X1153076Y382733D01*
X1153057Y382699D01*
G03X1153076Y381160I1383J-753D01*
G02X1153101Y378875I-2016J-1165D01*
G01X1153076Y378833D01*
X1153057Y378799D01*
G03X1153076Y377260I1383J-753D01*
G02X1153101Y374975I-2016J-1165D01*
G01X1153076Y374933D01*
G03X1153057Y373394I1364J-786D01*
G01X1153076Y373360D01*
G02Y371034I-2016J-1163D01*
G03Y369460I1364J-787D01*
G02X1153101Y367175I-2016J-1165D01*
G01X1153076Y367133D01*
X1153057Y367099D01*
G03X1153076Y365560I1383J-753D01*
G02X1151141Y362070I-2016J-1164D01*
G01X1151012D01*
G03X1149696Y361283I48J-1574D01*
G02X1147775Y360121I-2016J1164D01*
G01X1147652D01*
G03X1146316Y359333I28J-1574D01*
G02X1144381Y358170I-2016J1163D01*
G01X1144252D01*
G03X1142936Y357383I48J-1574D01*
G02X1141015Y356221I-2016J1164D01*
G01X1140892D01*
G03X1139556Y353860I28J-1574D01*
G02X1139581Y351575I-2016J-1165D01*
G01X1139556Y351533D01*
X1139537Y351499D01*
G03X1139556Y349960I1383J-753D01*
G02X1139581Y347675I-2016J-1165D01*
G01X1139556Y347633D01*
X1139537Y347599D01*
G03X1139556Y346060I1383J-753D01*
G02X1139581Y343775I-2016J-1165D01*
G01X1139556Y343733D01*
X1139537Y343699D01*
G03X1139556Y342160I1383J-753D01*
G02X1139581Y339875I-2016J-1165D01*
G01X1139556Y339833D01*
X1139537Y339799D01*
G03X1139556Y338260I1383J-753D01*
G02X1139581Y335975I-2016J-1165D01*
G01X1139556Y335933D01*
X1139537Y335899D01*
G03X1139556Y334360I1383J-753D01*
G02X1139581Y332075I-2016J-1165D01*
G01X1139556Y332033D01*
X1139537Y331999D01*
G03X1139556Y330460I1383J-753D01*
G02X1139581Y328175I-2016J-1165D01*
G01X1139556Y328133D01*
X1139537Y328099D01*
G03X1139556Y326560I1383J-753D01*
G01X1139621Y326449D01*
X1140920Y323446D01*
G01X1147680Y307847D02*
X1148833Y308512D01*
X1148927Y308864D01*
G02X1150979Y312123I2133J933D01*
G01X1151058Y312126D01*
G03X1152424Y312910I9J1567D01*
G02X1154359Y314073I2016J-1163D01*
G01X1154488D01*
G03X1155804Y314860I-48J1574D01*
G02X1159836I2016J-1164D01*
G03X1162564I1364J787D01*
G02X1164485Y316022I2016J-1164D01*
G01X1164608D01*
G03X1165944Y316810I-28J1574D01*
G02X1169997Y316773I2016J-1163D01*
G03X1172703Y316810I1342J823D01*
G02X1176735I2016J-1163D01*
G03X1179463I1364J786D01*
G02X1183495I2016J-1163D01*
G03X1186223I1364J786D01*
G02X1190255I2016J-1163D01*
G03X1191591Y316022I1364J786D01*
G01X1191714D01*
G02X1193635Y314860I-95J-2326D01*
G03X1196363I1364J787D01*
G02X1196733Y315342I2016J-1164D01*
G02X1198441Y316049I1708J-1708D01*
G01X1218485D01*
X1222787Y311747D01*
X1305886D01*
X1312133Y305500D01*
X1316600D01*
G01X1303380Y309441D02*
X1303322D01*
X1302506Y310257D01*
X1222378D01*
X1217347Y315288D01*
X1198419D01*
G03X1197265Y314810I0J-1632D01*
G03X1197015Y314483I1115J-1112D01*
G02X1192983I-2016J1164D01*
G03X1191667Y315270I-1364J-787D01*
G01X1191538D01*
G02X1189603Y316433I81J2326D01*
G03X1186875I-1364J-786D01*
G02X1182843I-2016J1163D01*
G03X1180115I-1364J-786D01*
G02X1176083I-2016J1163D01*
G03X1173355I-1364J-786D01*
G02X1169323I-2016J1163D01*
G01X1169302Y316470D01*
G03X1166596Y316433I-1342J-823D01*
G02X1164661Y315270I-2016J1163D01*
G01X1164532D01*
G03X1163216Y314483I48J-1574D01*
G02X1159184I-2016J1164D01*
G03X1156456I-1364J-787D01*
G02X1154535Y313321I-2016J1164D01*
G01X1154412D01*
G03X1153076Y312533I28J-1574D01*
G02X1151141Y311370I-2015J1161D01*
G03X1149597Y309216I-81J-1573D01*
G01X1149907Y309132D01*
X1151060Y309797D01*
G01X1368200Y284000D02*
X1364400Y280200D01*
X1334764D01*
X1326857Y288107D01*
Y291117D01*
X1325122Y292852D01*
X1314458D01*
X1307285Y300025D01*
X1303361D01*
X1300133Y303253D01*
X1214773D01*
X1213842Y304184D01*
X1200602D01*
G01X1306290Y298255D02*
X1305519Y299026D01*
X1302526D01*
X1300151Y296651D01*
X1292039D01*
X1290459Y298231D01*
X1215401D01*
X1212726Y300906D01*
X1204414D01*
X1201985Y298477D01*
X1195003D01*
G03X1192983Y297310I0J-2333D01*
G02X1190255I-1364J786D01*
G03X1186223I-2016J-1163D01*
G02X1183495I-1364J786D01*
G03X1179463I-2016J-1163D01*
G02X1176735I-1364J786D01*
G03X1172703I-2016J-1163D01*
G02X1171367Y296522I-1364J786D01*
G01X1171244D01*
G03X1169323Y295360I95J-2326D01*
G01X1169314Y295345D01*
G02X1167960Y294573I-1354J801D01*
G01X1167879D01*
G03X1165944Y293410I81J-2326D01*
G02X1163216I-1364J786D01*
G03X1159184I-2016J-1163D01*
G02X1156456I-1364J786D01*
G03X1154521Y294573I-2016J-1163D01*
G01X1154392D01*
G02X1153076Y295360I48J1574D01*
G03X1151155Y296522I-2016J-1164D01*
G01X1151032D01*
G02X1149696Y297310I28J1574D01*
G03X1147761Y298473I-2016J-1163D01*
G01X1147632D01*
G02X1146316Y299260I48J1574D01*
G03X1144556Y300410I-2016J-1164D01*
G01X1144300Y300666D01*
Y301996D01*
G01X1305558Y294313D02*
X1304139D01*
X1303940Y294114D01*
X1215990D01*
X1213580Y296524D01*
X1205058D01*
G03X1203123Y295361I81J-2326D01*
G02X1201787Y294573I-1364J786D01*
G01X1201678D01*
G03X1199743Y293410I81J-2326D01*
G02X1197015I-1364J786D01*
G03X1192983I-2016J-1163D01*
G02X1190255I-1364J786D01*
G03X1186223I-2016J-1163D01*
G02X1183495I-1364J786D01*
G03X1179463I-2016J-1163D01*
G02X1176735I-1364J786D01*
G03X1172703I-2016J-1163D01*
G02X1171367Y292622I-1364J786D01*
G01X1171244D01*
G03X1169323Y291460I95J-2326D01*
G01X1169314Y291445D01*
G02X1167960Y290673I-1354J801D01*
G01X1167879D01*
G03X1165944Y289510I81J-2326D01*
G02X1163216I-1364J786D01*
G03X1159184I-2016J-1163D01*
G02X1156456I-1364J786D01*
G03X1154521Y290673I-2016J-1163D01*
G01X1154392D01*
G02X1153076Y291460I48J1574D01*
G03X1151155Y292622I-2016J-1164D01*
G01X1151032D01*
G02X1149696Y293410I28J1574D01*
G03X1147761Y294573I-2016J-1163D01*
G01X1147632D01*
G01X1137540Y301996D02*
G02X1140920Y301997I3380J-5712199D01*
G01X1140985D01*
G02X1142651Y300689I-66J-1799D01*
G03X1143930Y299687I1235J259D01*
G02X1144528Y299654I117J-3323D01*
G02X1145664Y298883I-228J-1558D01*
G03X1147585Y297721I2016J1164D01*
G01X1147708D01*
G02X1149044Y296933I-28J-1574D01*
G03X1150979Y295770I2016J1163D01*
G01X1151108D01*
G02X1152424Y294983I-48J-1574D01*
G03X1154345Y293821I2016J1164D01*
G01X1154468D01*
G02X1155804Y293033I-28J-1574D01*
G03X1159836I2016J1163D01*
G02X1162564I1364J-786D01*
G03X1166596I2016J1163D01*
G02X1167932Y293821I1364J-786D01*
G01X1168055D01*
G03X1169976Y294983I-95J2326D01*
G01X1169985Y294998D01*
G02X1171339Y295770I1354J-801D01*
G01X1171420D01*
G03X1173355Y296933I-81J2326D01*
G02X1176083I1364J-786D01*
G03X1180115I2016J1163D01*
G02X1182843I1364J-786D01*
G03X1186875I2016J1163D01*
G02X1189603I1364J-786D01*
G03X1193635I2016J1163D01*
G02X1194971Y297721I1364J-786D01*
G01X1202414D01*
X1204702Y300009D01*
X1212110D01*
X1216753Y295366D01*
X1303421D01*
X1303997Y295942D01*
X1309738D01*
X1313580Y292100D01*
X1324800D01*
X1326105Y290795D01*
Y287795D01*
X1334452Y279448D01*
X1379848D01*
X1386384Y285984D01*
X1399311D01*
X1400516Y284779D01*
Y283369D01*
X1401439Y282446D01*
X1402774D01*
X1403816Y283488D01*
Y285352D01*
X1405364Y286900D01*
X1422500D01*
X1430360Y294760D01*
Y306058D01*
X1430355Y306083D01*
X1430286Y306429D01*
X1430267Y306522D01*
X1430051Y307608D01*
X1429289Y311427D01*
X1429287Y311429D01*
X1429135Y312186D01*
X1428515Y315284D01*
Y333158D01*
X1431315Y335958D01*
Y392134D01*
X1453600Y414419D01*
Y420960D01*
X1463203Y430563D01*
X1472980D01*
X1474151Y431734D01*
Y457679D01*
X1472703Y459127D01*
Y473934D01*
X1469372Y477265D01*
Y492199D01*
X1470829Y493656D01*
X1476958D01*
X1479128Y495826D01*
X1497136D01*
X1497523Y495439D01*
X1497524D01*
X1498546Y494417D01*
X1513112D01*
X1517848Y499153D01*
Y504936D01*
X1518828Y505916D01*
Y508226D01*
X1538166Y527564D01*
X1569215D01*
X1572138Y524641D01*
X1577977D01*
X1593369Y509251D01*
X1608995D01*
X1614198Y514454D01*
X1628912D01*
X1629778Y513588D01*
Y507294D01*
G01X1308887Y285015D02*
X1308552Y285350D01*
X1215334D01*
X1212481Y282497D01*
X1208088D01*
G03X1206979Y281522I731J-1950D01*
G02X1205869Y280546I-1840J974D01*
G01X1205091D01*
G02X1203449Y281522I48J1950D01*
G03X1201824Y282497I-1690J-975D01*
G01X1201694D01*
G03X1200069Y281522I65J-1950D01*
G02X1196689I-1690J974D01*
G03X1195064Y282497I-1690J-975D01*
G01X1194934D01*
G02X1193309Y283472I65J1950D01*
G03X1191698Y284446I-1690J-976D01*
G01X1191571D01*
G02X1189929Y285422I48J1950D01*
G03X1188304Y286397I-1690J-975D01*
G01X1188174D01*
G03X1186549Y285422I65J-1950D01*
G02X1183169I-1690J974D01*
G03X1181544Y286397I-1690J-975D01*
G01X1181477D01*
G03X1179789Y285422I0J-1949D01*
G02X1176409I-1690J974D01*
G03X1174784Y286397I-1690J-975D01*
G01X1174654D01*
G03X1173029Y285422I65J-1950D01*
G02X1171387Y284446I-1690J974D01*
G01X1171337D01*
G03X1169650Y283472I0J-1948D01*
G02X1168025Y282497I-1690J975D01*
G01X1167306D01*
G03X1165944Y281710I0J-1572D01*
G02X1163216I-1364J786D01*
G03X1159913Y282146I-1819J-1048D01*
G01X1159331Y281564D01*
G02X1157551Y280944I-1490J1414D01*
G02X1156741Y281349I270J1552D01*
G01X1156262Y281800D01*
G03X1154505Y282497I-1757J-1866D01*
G01X1154375D01*
G02X1152750Y283472I65J1950D01*
G03X1151139Y284446I-1690J-976D01*
G01X1151012D01*
G02X1149370Y285422I48J1950D01*
G03X1147745Y286397I-1690J-975D01*
G01X1147615D01*
G02X1145990Y287372I65J1950D01*
G03X1144379Y288346I-1690J-976D01*
G01X1144252D01*
G02X1142610Y289322I48J1950D01*
G03X1140985Y290297I-1690J-975D01*
G01X1140855D01*
G02X1139230Y291272I65J1950D01*
G03X1137619Y292246I-1690J-976D01*
G01X1137539D01*
G02X1135850Y293222I0J1949D01*
G01X1135818Y293277D01*
G02X1135850Y295172I1722J919D01*
G03Y297122I-1690J975D01*
G01X1135818Y297177D01*
G02X1135850Y299072I1722J919D01*
G03Y301022I-1690J975D01*
G01Y301021D01*
X1134160Y303947D01*
G01X1303866Y292345D02*
X1215669D01*
X1212242Y295772D01*
X1205111D01*
G03X1203775Y294984I28J-1574D01*
G02X1201840Y293821I-2016J1163D01*
G01X1201731D01*
G03X1200395Y293033I28J-1574D01*
G02X1196363I-2016J1163D01*
G03X1193635I-1364J-786D01*
G02X1189603I-2016J1163D01*
G03X1186875I-1364J-786D01*
G02X1182843I-2016J1163D01*
G03X1180115I-1364J-786D01*
G02X1176083I-2016J1163D01*
G03X1173355I-1364J-786D01*
G02X1171420Y291870I-2016J1163D01*
G01X1171339D01*
G03X1169985Y291098I0J-1573D01*
G01X1169976Y291083D01*
G02X1168055Y289921I-2016J1164D01*
G01X1167932D01*
G03X1166596Y289133I28J-1574D01*
G02X1162564I-2016J1163D01*
G03X1159836I-1364J-786D01*
G02X1155804I-2016J1163D01*
G03X1154468Y289921I-1364J-786D01*
G01X1154345D01*
G02X1152424Y291083I95J2326D01*
G03X1151108Y291870I-1364J-787D01*
G01X1150979D01*
G02X1149044Y293033I81J2326D01*
G03X1147708Y293821I-1364J-786D01*
G01X1147585D01*
G02X1145664Y294983I95J2326D01*
G03X1144348Y295770I-1364J-787D01*
G01X1144219D01*
G02X1142425Y296716I80J2326D01*
G02X1142087Y297339I2080J1532D01*
G03X1140920Y298097I-1098J-413D01*
G01X1137540Y298096D01*
G01X1299700Y298557D02*
X1298672Y299585D01*
X1215715D01*
X1212958Y302342D01*
X1203637D01*
X1202785Y301490D01*
X1199664D01*
G01X1199128Y301491D02*
X1197395D01*
X1197264Y301622D01*
G01X1299735Y301298D02*
X1298974Y300537D01*
X1216230D01*
X1213473Y303294D01*
X1203242D01*
X1202468Y302520D01*
X1199586D01*
G01X1319888Y290205D02*
X1312842D01*
X1311390Y288753D01*
X1216378D01*
X1214344Y290787D01*
G01X1323688Y290205D02*
X1321983Y288500D01*
X1319000D01*
X1318247Y289253D01*
X1313237D01*
X1311785Y287801D01*
X1215986D01*
X1214033Y289754D01*
G01X1280595Y496439D02*
X1278148Y493992D01*
X1276509D01*
X1274854Y492337D01*
X1269675D01*
X1268980Y491642D01*
X1267312D01*
X1263849Y488179D01*
Y483999D01*
X1259351Y479501D01*
X1250089D01*
X1191757Y421169D01*
X1188192D01*
X1172127Y405104D01*
X1170557D01*
X1169976Y404523D01*
Y404183D01*
G02X1168055Y403021I-2016J1164D01*
G01X1167960D01*
Y403022D01*
X1167916D01*
G03X1166595Y402234I44J-1575D01*
G02X1164650Y401071I-2015J1162D01*
G01X1164580D01*
G03X1163229Y400306I0J-1575D01*
G01X1162830Y399600D01*
Y397221D01*
X1162564Y396760D01*
G02X1160817Y395630I-1582J530D01*
G03X1159132Y394715I-169J-1698D01*
G03X1159184Y392483I2068J-1068D01*
G02X1157848Y390122I-1364J-787D01*
G01X1157725D01*
G03X1155779Y386675I95J-2326D01*
G01X1155804Y386633D01*
X1155823Y386599D01*
G02X1155804Y385060I-1383J-753D01*
G03X1155779Y382775I2016J-1165D01*
G01X1155804Y382733D01*
X1155823Y382699D01*
G02X1155804Y381160I-1383J-753D01*
G03X1155779Y378875I2016J-1165D01*
G01X1155804Y378833D01*
X1155823Y378799D01*
G02X1155804Y377260I-1383J-753D01*
G03X1155779Y374975I2016J-1165D01*
G01X1155804Y374933D01*
G02X1155823Y373394I-1364J-786D01*
G01X1155804Y373360D01*
G03Y371034I2016J-1163D01*
G02Y369460I-1364J-787D01*
G03X1155779Y367175I2016J-1165D01*
G01X1155804Y367133D01*
X1155823Y367099D01*
G02X1155804Y365560I-1383J-753D01*
G03X1155779Y363275I2016J-1165D01*
G01X1155804Y363233D01*
X1155823Y363199D01*
G02X1154488Y360873I-1383J-752D01*
G01X1154359D01*
G03X1152424Y359710I81J-2326D01*
G02X1151088Y358922I-1364J786D01*
G01X1150965D01*
G03X1149044Y357760I95J-2326D01*
G02X1147728Y356973I-1364J787D01*
G01X1147599D01*
G03X1145664Y355810I81J-2326D01*
G02X1144328Y355022I-1364J786D01*
G01X1144205D01*
G03X1142259Y351575I95J-2326D01*
G01X1142284Y351533D01*
X1142303Y351499D01*
G02X1142284Y349960I-1383J-753D01*
G03X1142259Y347675I2016J-1165D01*
G01X1142284Y347633D01*
X1142303Y347599D01*
G02X1142284Y346060I-1383J-753D01*
G03X1142259Y343775I2016J-1165D01*
G01X1142284Y343733D01*
X1142303Y343699D01*
G02X1142284Y342160I-1383J-753D01*
G03X1142259Y339875I2016J-1165D01*
G01X1142284Y339833D01*
X1142303Y339799D01*
G02X1142284Y338260I-1383J-753D01*
G03X1142259Y335975I2016J-1165D01*
G01X1142284Y335933D01*
X1142303Y335899D01*
G02X1142284Y334360I-1383J-753D01*
G03X1142259Y332075I2016J-1165D01*
G01X1142284Y332033D01*
X1142303Y331999D01*
G02X1142284Y330460I-1383J-753D01*
G03X1142259Y328175I2016J-1165D01*
G01X1142284Y328133D01*
X1142303Y328099D01*
G02X1142284Y326560I-1383J-753D01*
G03X1142259Y324275I2016J-1165D01*
G01X1142284Y324233D01*
G02Y322659I-1364J-787D01*
G03Y320333I2016J-1163D01*
G01X1142348Y320220D01*
X1144300Y317596D01*
G01X1266162Y496404D02*
X1265490Y495732D01*
X1260185D01*
X1259855Y496062D01*
X1256442D01*
X1252660Y492280D01*
Y487460D01*
X1190177Y424977D01*
X1186612D01*
X1171461Y409826D01*
X1164910D01*
X1158178Y403094D01*
X1155358D01*
X1154749Y402485D01*
Y401376D01*
G02X1153594Y399924I-2645J919D01*
G03X1152424Y398709I1863J-2964D01*
G03Y396383I2016J-1163D01*
G01X1152443Y396349D01*
G02X1151108Y394023I-1383J-752D01*
G01X1150995D01*
G03X1149019Y390575I65J-2327D01*
G01X1149044Y390533D01*
X1149063Y390499D01*
G02X1149044Y388960I-1383J-753D01*
G03X1149019Y386675I2016J-1165D01*
G01X1149044Y386633D01*
X1149063Y386599D01*
G02X1149044Y385060I-1383J-753D01*
G03X1149019Y382775I2016J-1165D01*
G01X1149044Y382733D01*
X1149063Y382699D01*
G02X1149044Y381160I-1383J-753D01*
G03X1149019Y378875I2016J-1165D01*
G01X1149044Y378833D01*
X1149063Y378799D01*
G02X1149044Y377260I-1383J-753D01*
G03X1149019Y374975I2016J-1165D01*
G01X1149044Y374933D01*
G02X1149063Y373394I-1364J-786D01*
G01X1149044Y373360D01*
G03Y371034I2016J-1163D01*
G02Y369460I-1364J-787D01*
G03X1149019Y367175I2016J-1165D01*
G01X1149044Y367133D01*
X1149063Y367099D01*
G02X1147728Y364773I-1383J-752D01*
G01X1147599D01*
G03X1145664Y363610I81J-2326D01*
G02X1144328Y362822I-1364J786D01*
G01X1144205D01*
G03X1142284Y361660I95J-2326D01*
G02X1140968Y360873I-1364J787D01*
G01X1140839D01*
G03X1138904Y359710I81J-2326D01*
G02X1137568Y358922I-1364J786D01*
G01X1137445D01*
G03X1135524Y357760I95J-2326D01*
G02X1134208Y356973I-1364J787D01*
G01X1134079D01*
G03X1132144Y353483I81J-2326D01*
G02X1132163Y351944I-1364J-786D01*
G01X1132144Y351910D01*
X1132119Y351868D01*
G03X1132144Y349583I2041J-1120D01*
G02X1132163Y348044I-1364J-786D01*
G01X1132144Y348010D01*
X1132119Y347968D01*
G03X1132144Y345683I2041J-1120D01*
G02X1132163Y344144I-1364J-786D01*
G01X1132144Y344110D01*
X1132119Y344068D01*
G03X1132144Y341783I2041J-1120D01*
G02X1132163Y340244I-1364J-786D01*
G01X1132144Y340210D01*
X1132119Y340168D01*
G03X1132144Y337883I2041J-1120D01*
G02X1132163Y336344I-1364J-786D01*
G01X1132144Y336310D01*
X1132119Y336268D01*
G03X1132144Y333983I2041J-1120D01*
G02X1132163Y332444I-1364J-786D01*
G01X1132144Y332410D01*
X1132119Y332368D01*
G03X1132144Y330083I2041J-1120D01*
G02X1132163Y328544I-1364J-786D01*
G01X1132144Y328510D01*
X1132119Y328468D01*
G03X1134095Y325020I2041J-1121D01*
G01X1134208D01*
G02X1135524Y324233I-48J-1574D01*
G01X1135590Y324118D01*
X1137540Y321496D01*
G01X1269006Y496016D02*
Y495815D01*
X1267971Y494780D01*
X1259790D01*
X1259460Y495110D01*
X1256960D01*
X1256716Y494866D01*
X1256677D01*
X1255754Y493943D01*
Y493904D01*
X1253690Y491840D01*
Y487143D01*
X1190572Y424025D01*
X1187007D01*
X1172035Y409053D01*
X1165362D01*
X1158553Y402244D01*
Y400690D01*
X1157580Y399717D01*
X1155473D01*
G03X1153076Y398332I0J-2767D01*
G03Y396760I1364J-786D01*
G02X1151104Y393270I-2016J-1163D01*
G01X1151012D01*
G03X1149677Y390944I48J-1574D01*
G01X1149696Y390910D01*
X1149721Y390868D01*
G02X1149696Y388583I-2041J-1120D01*
G03X1149677Y387044I1364J-786D01*
G01X1149696Y387010D01*
X1149721Y386968D01*
G02X1149696Y384683I-2041J-1120D01*
G03X1149677Y383144I1364J-786D01*
G01X1149696Y383110D01*
X1149721Y383068D01*
G02X1149696Y380783I-2041J-1120D01*
G03X1149677Y379244I1364J-786D01*
G01X1149696Y379210D01*
X1149721Y379168D01*
G02X1149696Y376883I-2041J-1120D01*
G03Y375309I1364J-787D01*
G02Y372983I-2016J-1163D01*
G01X1149677Y372949D01*
G03X1149696Y371410I1383J-753D01*
G01X1149721Y371368D01*
G02X1149696Y369083I-2041J-1120D01*
G03X1149677Y367544I1364J-786D01*
G01X1149696Y367510D01*
X1149721Y367468D01*
G02X1147775Y364021I-2041J-1121D01*
G01X1147652D01*
G03X1146316Y363233I28J-1574D01*
G02X1144381Y362070I-2016J1163D01*
G01X1144252D01*
G03X1142936Y361283I48J-1574D01*
G02X1141015Y360121I-2016J1164D01*
G01X1140892D01*
G03X1139556Y359333I28J-1574D01*
G02X1137621Y358170I-2016J1163D01*
G01X1137492D01*
G03X1136176Y357383I48J-1574D01*
G02X1134255Y356221I-2016J1164D01*
G01X1134132D01*
G03X1132796Y353860I28J-1574D01*
G02X1132821Y351575I-2016J-1165D01*
G01X1132796Y351533D01*
X1132777Y351499D01*
G03X1132796Y349960I1383J-753D01*
G02X1132821Y347675I-2016J-1165D01*
G01X1132796Y347633D01*
X1132777Y347599D01*
G03X1132796Y346060I1383J-753D01*
G02X1132821Y343775I-2016J-1165D01*
G01X1132796Y343733D01*
X1132777Y343699D01*
G03X1132796Y342160I1383J-753D01*
G02X1132821Y339875I-2016J-1165D01*
G01X1132796Y339833D01*
X1132777Y339799D01*
G03X1132796Y338260I1383J-753D01*
G02X1132821Y335975I-2016J-1165D01*
G01X1132796Y335933D01*
X1132777Y335899D01*
G03X1132796Y334360I1383J-753D01*
G02X1132821Y332075I-2016J-1165D01*
G01X1132796Y332033D01*
X1132777Y331999D01*
G03X1132796Y330460I1383J-753D01*
G01X1132861Y330349D01*
X1134160Y327347D01*
G01X1137540Y325396D02*
Y323778D01*
X1139163Y322155D01*
Y318489D01*
X1140033Y317619D01*
X1141891D01*
X1143488Y316022D01*
X1144328D01*
G03X1145664Y316810I-28J1574D01*
G02X1149696I2016J-1163D01*
G03X1152424I1364J786D01*
G02X1154359Y317973I2016J-1163D01*
G01X1154488D01*
G03X1155804Y318760I-48J1574D01*
G02X1157725Y319922I2016J-1164D01*
G01X1157848D01*
G03X1159184Y320710I-28J1574D01*
G02X1161119Y321873I2016J-1163D01*
G01X1161281D01*
G02X1163216Y320710I-81J-2326D01*
G03X1165944I1364J786D01*
G02X1167879Y321873I2016J-1163D01*
G01X1168041D01*
G02X1169976Y320710I-81J-2326D01*
G01X1169997Y320673D01*
G03X1172703Y320710I1342J823D01*
G02X1174638Y321873I2016J-1163D01*
G01X1174793D01*
G03X1176083Y322659I-74J1573D01*
G02X1178018Y323822I2016J-1163D01*
G01X1178180D01*
G02X1180115Y322659I-81J-2326D01*
G03X1181405Y321873I1364J787D01*
G01X1181553D01*
G03X1182843Y322659I-74J1573D01*
G02X1184778Y323822I2016J-1163D01*
G01X1184940D01*
G02X1186875Y322659I-81J-2326D01*
G03X1188165Y321873I1364J787D01*
G01X1188320D01*
G02X1190255Y320710I-81J-2326D01*
G03X1191591Y319922I1364J786D01*
G01X1191714D01*
G02X1193635Y318760I-95J-2326D01*
G03X1194951Y317973I1364J787D01*
G01X1196099D01*
X1196472Y317600D01*
X1221412D01*
X1224573Y314439D01*
X1302203D01*
G01X1201013Y213073D02*
X1202412Y211674D01*
X1219855D01*
X1225228Y206301D01*
X1227707D01*
X1231276Y209870D01*
Y219148D01*
X1245047Y232919D01*
X1253690D01*
X1272157Y214452D01*
X1320200D01*
X1320204Y214456D01*
X1328230D01*
X1330074Y216300D01*
Y216500D01*
G01X1202179Y212987D02*
X1221153D01*
X1243919Y235753D01*
X1254611D01*
X1254789Y235575D01*
X1254792D01*
X1270463Y219904D01*
X1374768D01*
X1382511Y212161D01*
X1387863D01*
X1394559Y218857D01*
X1398948D01*
X1400057Y217748D01*
X1411848D01*
X1432600Y238500D01*
X1438029D01*
X1441240Y241711D01*
Y248230D01*
X1443428Y250418D01*
Y252628D01*
X1448500Y257700D01*
G01X1333074Y216500D02*
X1333898Y215676D01*
Y215061D01*
X1332089Y213252D01*
X1271727D01*
X1253212Y231767D01*
X1245842D01*
X1232428Y218353D01*
Y209347D01*
X1228230Y205149D01*
X1225243D01*
X1223546Y203452D01*
X1205465D01*
X1200101Y208816D01*
X1199815D01*
G01X1218868Y214869D02*
X1214576D01*
X1207774Y221671D01*
X1205139D01*
G01X1430365Y262624D02*
X1419710Y251969D01*
X1404134D01*
X1401261Y249096D01*
X1398155D01*
X1396367Y250884D01*
X1320724D01*
X1308675Y262933D01*
X1229323D01*
X1227718Y264538D01*
X1222450D01*
X1216633Y258721D01*
X1208491D01*
G03X1207155Y257933I28J-1574D01*
G02X1203123I-2016J1163D01*
G03X1201787Y258721I-1364J-786D01*
G01X1201664D01*
G02X1199743Y259883I95J2326D01*
G03X1197015I-1364J-787D01*
G02X1192983I-2016J1164D01*
G03X1190255I-1364J-787D01*
G02X1186223I-2016J1164D01*
G03X1184907Y260670I-1364J-787D01*
G01X1184778D01*
G02X1182843Y261833I81J2326D01*
G03X1180115I-1364J-786D01*
G02X1178355Y260682I-2016J1162D01*
G01X1178247Y260670D01*
X1178051D01*
G03X1176409Y260072I0J-2553D01*
G02X1175661Y260104I-357J424D01*
G01X1174719Y261047D01*
G01X1270478Y243490D02*
Y249162D01*
X1265292Y254348D01*
X1232986D01*
X1225659Y247021D01*
X1201731D01*
G03X1200395Y246233I28J-1574D01*
G02X1198460Y245070I-2016J1163D01*
G01X1198298D01*
G02X1196363Y246233I81J2326D01*
G01X1196122Y246651D01*
G03X1195481Y247021I-641J-370D01*
G01X1188211D01*
G03X1186875Y246233I28J-1574D01*
G02X1184940Y245070I-2016J1163D01*
G01X1184778D01*
G02X1182843Y246233I81J2326D01*
G03X1181507Y247021I-1364J-786D01*
G01X1181451D01*
G03X1180115Y246233I28J-1574D01*
G02X1178180Y245070I-2016J1163D01*
G01X1178018D01*
G02X1176083Y246233I81J2326D01*
G03X1174747Y247021I-1364J-786D01*
G01X1174624D01*
G02X1172703Y248183I95J2326D01*
G03X1171387Y248970I-1364J-787D01*
G01X1170430D01*
X1169650Y250322D01*
G03X1168025Y251297I-1690J-975D01*
G01X1167960D01*
X1164580Y251296D01*
G01X1405392Y284022D02*
X1405878Y283536D01*
Y278934D01*
X1388017Y261073D01*
X1324937D01*
X1305842Y280168D01*
G01X1217194D02*
X1213297Y276271D01*
X1211327D01*
X1209433Y274377D01*
X1208651D01*
G03X1207405Y273861I0J-1762D01*
G03X1207155Y273533I1117J-1110D01*
G02X1203123I-2016J1163D01*
G03X1201821Y274320I-1364J-786D01*
G01X1201697D01*
G03X1200395Y273533I62J-1573D01*
G02X1196363I-2016J1163D01*
G03X1195061Y274320I-1364J-786D01*
G01X1194918D01*
G02X1192983Y275483I81J2326D01*
G03X1191667Y276270I-1364J-787D01*
G01X1191538D01*
G02X1189603Y277433I81J2326D01*
G03X1186875I-1364J-787D01*
G02X1182843I-2016J1163D01*
G03X1180115I-1364J-787D01*
G02X1176083I-2016J1163D01*
G03X1173355I-1364J-787D01*
G02X1171420Y276270I-2016J1163D01*
G01X1171339D01*
G03X1169985Y275498I0J-1573D01*
G01X1169976Y275483D01*
G02X1169717Y275120I-2015J1164D01*
G01X1167960Y272747D01*
G01X1171339Y255196D02*
X1173061Y258177D01*
G03X1173029Y260072I-1722J919D01*
G02Y262022I1690J975D01*
G02X1174717Y262997I1688J-974D01*
G01X1174784D01*
G02X1176000Y262519I-65J-1950D01*
G03X1177516Y261538I3335J3491D01*
G03X1178692I588J1446D01*
G03X1179463Y262210I-593J1458D01*
G02X1183495I2016J-1163D01*
G03X1184831Y261422I1364J786D01*
G01X1184954D01*
G02X1186875Y260260I-95J-2326D01*
G03X1189603I1364J787D01*
G02X1193635I2016J-1164D01*
G03X1196363I1364J787D01*
G02X1200395I2016J-1164D01*
G03X1201711Y259473I1364J787D01*
G01X1201840D01*
G02X1203775Y258310I-81J-2326D01*
G03X1206503I1364J786D01*
G02X1208438Y259473I2016J-1163D01*
G01X1215776D01*
X1221930Y265627D01*
X1228781D01*
X1230229Y264179D01*
X1308493D01*
X1321036Y251636D01*
X1396679D01*
X1398467Y249848D01*
X1400949D01*
X1403994Y252893D01*
X1418192D01*
X1429499Y264200D01*
X1431900D01*
X1437800Y258300D01*
G01X1310950Y255650D02*
X1307940Y252640D01*
X1282187D01*
X1278259Y248712D01*
X1272019D01*
X1265231Y255500D01*
X1232964D01*
X1225237Y247773D01*
X1201678D01*
G03X1199743Y246610I81J-2326D01*
G02X1198407Y245822I-1364J786D01*
G01X1198351D01*
G02X1197015Y246610I28J1574D01*
G01X1196604Y247324D01*
G03X1195828Y247773I-776J-446D01*
G01X1188158D01*
G03X1186223Y246610I81J-2326D01*
G02X1184887Y245822I-1364J786D01*
G01X1184831D01*
G02X1183495Y246610I28J1574D01*
G03X1181560Y247773I-2016J-1163D01*
G01X1181398D01*
G03X1179463Y246610I81J-2326D01*
G02X1178127Y245822I-1364J786D01*
G01X1178071D01*
G02X1176735Y246610I28J1574D01*
G03X1174800Y247773I-2016J-1163D01*
G01X1174671D01*
G02X1173355Y248560I48J1574D01*
G03X1171339Y251296I-13203J-7618D01*
G01X1174719Y272747D02*
Y271417D01*
X1174975Y271161D01*
G02X1176735Y270010I-256J-2313D01*
G03X1179463I1364J786D01*
G02X1183495I2016J-1163D01*
G03X1184797Y269223I1364J786D01*
G01X1184921D01*
G03X1186223Y270010I-62J1573D01*
G02X1190255I2016J-1163D01*
G03X1191591Y269222I1364J786D01*
G01X1191714D01*
G02X1193635Y268060I-95J-2326D01*
G03X1194951Y267273I1364J787D01*
G01X1202683D01*
G02X1203775Y266110I-1925J-2901D01*
G03X1205111Y265322I1364J786D01*
G01X1205167D01*
G03X1206503Y266110I-28J1574D01*
G02X1208438Y267273I2016J-1163D01*
G01X1210064D01*
X1214094Y271303D01*
G01X1216362Y273571D02*
X1306172D01*
X1323592Y256151D01*
X1390907D01*
X1399836Y265080D01*
X1412726D01*
X1414691Y267045D01*
X1426905D01*
G01X1234640Y249340D02*
X1258788D01*
X1269484Y238644D01*
X1273414D01*
X1274360Y239590D01*
X1281154D01*
X1283773Y236971D01*
X1310230D01*
X1312228Y238969D01*
Y239428D01*
X1315480Y242680D01*
X1398720D01*
X1402200Y239200D01*
Y230070D01*
X1401565Y229435D01*
G01X1275577Y253123D02*
X1271010D01*
X1267204Y256929D01*
G01X1264794Y257709D02*
X1272157Y250346D01*
X1277499D01*
G01X1174719Y268847D02*
Y267517D01*
X1174975Y267261D01*
G02X1176735Y266110I-256J-2313D01*
G03X1179463I1364J786D01*
G02X1183495Y266111I2016J-1163D01*
G01X1183508Y266088D01*
G03X1186210I1351J810D01*
G01X1186223Y266111D01*
G02X1190255Y266110I2016J-1164D01*
G03X1191591Y265322I1364J786D01*
G01X1191714D01*
G02X1193635Y264160I-95J-2326D01*
G03X1194951Y263373I1364J787D01*
G01X1195047D01*
G03X1196363Y264160I-48J1574D01*
G02X1196733Y264642I2016J-1164D01*
G01X1197414Y265323D01*
X1198444D01*
G02X1200395Y264160I-65J-2327D01*
G03X1201711Y263373I1364J787D01*
G01X1201840D01*
G02X1203775Y262210I-81J-2326D01*
G03X1205111Y261422I1364J786D01*
G01X1206220D01*
X1206963Y262165D01*
X1215130D01*
X1223265Y270300D01*
X1305457D01*
X1322110Y253647D01*
X1398558D01*
X1399852Y252353D01*
G01X1226250Y236940D02*
X1236146Y246836D01*
X1257750D01*
X1268490Y236096D01*
X1274954D01*
X1275154Y236296D01*
G01X1235368Y248088D02*
X1258269D01*
X1268965Y237392D01*
X1273933D01*
X1274445Y237904D01*
X1280574D01*
X1282759Y235719D01*
X1310749D01*
X1313480Y238450D01*
Y238881D01*
X1316027Y241428D01*
X1396567D01*
X1400057Y237938D01*
Y236274D01*
X1400066D01*
G01X1279950Y229338D02*
X1271510D01*
X1257458Y243390D01*
X1237490D01*
X1227911Y233811D01*
G01X1276628Y234270D02*
X1268349D01*
X1257659Y244960D01*
X1236390D01*
G01X1233949Y250770D02*
X1258988D01*
X1269538Y240220D01*
X1272761D01*
G01X1218000Y218100D02*
X1219939D01*
X1220548Y218709D01*
X1221007D01*
X1241507Y239209D01*
X1253177D01*
X1253178Y239210D01*
X1256044D01*
X1256223Y239031D01*
X1256226D01*
X1271367Y223890D01*
X1281330D01*
X1282886Y225446D01*
X1292638D01*
X1293540Y226348D01*
X1297160D01*
X1299997Y223511D01*
X1397011D01*
X1398700Y225200D01*
X1406900D01*
X1423335Y241635D01*
X1438000D01*
X1438983Y242618D01*
Y246967D01*
X1434350Y251600D01*
X1434300D01*
G01X1433057Y257388D02*
X1425802Y250133D01*
X1404426D01*
X1401885Y247592D01*
X1397531D01*
X1395743Y249380D01*
X1320100D01*
X1309380Y260100D01*
X1232162D01*
X1227073Y255011D01*
X1226915D01*
X1226725Y254821D01*
X1221388D01*
X1221387Y254822D01*
G01X1438500Y255400D02*
X1438471D01*
X1433871Y260000D01*
X1430399D01*
X1421554Y251155D01*
X1404384D01*
X1401573Y248344D01*
X1397843D01*
X1396055Y250132D01*
X1320412D01*
X1309292Y261252D01*
X1231684D01*
X1226595Y256163D01*
X1210525D01*
X1209936Y255574D01*
G01X1159390Y262460D02*
X1160130Y263200D01*
X1163368D01*
X1166637Y266469D01*
X1167960Y266897D01*
X1168025D01*
G03X1169650Y267872I-65J1950D01*
G02X1171337Y268846I1687J-974D01*
G01X1171387D01*
G03X1173029Y269822I-48J1950D01*
G02X1174946Y270404I1579J-1751D01*
G02X1176083Y269633I-226J-1558D01*
G03X1180115I2016J1163D01*
G02X1182843I1364J-786D01*
G03X1184753Y268471I2016J1163D01*
G01X1184965D01*
G03X1186875Y269633I-106J2325D01*
G02X1189603I1364J-786D01*
G03X1191538Y268470I2016J1163D01*
G01X1191667D01*
G02X1192983Y267683I-48J-1574D01*
G03X1194904Y266521I2016J1164D01*
G01X1202046D01*
G02X1203123Y265733I-354J-1613D01*
G03X1205058Y264570I2016J1163D01*
G01X1205220D01*
G03X1207155Y265733I-81J2326D01*
G02X1208491Y266521I1364J-786D01*
G01X1210757D01*
X1216336Y272100D01*
X1305651D01*
X1322852Y254899D01*
X1391426D01*
X1402200Y262669D01*
X1424770D01*
X1428600Y266499D01*
Y267929D01*
X1423800Y272729D01*
Y283455D01*
X1433213Y292868D01*
Y304960D01*
X1431113Y315479D01*
Y330941D01*
X1434083Y333911D01*
Y391801D01*
X1463872Y421590D01*
X1465486D01*
X1469019Y425123D01*
X1471922D01*
X1475093Y428294D01*
Y430095D01*
X1475653Y430655D01*
Y481697D01*
X1472250Y485100D01*
G01X1444400Y371600D02*
X1445250Y370750D01*
Y367423D01*
X1443622Y365795D01*
X1443124D01*
X1442384Y366535D01*
X1441886D01*
X1441074Y365723D01*
Y365225D01*
X1441814Y364485D01*
Y363987D01*
X1441002Y363175D01*
X1440504D01*
X1439764Y363915D01*
X1439266D01*
X1438454Y363103D01*
Y362605D01*
X1439194Y361865D01*
Y361367D01*
X1438382Y360555D01*
X1437884D01*
X1437144Y361295D01*
X1436646D01*
X1435834Y360483D01*
Y359985D01*
X1436574Y359245D01*
Y358747D01*
X1435373Y357546D01*
Y333233D01*
X1432365Y330225D01*
Y315605D01*
X1434529Y304772D01*
Y292088D01*
X1425082Y282641D01*
Y273218D01*
X1429900Y268400D01*
Y266000D01*
X1421684Y257784D01*
X1421149D01*
X1420797Y258136D01*
Y261065D01*
X1420445Y261417D01*
X1419297D01*
X1418945Y261065D01*
Y258136D01*
X1418593Y257784D01*
X1417445D01*
X1417093Y258136D01*
Y261065D01*
X1416741Y261417D01*
X1415593D01*
X1415241Y261065D01*
Y258136D01*
X1414889Y257784D01*
X1413741D01*
X1413389Y258136D01*
Y261065D01*
X1413037Y261417D01*
X1411889D01*
X1411537Y261065D01*
Y258136D01*
X1411185Y257784D01*
X1410037D01*
X1409685Y258136D01*
Y261065D01*
X1409333Y261417D01*
X1408185D01*
X1407833Y261065D01*
Y258136D01*
X1407481Y257784D01*
X1406333D01*
X1405981Y258136D01*
Y261065D01*
X1405629Y261417D01*
X1404481D01*
X1404129Y261065D01*
Y258136D01*
X1403777Y257784D01*
X1398004D01*
X1397652Y257432D01*
Y256345D01*
X1398065Y255932D01*
X1416548D01*
X1416900Y255580D01*
Y254432D01*
X1416548Y254080D01*
X1401879D01*
X1401527Y253728D01*
Y251528D01*
X1400599Y250600D01*
X1398779D01*
X1396884Y252495D01*
X1321632D01*
X1308112Y266015D01*
X1304605D01*
X1304253Y266367D01*
Y268772D01*
X1303901Y269124D01*
X1302753D01*
X1302401Y268772D01*
Y266367D01*
X1302049Y266015D01*
X1296750D01*
X1296398Y266367D01*
Y268796D01*
X1296046Y269148D01*
X1294898D01*
X1294546Y268796D01*
Y266367D01*
X1294194Y266015D01*
X1293046D01*
X1292694Y266367D01*
Y268796D01*
X1292342Y269148D01*
X1291194D01*
X1290842Y268796D01*
Y266367D01*
X1290490Y266015D01*
X1289342D01*
X1288990Y266367D01*
Y268796D01*
X1288638Y269148D01*
X1287490D01*
X1287138Y268796D01*
Y266367D01*
X1286786Y266015D01*
X1285638D01*
X1285286Y266367D01*
Y268796D01*
X1284934Y269148D01*
X1283786D01*
X1283434Y268796D01*
Y266367D01*
X1283082Y266015D01*
X1281934D01*
X1281582Y266367D01*
Y268796D01*
X1281230Y269148D01*
X1280082D01*
X1279730Y268796D01*
Y266367D01*
X1279378Y266015D01*
X1278230D01*
X1277878Y266367D01*
Y268796D01*
X1277526Y269148D01*
X1276378D01*
X1276026Y268796D01*
Y266367D01*
X1275674Y266015D01*
X1274526D01*
X1274174Y266367D01*
Y268796D01*
X1273822Y269148D01*
X1272674D01*
X1272322Y268796D01*
Y266367D01*
X1271970Y266015D01*
X1270822D01*
X1270470Y266367D01*
Y268796D01*
X1270118Y269148D01*
X1268970D01*
X1268618Y268796D01*
Y266367D01*
X1268266Y266015D01*
X1267118D01*
X1266766Y266367D01*
Y268796D01*
X1266414Y269148D01*
X1265266D01*
X1264914Y268796D01*
Y266367D01*
X1264562Y266015D01*
X1263414D01*
X1263062Y266367D01*
Y268796D01*
X1262710Y269148D01*
X1261562D01*
X1261210Y268796D01*
Y266367D01*
X1260858Y266015D01*
X1259710D01*
X1259358Y266367D01*
Y268796D01*
X1259006Y269148D01*
X1257858D01*
X1257506Y268796D01*
Y266367D01*
X1257154Y266015D01*
X1256006D01*
X1255654Y266367D01*
Y268796D01*
X1255302Y269148D01*
X1254154D01*
X1253802Y268796D01*
Y266367D01*
X1253450Y266015D01*
X1252302D01*
X1251950Y266367D01*
Y268796D01*
X1251598Y269148D01*
X1250450D01*
X1250098Y268796D01*
Y266367D01*
X1249746Y266015D01*
X1248598D01*
X1248246Y266367D01*
Y268796D01*
X1247894Y269148D01*
X1246746D01*
X1246394Y268796D01*
Y266367D01*
X1246042Y266015D01*
X1244894D01*
X1244542Y266367D01*
Y268796D01*
X1244190Y269148D01*
X1243042D01*
X1242690Y268796D01*
Y266367D01*
X1242338Y266015D01*
X1241190D01*
X1240838Y266367D01*
Y268796D01*
X1240486Y269148D01*
X1239338D01*
X1238986Y268796D01*
Y266367D01*
X1238634Y266015D01*
X1237486D01*
X1237134Y266367D01*
Y268796D01*
X1236782Y269148D01*
X1235634D01*
X1235282Y268796D01*
Y266367D01*
X1234930Y266015D01*
X1233782D01*
X1233430Y266367D01*
Y268796D01*
X1233078Y269148D01*
X1231930D01*
X1231578Y268796D01*
Y266367D01*
X1231226Y266015D01*
X1230286D01*
X1228986Y267315D01*
X1221791D01*
X1215886Y261410D01*
X1207272D01*
X1206532Y260670D01*
X1205058D01*
G02X1203123Y261833I81J2326D01*
G03X1201787Y262621I-1364J-786D01*
G01X1201664D01*
G02X1199743Y263783I95J2326D01*
G01X1199730Y263806D01*
G03X1198379Y264571I-1351J-810D01*
G01X1197726D01*
X1197265Y264110D01*
G03X1197015Y263783I1115J-1112D01*
G02X1195094Y262621I-2016J1164D01*
G01X1194904D01*
G02X1192983Y263783I95J2326D01*
G03X1191667Y264570I-1364J-787D01*
G01X1191538D01*
G02X1189603Y265733I81J2326D01*
G03X1186875Y265734I-1364J-786D01*
G02X1184924Y264571I-2016J1164D01*
G01X1184794D01*
G02X1182843Y265734I65J2327D01*
G03X1180115Y265733I-1364J-787D01*
G02X1176083I-2016J1163D01*
G03X1174946Y266504I-1363J-787D01*
G01X1174829Y266521D01*
X1174691D01*
G03X1173355Y265733I28J-1574D01*
G02X1171342Y264570I-2013J1161D01*
G01X1168337D01*
X1167960Y264947D01*
G01X1208519Y229847D02*
X1228499D01*
X1239113Y240461D01*
X1252658D01*
X1252659Y240462D01*
X1256563D01*
X1256742Y240283D01*
X1256745D01*
X1271378Y225650D01*
X1281319D01*
X1282367Y226698D01*
X1292119D01*
X1293021Y227600D01*
X1297679D01*
X1300516Y224763D01*
X1395315D01*
X1396593Y226041D01*
X1397211D01*
G01X1255118Y-9901D02*
X1256800Y-8219D01*
Y12200D01*
X1255118Y13882D01*
Y16999D01*
G01Y-1743D02*
Y9157D01*
G01X1470950Y252846D02*
X1470700D01*
X1467854Y250000D01*
X1466824D01*
X1464076Y247252D01*
Y243219D01*
X1441853Y220999D01*
X1435098D01*
X1419689Y205590D01*
X1414245D01*
X1405349Y196694D01*
X1293541D01*
X1272241Y175394D01*
X1260942D01*
X1255366Y169818D01*
Y142749D01*
X1261510Y136605D01*
X1265731D01*
X1279381Y122955D01*
Y114464D01*
X1274228Y109311D01*
Y100377D01*
X1273894Y100043D01*
Y98737D01*
X1274432Y98199D01*
Y-8336D01*
X1276346Y-10250D01*
G01X1296935Y51335D02*
Y54465D01*
X1293286Y58114D01*
X1283462D01*
X1276369Y65207D01*
Y97297D01*
X1287800Y108728D01*
Y125000D01*
X1291307Y128507D01*
Y143508D01*
X1302056Y154257D01*
X1306947D01*
X1309986Y157296D01*
X1316753D01*
X1323180Y163723D01*
Y165734D01*
X1324094Y166648D01*
X1393888D01*
X1396551Y163985D01*
X1404307D01*
X1408100Y167778D01*
X1414738D01*
X1439639Y192679D01*
X1445018D01*
X1458517Y206178D01*
Y209803D01*
X1471214Y222500D01*
X1477458D01*
X1479759Y224801D01*
X1479700D01*
G01X1470950Y229669D02*
Y226492D01*
X1451705Y207247D01*
X1446344D01*
X1443719Y204622D01*
X1436117D01*
X1411484Y179989D01*
X1410238D01*
X1410237Y179990D01*
X1314801D01*
X1308797Y173986D01*
X1300022D01*
X1291736Y165700D01*
X1284081D01*
X1268921Y150540D01*
X1266646D01*
G01X1497179Y306372D02*
X1496757Y305950D01*
X1492971D01*
X1491350Y304329D01*
Y297798D01*
X1484927Y291375D01*
Y280301D01*
X1487867Y277361D01*
Y269845D01*
X1486619Y268597D01*
X1485965D01*
X1485104Y267736D01*
Y267104D01*
X1484717Y266717D01*
Y266695D01*
X1483856Y265834D01*
X1483834D01*
X1481000Y263000D01*
Y256359D01*
X1481728Y255631D01*
Y251218D01*
X1479236Y248726D01*
Y242685D01*
X1473706Y237155D01*
X1471883D01*
X1466076Y231348D01*
Y230936D01*
X1460140Y225000D01*
X1458500D01*
X1447309Y213809D01*
X1445951D01*
X1445950Y213808D01*
X1444372D01*
X1444371Y213809D01*
X1441504D01*
X1441503Y213808D01*
X1439925D01*
X1439924Y213809D01*
X1437132D01*
X1412127Y188804D01*
X1294874D01*
X1269824Y163754D01*
Y161595D01*
X1268112Y159883D01*
X1264481D01*
X1259950Y155352D01*
Y144650D01*
G01X1264700Y154800D02*
X1267917Y158017D01*
X1270116D01*
X1273500Y161401D01*
Y163700D01*
X1295100Y185300D01*
X1412900D01*
X1437823Y210223D01*
X1448040D01*
X1459548Y221731D01*
G01X1270350Y98300D02*
X1268450D01*
X1266924Y99826D01*
Y105774D01*
X1274074Y112924D01*
Y125092D01*
X1270956Y128210D01*
X1263774D01*
X1255354Y136630D01*
Y139558D01*
X1250000Y144912D01*
Y168571D01*
X1259079Y177650D01*
X1271305D01*
X1294094Y200439D01*
X1329197D01*
X1329199Y200437D01*
X1331069D01*
X1331070Y200438D01*
X1341220D01*
X1346042Y205260D01*
X1365025D01*
X1367789Y208024D01*
Y209216D01*
G01X1478500Y252000D02*
Y251500D01*
X1477332Y250332D01*
Y243475D01*
X1472916Y239059D01*
X1470002D01*
X1464784Y233841D01*
X1462992D01*
X1444864Y215713D01*
X1436342D01*
X1412009Y191380D01*
X1294611D01*
X1272279Y169048D01*
X1268896D01*
X1258374Y158526D01*
Y143997D01*
X1260246Y142125D01*
X1264271D01*
X1265828Y140568D01*
G01X1466404Y245350D02*
Y243419D01*
X1442315Y219331D01*
X1435558D01*
X1420313Y204086D01*
X1414869D01*
X1405972Y195189D01*
X1294164D01*
X1272865Y173890D01*
X1261566D01*
X1256870Y169194D01*
Y143373D01*
X1262032Y138211D01*
X1274514D01*
X1279576Y143273D01*
Y146964D01*
X1278030Y148510D01*
G01X1261546Y150584D02*
X1264186Y153224D01*
X1265353D01*
X1269183Y157054D01*
X1270836D01*
X1271012Y157230D01*
X1272226D01*
X1282812Y167816D01*
X1291158D01*
X1299233Y175891D01*
X1300187D01*
X1300188Y175890D01*
X1308007D01*
X1314012Y181895D01*
X1314966D01*
X1314967Y181894D01*
X1410695D01*
X1435725Y206924D01*
X1439653D01*
X1441880Y209151D01*
X1450725D01*
X1461124Y219550D01*
Y222353D01*
X1468448Y229677D01*
Y230460D01*
X1472832Y234844D01*
X1474244D01*
X1474251Y234851D01*
X1478080D01*
X1481810Y238581D01*
Y246710D01*
X1482400Y247300D01*
Y248000D01*
G01X1447999Y205645D02*
X1447079D01*
X1444700Y203266D01*
X1435825D01*
X1411796Y179237D01*
X1409926D01*
X1409925Y179238D01*
X1315113D01*
X1309109Y173234D01*
X1300334D01*
X1291600Y164500D01*
X1283945D01*
X1268183Y148738D01*
X1265992D01*
X1264146Y150584D01*
G01X1277600Y106200D02*
X1280885Y109485D01*
Y124294D01*
X1282499Y125908D01*
Y128061D01*
X1281999Y128561D01*
Y137728D01*
X1283510Y139239D01*
Y154894D01*
X1286916Y158300D01*
X1290143D01*
X1292411Y156032D01*
X1305387D01*
X1308155Y158800D01*
X1316129D01*
X1321676Y164347D01*
Y166358D01*
X1323618Y168300D01*
X1398271D01*
X1398501Y168530D01*
X1414426D01*
X1439327Y193431D01*
X1444705D01*
X1446983Y195709D01*
X1446984D01*
X1447907Y196632D01*
Y196633D01*
X1457765Y206491D01*
Y210115D01*
X1471720Y224070D01*
X1473993D01*
X1487735Y237812D01*
Y244265D01*
X1487500Y244500D01*
G01X1344462Y209272D02*
X1339036Y203846D01*
X1330612D01*
X1330611Y203847D01*
X1288984D01*
X1270409Y185272D01*
X1266744D01*
X1263242Y181770D01*
X1254213D01*
X1249720Y177277D01*
Y174697D01*
X1249990Y174427D01*
Y171873D01*
X1247269Y169152D01*
Y140622D01*
X1247268Y140621D01*
Y139999D01*
X1248799Y138468D01*
X1250868D01*
X1263067Y126269D01*
Y121574D01*
X1265221Y119420D01*
X1266944D01*
X1268576Y117788D01*
G01X1262569Y147201D02*
X1265420Y144350D01*
X1268429D01*
X1270001Y142778D01*
Y141472D01*
X1267492Y138963D01*
X1262344D01*
X1257622Y143685D01*
Y164543D01*
X1260776Y167697D01*
Y170042D01*
X1263872Y173138D01*
X1273177D01*
X1294476Y194437D01*
X1406284D01*
X1415181Y203334D01*
X1420625D01*
X1435870Y218579D01*
X1442708D01*
X1467324Y243193D01*
Y243753D01*
X1468247Y244676D01*
X1469993D01*
X1471604Y246287D01*
G01X1243948Y154916D02*
X1243511Y155353D01*
Y167483D01*
X1239805Y171189D01*
Y176064D01*
X1249718Y185977D01*
X1263193D01*
X1284071Y206855D01*
X1335055D01*
X1336316Y208116D01*
Y211098D01*
X1340522Y215304D01*
X1371260D01*
X1377871Y208693D01*
X1397754D01*
X1401203Y212142D01*
X1413890D01*
X1421449Y219701D01*
X1424978D01*
X1431605Y226328D01*
X1437979D01*
X1454496Y242845D01*
Y249266D01*
X1457176Y251946D01*
Y255487D01*
X1462046Y260357D01*
X1467040D01*
G01X1483457Y244568D02*
Y239045D01*
X1478504Y234092D01*
X1473144D01*
X1469200Y230148D01*
Y228983D01*
X1464835Y224618D01*
Y221536D01*
X1451298Y207999D01*
X1442358D01*
X1440131Y205772D01*
X1436203D01*
X1411172Y180741D01*
X1410550D01*
X1410549Y180742D01*
X1314489D01*
X1308485Y174738D01*
X1299710D01*
X1291636Y166664D01*
X1283290D01*
X1272704Y156078D01*
X1271490D01*
X1269810Y154398D01*
G01X1469004Y246287D02*
X1467941Y247350D01*
X1465840D01*
X1464828Y246338D01*
Y242907D01*
X1442166Y220247D01*
X1435410D01*
X1420001Y204838D01*
X1414557D01*
X1405661Y195942D01*
X1293853D01*
X1272553Y174642D01*
X1261254D01*
X1256118Y169506D01*
Y143061D01*
X1261822Y137357D01*
X1266043D01*
X1280133Y123267D01*
Y114152D01*
X1275470Y109489D01*
Y99390D01*
G01X1461348Y244350D02*
Y242619D01*
X1441292Y222568D01*
X1439057D01*
X1439055Y222566D01*
X1437185D01*
X1437184Y222567D01*
X1436562D01*
X1436561Y222568D01*
X1434027D01*
X1418553Y207094D01*
X1412804D01*
X1404708Y198998D01*
X1293717D01*
X1271617Y176898D01*
X1259998D01*
X1252000Y168900D01*
Y145300D01*
G01X1408247Y206270D02*
Y204508D01*
X1403489Y199750D01*
X1380081D01*
X1369039Y210792D01*
X1366923D01*
X1362143Y206012D01*
X1345730D01*
X1340908Y201190D01*
X1329510D01*
X1329509Y201191D01*
X1293782D01*
X1272856Y180265D01*
X1254836D01*
X1251224Y176653D01*
Y175321D01*
X1251494Y175051D01*
Y171249D01*
X1249154Y168909D01*
Y142886D01*
X1251657Y140383D01*
X1252246D01*
X1252437Y140192D01*
G01X1227200Y215543D02*
Y216702D01*
X1244569Y234071D01*
X1254168D01*
X1269839Y218400D01*
X1374144D01*
X1381887Y210657D01*
X1388589D01*
X1395285Y217353D01*
X1397988D01*
X1399097Y216244D01*
X1414544D01*
X1430700Y232400D01*
X1440400D01*
X1448600Y240600D01*
Y248671D01*
X1453776Y253847D01*
Y255231D01*
X1461165Y262620D01*
X1461399D01*
X1463284Y264505D01*
Y266174D01*
X1468074Y270964D01*
Y315093D01*
X1473231Y320250D01*
G01X1267800Y161800D02*
Y163576D01*
X1272520Y168296D01*
X1272591D01*
X1294395Y190100D01*
X1411793D01*
X1436654Y214961D01*
X1440402D01*
X1440403Y214960D01*
X1441025D01*
X1441026Y214961D01*
X1445329D01*
X1463346Y232976D01*
X1464983D01*
X1470314Y238307D01*
X1473228D01*
X1478084Y243163D01*
Y249355D01*
X1480576Y251847D01*
Y255153D01*
X1479847Y255882D01*
Y264974D01*
X1481568Y266695D01*
Y267704D01*
X1482638Y268774D01*
X1483646D01*
X1484717Y269845D01*
Y277362D01*
X1483856Y278223D01*
X1482847D01*
X1478628Y282442D01*
Y286811D01*
X1479489Y287672D01*
X1480498D01*
X1481568Y288742D01*
Y297328D01*
X1480098Y298798D01*
G01X1271400Y161900D02*
Y163524D01*
X1295128Y187252D01*
X1412205D01*
X1437508Y212555D01*
X1448055D01*
X1459000Y223500D01*
X1460270D01*
X1467229Y230459D01*
Y230871D01*
X1472354Y235996D01*
X1472667D01*
X1472674Y236003D01*
X1474184D01*
X1480389Y242208D01*
Y243162D01*
X1480388Y243163D01*
Y248248D01*
X1482880Y250740D01*
Y256109D01*
X1482424Y256565D01*
Y260148D01*
X1489945Y267669D01*
Y268774D01*
X1491016Y269845D01*
Y271114D01*
X1489600Y272530D01*
Y277769D01*
X1488076Y279293D01*
Y292473D01*
X1493400Y297797D01*
Y300800D01*
G01X1402400Y223600D02*
X1400007Y221207D01*
X1284916D01*
X1284851Y221142D01*
X1282589D01*
X1282524Y221207D01*
X1270790D01*
X1255270Y236727D01*
X1255267D01*
X1255088Y236906D01*
X1254134D01*
X1254133Y236905D01*
X1243441D01*
X1221405Y214869D01*
X1218868D01*
G01X1399600Y223600D02*
X1398359Y222359D01*
X1284438D01*
X1284373Y222294D01*
X1283067D01*
X1283002Y222359D01*
X1271268D01*
X1255748Y237879D01*
X1255745D01*
X1255566Y238058D01*
X1253656D01*
X1253655Y238057D01*
X1242051D01*
X1220702Y216708D01*
G01X1329324Y208951D02*
X1327980Y207607D01*
X1283377D01*
X1263799Y188029D01*
X1250140D01*
X1238653Y176542D01*
Y163556D01*
X1240309Y161900D01*
G01X1267050Y169800D02*
X1271967D01*
X1294300Y192133D01*
X1406674D01*
X1416371Y201830D01*
X1421249D01*
X1436231Y216812D01*
X1443073D01*
X1466089Y239826D01*
X1472619D01*
X1476580Y243787D01*
Y252920D01*
X1475672Y253828D01*
Y257359D01*
X1475130Y257901D01*
Y261699D01*
X1472119Y264710D01*
Y303628D01*
X1470649Y305098D01*
G01X1241381Y172040D02*
X1241224Y172197D01*
Y175853D01*
X1250098Y184727D01*
X1263007D01*
X1284383Y206103D01*
X1338003D01*
X1341348Y209448D01*
Y212715D01*
X1343185Y214552D01*
X1370948D01*
X1377560Y207940D01*
X1398065D01*
X1401306Y211181D01*
X1415689D01*
X1422196Y217688D01*
Y218052D01*
G01X1444850Y242730D02*
X1439720Y237600D01*
X1434836D01*
X1414232Y216996D01*
X1399745D01*
X1398636Y218105D01*
X1394967D01*
X1388271Y211409D01*
X1382199D01*
X1374456Y219152D01*
X1270151D01*
X1254480Y234823D01*
X1244235D01*
X1225063Y215651D01*
Y209708D01*
X1226867Y207904D01*
G01X1474096Y256706D02*
X1472600Y255210D01*
Y248660D01*
X1473180Y248080D01*
Y244449D01*
X1473876Y243753D01*
Y242147D01*
X1472518Y240789D01*
X1465988D01*
X1442761Y217564D01*
X1435919D01*
X1420937Y202582D01*
X1416059D01*
X1406762Y193285D01*
X1294388D01*
X1273489Y172386D01*
X1264184D01*
X1263300Y171502D01*
Y169450D01*
G01X1433700Y254200D02*
X1428129Y248629D01*
X1405050D01*
X1402508Y246087D01*
X1401886D01*
X1401885Y246088D01*
X1396907D01*
X1395119Y247876D01*
X1317660D01*
X1315873Y249663D01*
X1281454D01*
X1279393Y247602D01*
G01X1275577Y253123D02*
X1276247D01*
X1281174Y258050D01*
X1306385D01*
X1306585Y258250D01*
G01X1308200Y255800D02*
X1282958D01*
X1277509Y250351D01*
X1277499D01*
Y250346D01*
G01D02*
X1277504D01*
G01X1388518Y230789D02*
X1387616Y229887D01*
X1302913D01*
X1299900Y232900D01*
X1290558D01*
X1289875Y232217D01*
X1284115D01*
X1280036Y236296D01*
X1275154D01*
G01X1398600Y228700D02*
X1398251Y229049D01*
X1393788D01*
X1392073Y227333D01*
X1301488D01*
X1298717Y230104D01*
X1291983D01*
X1291217Y229338D01*
X1279950D01*
G01X1399978Y233775D02*
X1400100Y233653D01*
Y232306D01*
X1398095Y230301D01*
X1393159D01*
X1391443Y228585D01*
X1302007D01*
X1299236Y231356D01*
X1291464D01*
X1290920Y230812D01*
X1283375D01*
X1279917Y234270D01*
X1276628D01*
G01X1272761Y240220D02*
X1273881Y241340D01*
X1281034D01*
X1284250Y238124D01*
X1309625D01*
X1311076Y239575D01*
Y239906D01*
X1315002Y243832D01*
X1406010D01*
X1407274Y245096D01*
Y245652D01*
G01X1249230Y402022D02*
X1249508Y402300D01*
X1265500D01*
X1273150Y409950D01*
X1287450D01*
X1298104Y420604D01*
X1316024D01*
X1316820Y421400D01*
G01X1319320Y418900D02*
X1317618Y417198D01*
X1299512D01*
X1288860Y406546D01*
X1274560D01*
X1266712Y398698D01*
X1247005D01*
X1246714Y398407D01*
X1246657D01*
X1246589Y398339D01*
X1243399D01*
G01X1316820Y418900D02*
X1298807D01*
X1288155Y408248D01*
X1273855D01*
X1266007Y400400D01*
X1246300D01*
X1246010Y400110D01*
G01X1255120Y574834D02*
X1253544Y576410D01*
Y611058D01*
X1255120Y612634D01*
G01X1299369Y-15680D02*
X1299470Y-15579D01*
X1303801D01*
X1305124Y-16902D01*
Y-17453D01*
X1306547Y-18876D01*
X1327724D01*
X1331000Y-15600D01*
Y40908D01*
X1340148Y50056D01*
X1365640D01*
X1376032Y60448D01*
Y72868D01*
X1373700Y75200D01*
Y84137D01*
X1374751Y85188D01*
X1378993D01*
X1387905Y94100D01*
X1397080D01*
X1402050Y99070D01*
Y110981D01*
X1398331Y114700D01*
X1397400D01*
X1396200Y115900D01*
Y118500D01*
X1396780Y119080D01*
G01X1496812Y273718D02*
Y272536D01*
X1498252Y271096D01*
Y266744D01*
X1495260Y263752D01*
X1491558D01*
X1488532Y260726D01*
Y250844D01*
X1493276Y246100D01*
Y240361D01*
X1490815Y237900D01*
Y233830D01*
X1487894Y230909D01*
Y223545D01*
X1483372Y219023D01*
X1471993D01*
X1461525Y208555D01*
Y204930D01*
X1446266Y189671D01*
X1441545D01*
X1405174Y153300D01*
X1396264D01*
X1391259Y158305D01*
X1323877D01*
X1319472Y153900D01*
X1316229D01*
X1310753Y148424D01*
X1307095D01*
X1302385Y143714D01*
Y132289D01*
X1295996Y125900D01*
Y110970D01*
X1280577Y95551D01*
Y66953D01*
X1285020Y62510D01*
X1293890D01*
X1300982Y55418D01*
Y44308D01*
X1299347Y42673D01*
Y40288D01*
X1298869Y39810D01*
X1284611D01*
X1280474Y35675D01*
Y8353D01*
X1287327Y1500D01*
X1292200D01*
X1292692Y1008D01*
G01X1837900Y9700D02*
X1837000Y8800D01*
X1833500D01*
X1830500Y5800D01*
X1828696D01*
X1827248Y4352D01*
Y448D01*
X1825250Y-1550D01*
X1823350D01*
X1821276Y524D01*
X1819147D01*
X1817393Y2278D01*
Y3730D01*
X1815355Y5768D01*
X1813777D01*
X1813776Y5767D01*
X1811373D01*
X1809678Y4072D01*
X1775870D01*
X1765132Y14810D01*
X1760913D01*
X1760912Y14811D01*
X1735584D01*
X1733291Y17104D01*
X1673090D01*
X1671290Y18904D01*
X1646095D01*
X1641048Y23951D01*
X1631497D01*
X1628550Y21004D01*
X1596760D01*
X1595157Y22607D01*
Y25425D01*
X1589995Y30587D01*
X1589373D01*
X1589372Y30586D01*
X1558974D01*
X1547537Y42023D01*
X1489721D01*
X1479252Y31554D01*
X1469261D01*
X1466746Y34069D01*
Y44002D01*
X1433122Y77626D01*
Y109158D01*
X1399972Y142308D01*
X1329773D01*
X1328755Y141290D01*
X1324508D01*
X1305892Y122674D01*
Y84879D01*
X1309976Y80795D01*
Y47771D01*
X1301604Y39399D01*
Y23648D01*
X1295240Y17284D01*
Y-9031D01*
X1287700Y-16571D01*
Y-16700D01*
G01X1545572Y38188D02*
X1544316Y36932D01*
X1540850D01*
X1540275Y37507D01*
X1488773D01*
X1481316Y30050D01*
X1468637D01*
X1464670Y34017D01*
Y39360D01*
X1431218Y72812D01*
Y108822D01*
X1399236Y140804D01*
X1330397D01*
X1329379Y139786D01*
X1325132D01*
X1307396Y122050D01*
Y92275D01*
X1316647Y83024D01*
X1320323D01*
X1322055Y84756D01*
X1329044D01*
X1330300Y83500D01*
G01X1327168Y61483D02*
X1329328Y63643D01*
Y77636D01*
X1336554Y84862D01*
X1345730D01*
X1347500Y83092D01*
Y83000D01*
G01X1514067Y315626D02*
X1513500Y315059D01*
Y299630D01*
X1517153Y295977D01*
Y295023D01*
X1517152Y295022D01*
Y291716D01*
X1514095Y288659D01*
Y287341D01*
X1509121Y282367D01*
Y278793D01*
X1509879Y278035D01*
Y277081D01*
X1509878Y277080D01*
Y267652D01*
X1502096Y259870D01*
Y255842D01*
X1502097Y255841D01*
Y254887D01*
X1500416Y253206D01*
X1498657D01*
X1498451Y253000D01*
X1497701Y252170D01*
X1496992Y251461D01*
Y248877D01*
X1496984Y248869D01*
X1499988Y245865D01*
Y245814D01*
X1500002Y245800D01*
X1500015D01*
Y238294D01*
X1502601Y235708D01*
Y231312D01*
X1502602Y231311D01*
Y230357D01*
X1500690Y228445D01*
X1498516D01*
X1494382Y224311D01*
Y216289D01*
X1490497Y212404D01*
X1475438D01*
X1469888Y206854D01*
Y201169D01*
X1457497Y188778D01*
X1453758D01*
X1443332Y178352D01*
X1438375D01*
X1405780Y145757D01*
X1395615D01*
X1389452Y151920D01*
X1324520D01*
X1322696Y150096D01*
X1317745D01*
X1313180Y145531D01*
Y143723D01*
X1309713Y140256D01*
Y131186D01*
X1307942Y129415D01*
X1304614D01*
X1300228Y125029D01*
Y108400D01*
X1304248Y104380D01*
Y88727D01*
X1298754Y83233D01*
G01X1509500Y31900D02*
Y28300D01*
X1506808Y25608D01*
X1465264D01*
X1456650Y34222D01*
Y39187D01*
X1425174Y70663D01*
Y107904D01*
X1425175Y107905D01*
Y108859D01*
X1397462Y136572D01*
X1333642D01*
X1328148Y131078D01*
X1324369D01*
X1312297Y119006D01*
Y94698D01*
X1311551Y93952D01*
G01X1311559Y91431D02*
X1313500Y93372D01*
Y118579D01*
X1324846Y129925D01*
X1328625D01*
X1334120Y135420D01*
X1396984D01*
X1424022Y108382D01*
Y70185D01*
X1455498Y38709D01*
Y33744D01*
X1464934Y24308D01*
X1508242D01*
X1512924Y19626D01*
X1537617D01*
X1543739Y25748D01*
X1546100D01*
X1547600Y24248D01*
Y20900D01*
X1549400Y19100D01*
X1634959D01*
X1637482Y21623D01*
G01X1309700Y83300D02*
X1306644Y86356D01*
Y122362D01*
X1324820Y140538D01*
X1329067D01*
X1330085Y141556D01*
X1399594D01*
X1431971Y109179D01*
Y77713D01*
X1465979Y43705D01*
Y33772D01*
X1468949Y30802D01*
X1480438D01*
X1490907Y41271D01*
X1547225D01*
X1558662Y29834D01*
X1589684D01*
X1594405Y25113D01*
Y22295D01*
X1596448Y20252D01*
X1630153D01*
X1633100Y23199D01*
X1640601D01*
X1645648Y18152D01*
X1670978D01*
X1672778Y16352D01*
X1732979D01*
X1735272Y14059D01*
X1760600D01*
X1760601Y14058D01*
X1764820D01*
X1775558Y3320D01*
X1809990D01*
X1811685Y5015D01*
X1814088D01*
X1814089Y5016D01*
X1815043D01*
X1816641Y3418D01*
Y1966D01*
X1818835Y-228D01*
X1820799D01*
X1823185Y-2614D01*
X1826798D01*
X1830800Y1388D01*
Y5000D01*
X1833700Y7900D01*
X1844100D01*
X1847300Y11100D01*
X1849752D01*
X1850594Y11942D01*
X1857216D01*
X1865306Y20032D01*
X1865853D01*
X1867126Y21305D01*
Y22695D01*
X1866113Y23708D01*
Y32593D01*
X1871398Y37878D01*
Y43896D01*
X1866552Y48742D01*
Y70938D01*
X1869127Y73513D01*
Y98848D01*
X1867170Y100805D01*
Y100806D01*
X1866874Y101102D01*
Y108006D01*
X1872922Y114054D01*
Y131995D01*
X1875680Y134753D01*
Y148319D01*
X1873849Y150150D01*
Y156924D01*
X1874187Y157262D01*
Y171913D01*
X1871830Y174270D01*
Y183159D01*
X1878596Y189925D01*
Y201116D01*
X1883800Y206320D01*
Y210575D01*
G01X1308983Y93814D02*
Y94504D01*
X1311145Y96666D01*
Y123671D01*
X1325395Y137921D01*
X1329642D01*
X1330949Y139228D01*
X1398564D01*
X1429066Y108726D01*
Y71987D01*
X1462563Y38490D01*
Y33996D01*
X1468013Y28546D01*
X1489446D01*
X1496903Y36003D01*
X1539172D01*
X1540931Y34244D01*
X1551558D01*
X1557872Y27930D01*
X1589089D01*
X1590648Y26371D01*
Y25553D01*
X1589623Y24528D01*
G01X1301219Y89141D02*
Y97602D01*
X1303496Y99879D01*
Y103833D01*
X1299476Y107853D01*
Y125341D01*
X1304303Y130168D01*
X1307631D01*
X1308931Y131468D01*
Y140538D01*
X1312428Y144035D01*
Y145843D01*
X1317433Y150848D01*
X1322384D01*
X1324208Y152672D01*
X1389917D01*
X1396080Y146509D01*
X1405468D01*
X1443326Y184367D01*
X1448126D01*
X1469136Y205377D01*
Y207166D01*
X1475126Y213156D01*
X1490185D01*
X1493628Y216599D01*
Y218947D01*
X1491438Y221137D01*
G01X1308400Y79600D02*
X1305000Y83000D01*
Y123291D01*
X1312017Y130308D01*
Y137716D01*
X1317912Y143611D01*
Y144990D01*
X1319498Y146576D01*
X1385753D01*
X1388499Y143830D01*
X1411689D01*
X1452712Y184853D01*
X1459157D01*
X1460524Y186220D01*
Y188778D01*
X1473165Y201419D01*
Y203850D01*
X1477035Y207720D01*
Y210777D01*
X1477910Y211652D01*
X1490809D01*
X1495134Y215977D01*
Y223999D01*
X1498828Y227693D01*
X1501002D01*
X1503354Y230045D01*
Y231623D01*
X1503353Y231624D01*
Y236020D01*
X1500800Y238573D01*
Y246600D01*
X1497896Y249504D01*
Y251023D01*
X1498819Y251946D01*
X1500245D01*
X1502848Y254549D01*
Y254574D01*
X1502849Y254575D01*
Y256153D01*
X1502848Y256154D01*
Y259558D01*
X1510630Y267340D01*
Y276768D01*
X1510631Y276769D01*
Y278347D01*
X1509873Y279105D01*
Y282055D01*
X1514847Y287029D01*
Y288347D01*
X1517904Y291404D01*
Y294710D01*
X1517906Y294712D01*
Y295334D01*
X1517905Y295335D01*
Y296289D01*
X1514421Y299773D01*
Y311364D01*
X1516301Y313244D01*
G01X1508455Y313041D02*
X1510268Y311228D01*
Y301680D01*
X1509074Y300486D01*
Y290514D01*
X1510324Y289264D01*
Y285518D01*
X1507969Y283163D01*
Y278315D01*
X1508726Y277558D01*
Y268130D01*
X1500944Y260348D01*
Y255364D01*
X1499938Y254358D01*
X1498179D01*
X1495836Y252015D01*
Y251179D01*
X1495838Y251176D01*
X1495836Y250582D01*
Y250142D01*
X1495835Y250141D01*
X1495830Y248685D01*
Y248393D01*
X1498836Y245387D01*
Y245336D01*
X1498863Y245309D01*
Y244273D01*
X1498862Y244272D01*
Y237817D01*
X1501449Y235230D01*
Y230834D01*
X1500212Y229597D01*
X1498906D01*
X1498899Y229604D01*
X1498311D01*
X1498304Y229597D01*
X1497138D01*
X1489596Y222055D01*
Y214891D01*
X1488671Y213966D01*
X1483201D01*
X1483200Y213965D01*
X1482578D01*
X1482577Y213966D01*
X1474872D01*
X1468384Y207478D01*
Y205689D01*
X1447817Y185122D01*
X1443017D01*
X1405156Y147261D01*
X1397026D01*
X1396511Y147602D01*
X1390688Y153424D01*
X1323896D01*
X1322072Y151600D01*
X1317121D01*
X1311676Y146155D01*
Y144347D01*
X1306900Y139571D01*
Y131744D01*
G01X1301900Y124400D02*
X1304557D01*
X1310865Y130708D01*
Y137865D01*
X1317159Y144159D01*
Y145301D01*
X1319186Y147328D01*
X1386500D01*
X1389223Y144605D01*
X1406913D01*
X1439508Y177200D01*
X1443900D01*
X1454326Y187626D01*
X1458835D01*
X1458908Y187699D01*
G01X1326026Y133323D02*
X1329120Y136417D01*
X1330266D01*
X1331573Y137724D01*
X1397940D01*
X1426785Y108879D01*
Y71068D01*
X1457802Y40051D01*
Y34700D01*
X1465460Y27042D01*
X1496169D01*
X1502885Y33758D01*
X1537037D01*
X1538713Y32082D01*
X1543608D01*
X1551834Y23856D01*
G01X1323026Y133323D02*
X1326872Y137169D01*
X1329954D01*
X1331261Y138476D01*
X1398252D01*
X1427737Y108991D01*
Y71463D01*
X1458754Y40446D01*
Y34812D01*
X1465772Y27794D01*
X1495574D01*
X1502290Y34510D01*
X1537632D01*
X1539308Y32834D01*
X1545456D01*
X1554434Y23856D01*
G01X1592829Y24460D02*
X1592363D01*
X1591400Y25423D01*
Y26683D01*
X1589401Y28682D01*
X1558184D01*
X1551670Y35196D01*
X1541326D01*
X1539767Y36755D01*
X1496308D01*
X1488851Y29298D01*
X1468325D01*
X1463515Y34108D01*
Y38885D01*
X1430019Y72381D01*
Y108837D01*
X1398876Y139980D01*
X1330637D01*
X1329330Y138673D01*
X1325083D01*
X1310393Y123983D01*
Y97095D01*
X1310040Y96742D01*
X1308972D01*
G01X1327900Y142918D02*
X1328042Y143060D01*
X1411545D01*
X1415855Y138750D01*
X1451590D01*
G01X1301770Y101300D02*
Y104495D01*
X1298724Y107541D01*
Y125653D01*
X1304329Y131258D01*
Y142006D01*
X1309243Y146920D01*
X1310753D01*
X1310754Y146919D01*
X1311376D01*
X1316853Y152396D01*
X1320096D01*
X1324500Y156800D01*
X1390200D01*
X1398987Y148013D01*
X1404844D01*
X1442705Y185874D01*
X1447505D01*
X1467543Y205912D01*
Y207823D01*
X1474374Y214654D01*
X1474496D01*
X1474560Y214718D01*
X1481195D01*
X1489398Y222921D01*
Y224625D01*
X1491265Y226492D01*
G01X1402020Y165561D02*
X1401783Y165324D01*
X1396276D01*
X1394200Y167400D01*
X1323782D01*
X1322428Y166046D01*
Y164035D01*
X1316441Y158048D01*
X1308950D01*
X1306182Y155280D01*
X1292099D01*
X1290804Y156575D01*
X1287790D01*
G01X1281799Y193190D02*
X1291304Y202695D01*
X1330133D01*
X1330134Y202694D01*
X1340284D01*
X1346123Y208533D01*
Y209706D01*
X1348713Y212296D01*
X1370012D01*
X1380748Y201560D01*
X1402598D01*
X1405825Y204787D01*
Y207141D01*
X1407282Y208598D01*
X1417679D01*
X1433153Y224072D01*
X1437185D01*
X1437186Y224071D01*
X1437808D01*
X1437809Y224070D01*
X1438431D01*
X1438433Y224072D01*
X1438915D01*
X1456092Y241249D01*
X1456093D01*
X1457844Y243000D01*
X1458318D01*
G01X1496600Y281400D02*
X1494491Y279291D01*
Y272755D01*
X1494534Y272712D01*
Y266776D01*
X1493023Y265265D01*
X1490943D01*
X1487028Y261350D01*
Y250464D01*
X1485062Y248498D01*
Y246256D01*
X1485785Y245533D01*
Y237396D01*
X1473211Y224822D01*
X1471408D01*
X1457013Y210427D01*
Y207259D01*
X1449831Y200077D01*
X1435330D01*
X1412586Y177333D01*
X1409136D01*
X1409135Y177334D01*
X1316453D01*
X1308691Y169572D01*
Y168287D01*
X1305171Y164767D01*
G01X1489546Y286202D02*
X1491082Y284666D01*
Y272111D01*
X1492009Y271184D01*
Y269059D01*
X1490973Y268023D01*
Y266359D01*
X1486276Y261662D01*
Y251076D01*
X1484310Y249110D01*
Y245944D01*
X1485033Y245221D01*
Y243915D01*
X1484310Y243192D01*
Y236985D01*
X1472900Y225575D01*
X1471097D01*
X1451333Y205811D01*
X1450671D01*
X1446360Y201500D01*
X1435689D01*
X1412274Y178085D01*
X1409448D01*
X1409447Y178086D01*
X1316141D01*
X1307939Y169884D01*
Y169275D01*
X1305007Y166343D01*
X1304518D01*
X1303595Y165420D01*
Y164114D01*
X1304518Y163191D01*
X1308017D01*
X1310061Y165235D01*
G01X1310950Y255650D02*
X1317972Y248628D01*
X1395431D01*
X1397219Y246840D01*
X1402197D01*
X1404738Y249381D01*
X1426582D01*
X1433001Y255800D01*
X1435200D01*
X1437900Y253100D01*
X1439700D01*
G01X1321172Y464474D02*
Y461238D01*
X1322349Y460061D01*
X1332055D01*
X1338751Y466757D01*
X1360418D01*
X1360971Y467310D01*
X1446807D01*
X1457676Y478179D01*
X1460721D01*
X1465313Y482771D01*
Y495380D01*
X1469790Y499857D01*
X1473976D01*
X1475402Y501283D01*
X1490583D01*
X1491255Y500611D01*
X1512133D01*
X1513948Y502426D01*
Y505370D01*
X1515820Y507242D01*
Y509474D01*
X1536918Y530572D01*
X1570463D01*
X1573386Y527649D01*
X1579225D01*
X1593008Y513872D01*
X1609360D01*
X1616064Y520576D01*
X1625573D01*
X1625831Y520318D01*
X1627407D01*
G01X1288671Y445338D02*
X1297585Y454252D01*
X1310387D01*
X1311735Y455600D01*
Y472134D01*
X1318675Y479074D01*
X1318883D01*
X1319121Y479312D01*
X1351721D01*
X1355940Y475093D01*
X1443113D01*
X1443899Y475879D01*
Y476869D01*
X1443917Y476887D01*
Y478359D01*
X1443899Y478377D01*
Y483446D01*
X1442385Y484960D01*
Y487073D01*
X1442759Y487447D01*
X1442777D01*
X1443817Y488487D01*
Y488505D01*
X1443899Y488587D01*
Y491199D01*
X1451260Y498560D01*
X1454427D01*
X1463096Y507229D01*
X1467273D01*
X1473544Y513500D01*
X1488818D01*
X1496084Y520766D01*
X1504516D01*
X1507656Y523906D01*
X1516433D01*
X1531987Y539460D01*
X1574494D01*
X1578593Y535361D01*
X1590990D01*
X1593992Y538363D01*
X1602608D01*
X1613371Y533718D01*
X1623107D01*
X1623946Y534557D01*
X1632037D01*
X1632912Y535432D01*
X1640554D01*
X1641429Y534557D01*
X1645366D01*
X1654718Y525205D01*
Y521923D01*
X1670309Y506332D01*
X1675212D01*
X1678944Y502600D01*
X1688696D01*
X1690091Y503995D01*
G01X1671050Y487000D02*
X1672800Y488750D01*
Y491329D01*
X1671703Y492426D01*
X1670538D01*
X1654317Y508647D01*
X1646038D01*
X1637975Y516710D01*
X1613262D01*
X1609672Y513120D01*
X1592694D01*
X1578913Y526897D01*
X1573074D01*
X1570151Y529820D01*
X1537230D01*
X1516572Y509162D01*
Y506884D01*
X1515089Y505401D01*
Y499896D01*
X1512373Y497180D01*
X1504020D01*
X1502138Y499062D01*
X1491152D01*
X1489682Y500532D01*
X1475857D01*
X1474430Y499105D01*
X1470102D01*
X1466065Y495068D01*
Y482459D01*
X1461032Y477426D01*
X1457987D01*
X1447119Y466558D01*
X1361283D01*
X1360730Y466005D01*
X1344005D01*
X1341528Y463528D01*
G01X1323815Y463543D02*
X1325388Y461970D01*
X1331502D01*
X1337041Y467509D01*
X1360106D01*
X1360659Y468062D01*
X1446495D01*
X1457365Y478932D01*
X1460410D01*
X1464561Y483083D01*
Y495692D01*
X1469478Y500609D01*
X1473664D01*
X1475089Y502034D01*
X1492413D01*
X1493085Y501362D01*
X1511821D01*
X1513148Y502689D01*
Y505634D01*
X1515068Y507554D01*
Y509786D01*
X1536606Y531324D01*
X1570775D01*
X1573698Y528401D01*
X1579537D01*
X1593323Y514624D01*
X1609048D01*
X1616001Y521577D01*
X1625424D01*
X1626031Y522184D01*
X1630945D01*
X1635629Y517500D01*
X1640109D01*
X1642670Y514939D01*
G01X1286831Y443058D02*
Y445727D01*
X1296276Y455172D01*
X1306357D01*
X1308055Y456870D01*
Y460966D01*
X1310983Y463894D01*
Y472446D01*
X1318363Y479826D01*
X1318571D01*
X1318809Y480064D01*
X1322320D01*
X1322321Y480065D01*
X1352834D01*
X1357054Y475845D01*
X1402756D01*
X1412234Y485323D01*
X1423279D01*
X1435530Y497574D01*
X1445504D01*
X1455511Y507581D01*
X1459368D01*
X1462257Y510470D01*
X1468753D01*
X1472955Y514672D01*
X1477879D01*
X1481185Y517978D01*
X1485191D01*
X1491913Y524700D01*
X1498373D01*
X1501038Y522035D01*
X1504265D01*
X1508137Y525907D01*
X1514794D01*
X1529499Y540612D01*
X1541419D01*
X1541557Y540750D01*
X1588813D01*
X1590359Y539204D01*
X1602561D01*
X1612600Y534870D01*
X1622629D01*
X1623468Y535709D01*
X1631559D01*
X1632434Y536584D01*
X1643099D01*
X1643974Y535709D01*
X1645844D01*
X1656535Y525018D01*
Y521887D01*
X1670891Y507531D01*
X1675746D01*
X1679653Y503624D01*
X1685924D01*
X1687500Y505200D01*
G01X1285769Y440062D02*
X1285255Y440576D01*
Y445215D01*
X1295964Y455924D01*
X1306045D01*
X1307303Y457182D01*
Y461278D01*
X1310231Y464206D01*
Y472758D01*
X1318290Y480817D01*
X1353429D01*
X1357649Y476597D01*
X1402161D01*
X1411839Y486275D01*
X1422884D01*
X1435135Y498526D01*
X1445109D01*
X1455116Y508533D01*
X1458973D01*
X1461862Y511422D01*
X1468358D01*
X1472560Y515624D01*
X1477484D01*
X1480790Y518930D01*
X1484796D01*
X1491518Y525652D01*
X1498768D01*
X1501433Y522987D01*
X1504028D01*
X1508001Y526960D01*
X1514500D01*
X1529104Y541564D01*
X1541048D01*
X1541186Y541702D01*
X1589208D01*
X1590828Y540082D01*
X1602426D01*
X1612295Y535822D01*
X1622234D01*
X1623073Y536661D01*
X1631164D01*
X1632039Y537536D01*
X1643494D01*
X1644369Y536661D01*
X1646239D01*
X1657487Y525413D01*
Y522282D01*
X1671286Y508483D01*
X1676141D01*
X1680048Y504576D01*
X1684026D01*
X1684650Y505200D01*
G01X1293290Y581160D02*
X1295500Y583370D01*
Y612800D01*
X1293800Y614500D01*
Y620052D01*
X1296600Y622852D01*
X1373995D01*
X1378495Y618352D01*
X1388095D01*
X1391752Y614695D01*
Y605495D01*
X1399215Y598032D01*
X1408309D01*
X1412353Y593988D01*
X1426063D01*
X1435814Y603739D01*
Y610264D01*
X1445743Y620193D01*
X1460895D01*
X1464428Y623726D01*
X1546874D01*
X1551300Y619300D01*
X1568700D01*
X1573194Y623794D01*
X1617706D01*
X1620504Y620996D01*
Y619531D01*
X1620223Y619250D01*
X1619842Y618930D01*
X1619700Y617300D01*
G01X1295090Y579360D02*
X1296252Y580522D01*
Y613112D01*
X1294552Y614812D01*
Y619740D01*
X1296712Y621900D01*
X1373600D01*
X1378100Y617400D01*
X1387700D01*
X1390800Y614300D01*
Y605100D01*
X1398820Y597080D01*
X1407914D01*
X1411958Y593036D01*
X1426458D01*
X1436766Y603344D01*
Y609869D01*
X1446138Y619241D01*
X1461543D01*
X1465237Y622935D01*
X1546235D01*
X1550822Y618348D01*
X1569095D01*
X1573589Y622842D01*
X1617311D01*
X1619552Y620601D01*
Y619930D01*
X1619229Y619659D01*
X1617600Y619800D01*
G01X1400100Y10000D02*
X1403396Y13296D01*
Y16055D01*
X1405246Y17905D01*
X1406034D01*
X1406035Y17904D01*
X1431307D01*
X1439807Y9404D01*
X1486093D01*
X1487693Y11004D01*
X1495700D01*
X1505300Y1404D01*
X1541504D01*
X1543500Y3400D01*
G01X1402600Y10000D02*
X1404348Y11748D01*
Y15660D01*
X1405640Y16952D01*
X1430912D01*
X1439412Y8452D01*
X1486488D01*
X1488088Y10052D01*
X1495305D01*
X1504905Y452D01*
X1573832D01*
X1577884Y-3600D01*
X1605500D01*
G01X1875600Y156300D02*
Y155101D01*
X1876101Y154600D01*
X1878568D01*
X1879672Y153496D01*
Y150594D01*
X1877105Y148027D01*
Y134105D01*
X1874074Y131074D01*
Y113576D01*
X1868026Y107528D01*
Y101580D01*
X1870279Y99327D01*
Y73035D01*
X1867704Y70460D01*
Y49220D01*
X1872550Y44374D01*
Y37290D01*
X1867265Y32005D01*
Y24186D01*
X1868278Y23173D01*
Y20827D01*
X1866331Y18880D01*
X1865784D01*
X1857694Y10790D01*
X1851072D01*
X1850168Y9886D01*
X1848814D01*
X1848800Y9900D01*
X1847800D01*
X1844600Y6700D01*
X1834200D01*
X1831980Y4480D01*
Y938D01*
X1829394Y-1648D01*
Y-3665D01*
X1824283Y-8776D01*
X1817939D01*
X1815489Y-6326D01*
Y2940D01*
X1814566Y3863D01*
X1812163D01*
X1810468Y2168D01*
X1770861D01*
X1760122Y12907D01*
X1734794D01*
X1732501Y15200D01*
X1672300D01*
X1670500Y17000D01*
X1512290D01*
X1507286Y22004D01*
X1463320D01*
X1453151Y32173D01*
Y36526D01*
X1421400Y68277D01*
Y99771D01*
X1402624Y118547D01*
Y119965D01*
X1402770Y120111D01*
Y124951D01*
X1401321Y126400D01*
X1399400D01*
G01X1401200Y124300D02*
X1401876Y123624D01*
Y120847D01*
X1400900Y119871D01*
Y115499D01*
X1418300Y98099D01*
Y62399D01*
X1460999Y19700D01*
X1499500D01*
X1504600Y14600D01*
X1532000D01*
X1537404Y9196D01*
X1587238D01*
X1590230Y6204D01*
X1601326D01*
X1604530Y3000D01*
X1639594D01*
X1648094Y11500D01*
X1653100D01*
G01X1398600Y116500D02*
X1416700Y98400D01*
Y53412D01*
X1452716Y17396D01*
X1498274D01*
X1503374Y12296D01*
X1531044D01*
X1536448Y6892D01*
X1574308D01*
X1579600Y1600D01*
X1602300D01*
X1603300Y600D01*
X1636948D01*
X1644100Y-6552D01*
X1667448D01*
X1677706Y3706D01*
Y4406D01*
X1679314Y6014D01*
X1756541D01*
X1764700Y-2145D01*
Y-6938D01*
X1767690Y-9928D01*
X1823805D01*
X1823806Y-9929D01*
X1824760D01*
X1830546Y-4143D01*
Y-2126D01*
X1833132Y460D01*
Y3932D01*
X1834700Y5500D01*
X1845099D01*
X1848333Y8734D01*
X1850646D01*
X1851550Y9638D01*
X1858172D01*
X1866262Y17728D01*
X1866809D01*
X1869430Y20349D01*
Y23651D01*
X1868417Y24664D01*
Y31527D01*
X1873702Y36812D01*
Y41984D01*
X1873703Y41985D01*
Y44851D01*
X1868856Y49698D01*
Y69678D01*
X1871939Y72761D01*
Y99723D01*
X1869200Y102462D01*
Y106800D01*
X1877276Y114876D01*
Y132522D01*
X1880705Y135951D01*
Y141252D01*
X1878770Y143187D01*
Y148062D01*
X1882900Y152192D01*
Y164337D01*
X1872582Y174655D01*
Y178917D01*
X1879348Y185683D01*
Y200779D01*
X1888576Y210007D01*
Y212773D01*
X1888224Y213125D01*
X1886952D01*
G01X1402500Y116300D02*
X1403000D01*
X1420000Y99300D01*
Y63694D01*
X1462842Y20852D01*
X1500648D01*
X1505676Y15824D01*
X1669473D01*
X1675692Y9605D01*
X1677164D01*
X1677869Y8900D01*
X1731200D01*
X1734055Y11755D01*
X1759644D01*
X1770599Y800D01*
X1802500D01*
X1804800Y-1500D01*
G01X1344090Y463630D02*
X1345713Y465253D01*
X1361042D01*
X1361595Y465806D01*
X1447431D01*
X1458299Y476674D01*
X1461344D01*
X1466817Y482147D01*
Y494756D01*
X1468322Y496261D01*
Y496262D01*
X1470182Y498122D01*
X1470804D01*
X1470805Y498121D01*
X1474764D01*
X1475555Y497330D01*
X1499298D01*
X1500199Y496429D01*
X1512685D01*
X1515948Y499692D01*
Y505196D01*
X1517324Y506572D01*
Y508850D01*
X1537542Y529068D01*
X1569839D01*
X1572762Y526145D01*
X1578601D01*
X1592381Y512368D01*
X1609984D01*
X1613574Y515958D01*
X1636498D01*
X1639391Y513065D01*
G01X1346739Y463615D02*
X1360468D01*
X1361907Y465054D01*
X1448006D01*
X1458874Y475922D01*
X1461656D01*
X1467657Y481923D01*
Y494532D01*
X1468953Y495828D01*
Y495829D01*
X1469073Y495949D01*
Y495950D01*
X1470493Y497370D01*
X1474451D01*
X1475243Y496578D01*
X1498986D01*
X1499886Y495678D01*
X1512997D01*
X1516848Y499529D01*
Y505032D01*
X1518076Y506260D01*
Y508538D01*
X1537854Y528316D01*
X1569527D01*
X1572450Y525393D01*
X1578289D01*
X1592068Y511616D01*
X1610296D01*
X1613886Y515206D01*
X1629224D01*
X1634655Y509775D01*
X1641290D01*
X1643735Y507330D01*
X1654570D01*
X1671050Y490850D01*
G01X1362560Y463478D02*
X1363501Y462537D01*
X1469067D01*
X1471530Y465000D01*
Y474044D01*
X1468599Y476975D01*
Y493255D01*
X1470643Y495299D01*
G01X1347546Y476897D02*
X1350932D01*
X1352424Y475405D01*
Y473950D01*
X1353809Y472565D01*
X1358009D01*
X1358562Y473118D01*
X1443832D01*
X1453845Y483131D01*
Y494381D01*
X1464789Y505325D01*
X1470974D01*
X1472338Y506689D01*
X1473717D01*
X1478624Y511596D01*
X1489608D01*
X1496874Y518862D01*
X1505326D01*
X1508466Y522002D01*
X1517223D01*
X1531601Y536380D01*
X1574367D01*
X1577290Y533457D01*
X1591780D01*
X1594737Y536414D01*
X1602310D01*
X1612976Y531814D01*
X1623897D01*
X1624440Y532357D01*
X1633441D01*
X1634782Y531016D01*
X1642931D01*
X1669519Y504428D01*
X1674422D01*
X1678154Y500696D01*
X1678192D01*
X1679091Y499797D01*
Y492409D01*
X1687500Y484000D01*
G01X1347196Y472941D02*
X1351476Y468661D01*
X1359628D01*
X1360181Y469214D01*
X1446017D01*
X1456978Y480175D01*
X1460023D01*
X1463409Y483561D01*
Y496170D01*
X1468674Y501435D01*
X1473426D01*
X1474911Y502920D01*
X1504460D01*
X1507745Y506205D01*
X1511868D01*
X1513714Y508051D01*
Y510062D01*
X1536128Y532476D01*
X1571254D01*
X1574177Y529553D01*
X1580014D01*
X1593803Y515776D01*
X1607863D01*
X1614816Y522729D01*
X1624946D01*
X1625553Y523336D01*
X1631423D01*
X1636059Y518700D01*
X1644841D01*
X1648326Y515215D01*
X1649545D01*
G01X1354462Y474141D02*
X1443508D01*
X1445898Y476531D01*
Y486010D01*
X1446293Y486405D01*
Y488176D01*
X1464394Y506277D01*
X1469738D01*
X1471182Y507721D01*
X1473394D01*
X1478221Y512548D01*
X1489213D01*
X1496479Y519814D01*
X1504931D01*
X1508071Y522954D01*
X1516828D01*
X1531206Y537332D01*
X1575275D01*
X1578198Y534409D01*
X1591385D01*
X1594342Y537366D01*
X1602511D01*
X1611121Y533651D01*
X1613174Y532766D01*
X1623502D01*
X1624045Y533309D01*
X1633836D01*
X1635177Y531968D01*
X1643326D01*
X1669914Y505380D01*
X1674817D01*
X1678549Y501648D01*
X1678587D01*
X1687443Y492792D01*
Y487203D01*
G01X1350500Y475100D02*
Y474527D01*
X1353414Y471613D01*
X1358404D01*
X1358957Y472166D01*
X1444227D01*
X1454797Y482736D01*
Y493986D01*
X1465184Y504373D01*
X1472102D01*
X1473257Y505528D01*
X1491582D01*
X1492505Y506451D01*
Y513084D01*
X1497319Y517898D01*
X1501391D01*
X1504748Y514541D01*
X1511109D01*
X1531996Y535428D01*
X1573972D01*
X1576895Y532505D01*
X1581238D01*
X1595027Y518728D01*
X1606356D01*
X1617204Y529576D01*
X1623006D01*
X1624835Y531405D01*
X1633046D01*
X1635477Y528974D01*
Y525027D01*
X1637757Y522747D01*
X1649853D01*
X1669253Y503347D01*
X1674156D01*
X1677759Y499744D01*
X1677797D01*
X1678139Y499402D01*
Y491132D01*
X1686847Y482424D01*
X1701335D01*
X1701617Y482706D01*
G01X1362528Y547954D02*
X1365016Y545466D01*
X1383161D01*
X1389309Y551614D01*
X1414860D01*
X1417867Y554621D01*
X1423191D01*
X1428947Y560377D01*
Y563577D01*
X1444832Y579462D01*
X1452668D01*
X1458078Y574052D01*
X1460733D01*
X1465201Y578520D01*
X1489160D01*
X1492200Y581560D01*
X1516940D01*
X1523208Y587828D01*
X1529318D01*
X1534992Y593502D01*
X1555410D01*
X1557847Y595939D01*
X1565998D01*
X1568554Y598495D01*
Y601969D01*
X1569924Y603339D01*
X1571655D01*
X1576067Y607751D01*
X1585030D01*
X1592719Y615440D01*
Y617936D01*
X1593519Y618736D01*
G01X1365028Y547954D02*
Y546664D01*
X1365380Y546312D01*
X1382719D01*
X1388973Y552566D01*
X1414465D01*
X1417472Y555573D01*
X1422796D01*
X1427995Y560772D01*
Y563972D01*
X1444437Y580414D01*
X1453063D01*
X1458473Y575004D01*
X1460238D01*
X1465092Y579858D01*
X1488958D01*
X1491650Y582550D01*
X1516226D01*
X1522344Y588668D01*
X1528538D01*
X1534124Y594254D01*
X1554815D01*
X1557452Y596891D01*
X1565603D01*
X1567802Y599090D01*
Y602281D01*
X1569612Y604091D01*
X1571060D01*
X1575672Y608703D01*
X1584753D01*
X1591767Y615717D01*
Y617902D01*
X1590881Y618788D01*
G01X1535565Y591658D02*
X1530893Y586986D01*
X1523938D01*
X1517302Y580350D01*
X1492730D01*
X1489705Y577325D01*
X1465755D01*
X1461330Y572900D01*
X1457600D01*
X1452190Y578310D01*
X1445310D01*
X1430100Y563100D01*
Y559900D01*
X1423000Y552800D01*
X1418900D01*
X1407357Y541257D01*
X1396843D01*
X1391551Y546549D01*
X1390170D01*
X1387907Y544286D01*
G01X1813913Y2287D02*
X1812076Y450D01*
X1809472D01*
X1805922Y-3100D01*
X1805820D01*
X1805567Y-3353D01*
X1804033D01*
X1801164Y-484D01*
X1769263D01*
X1761613Y7166D01*
X1680550D01*
X1680549Y7167D01*
X1679595D01*
X1679594Y7166D01*
X1676167D01*
X1663601Y-5400D01*
X1644578D01*
X1637426Y1752D01*
X1604148D01*
X1600848Y5052D01*
X1589752D01*
X1586760Y8044D01*
X1536926D01*
X1531522Y13448D01*
X1503852D01*
X1498752Y18548D01*
X1453793D01*
X1425081Y47260D01*
Y48412D01*
G01X1545111Y24172D02*
X1539163Y18224D01*
X1512696D01*
X1507764Y23156D01*
X1463798D01*
X1454345Y32609D01*
Y37456D01*
X1422870Y68931D01*
Y100530D01*
X1404200Y119200D01*
G01X1680034Y2863D02*
X1668715Y-8456D01*
X1619244D01*
X1616700Y-11000D01*
X1578492D01*
X1569334Y-1842D01*
X1569242D01*
X1569200Y-1800D01*
X1504463D01*
X1502163Y500D01*
X1434658D01*
X1426058Y9100D01*
X1410600D01*
G01X1405100Y10000D02*
Y15348D01*
X1405952Y16200D01*
X1430600D01*
X1439100Y7700D01*
X1486800D01*
X1488400Y9300D01*
X1494993D01*
X1504593Y-300D01*
X1570394D01*
X1571500Y-1406D01*
G01X1420337Y45477D02*
X1419352Y44492D01*
Y43248D01*
X1422300Y40300D01*
X1424200D01*
X1448300Y16200D01*
X1497200D01*
X1504600Y8800D01*
X1514900D01*
X1516600Y7100D01*
X1520700D01*
G01X1416837Y45477D02*
X1418600Y43714D01*
Y42936D01*
X1421988Y39548D01*
X1423888D01*
X1447988Y15448D01*
X1496888D01*
X1505254Y7082D01*
X1513700D01*
G01X1819800Y2100D02*
Y3400D01*
X1816300Y6900D01*
X1811442D01*
X1809742Y5200D01*
X1775806D01*
X1765444Y15562D01*
X1761225D01*
X1761224Y15563D01*
X1735896D01*
X1733603Y17856D01*
X1673402D01*
X1671602Y19656D01*
X1646407D01*
X1641360Y24703D01*
X1631185D01*
X1629818Y23336D01*
X1604436D01*
X1603000Y21900D01*
X1597209D01*
X1595909Y23200D01*
Y25737D01*
X1590307Y31339D01*
X1589061D01*
X1589060Y31338D01*
X1564032D01*
X1552473Y42897D01*
X1481694D01*
X1474278Y35481D01*
X1473781D01*
X1471400Y33100D01*
X1469200D01*
X1467498Y34802D01*
Y59473D01*
X1453221Y73750D01*
G01X1450532Y178372D02*
X1448133Y175973D01*
Y159667D01*
X1453241Y154559D01*
Y137992D01*
X1451526Y136277D01*
Y120644D01*
X1446351Y115469D01*
Y80620D01*
X1453221Y73750D01*
G01X1451365Y176014D02*
X1451214D01*
X1449600Y174400D01*
Y159830D01*
X1454393Y155037D01*
Y137514D01*
X1452678Y135799D01*
Y120166D01*
X1447781Y115269D01*
Y115162D01*
X1447780Y115161D01*
Y114207D01*
X1447781Y114206D01*
Y81808D01*
X1455889Y73700D01*
G01D02*
X1468652Y60937D01*
Y37848D01*
X1469867Y36633D01*
X1473800D01*
X1481216Y44049D01*
X1552951D01*
X1564462Y32538D01*
X1591633D01*
X1597800Y26371D01*
Y24300D01*
G01X1497237Y217281D02*
Y216718D01*
X1491419Y210900D01*
X1487208D01*
X1471506Y195198D01*
X1469100D01*
X1462028Y188126D01*
Y185528D01*
X1455745Y179245D01*
Y170265D01*
X1453000Y167520D01*
Y164620D01*
X1451880Y163500D01*
Y159180D01*
X1455545Y155515D01*
Y137036D01*
X1453830Y135321D01*
Y119688D01*
X1448933Y114791D01*
Y83272D01*
X1470862Y61343D01*
Y38209D01*
G01X1503842Y245678D02*
X1504048Y245472D01*
Y238019D01*
X1506120Y235947D01*
Y222040D01*
X1504219Y220139D01*
Y219351D01*
X1504220Y219350D01*
Y217288D01*
X1494776Y207844D01*
X1488668D01*
X1472009Y191185D01*
X1469455D01*
X1465084Y186814D01*
Y184260D01*
X1458801Y177977D01*
Y135968D01*
X1457660Y134827D01*
Y110431D01*
X1462896Y105195D01*
Y85163D01*
X1500309Y47750D01*
X1573287D01*
X1579797Y41240D01*
X1594655D01*
X1606666Y29229D01*
X1753369D01*
X1755474Y27124D01*
X1758913D01*
X1760266Y28477D01*
X1770181D01*
X1783780Y14878D01*
Y14870D01*
X1784340Y14310D01*
X1814260D01*
X1814857Y14907D01*
X1817893D01*
X1819547Y13253D01*
Y8806D01*
X1822153Y6200D01*
X1827100D01*
X1829700Y8800D01*
X1831400D01*
X1832900Y10300D01*
G01X1504772Y259229D02*
X1504196Y258653D01*
Y254847D01*
X1504215Y254828D01*
Y251785D01*
X1505554Y250446D01*
Y237860D01*
X1507072Y236342D01*
Y221645D01*
X1505172Y219745D01*
Y217799D01*
X1505173Y217798D01*
Y216894D01*
X1495171Y206892D01*
X1489462D01*
X1472803Y190233D01*
X1469850D01*
X1466036Y186419D01*
Y183865D01*
X1459753Y177582D01*
Y135573D01*
X1458612Y134432D01*
Y110826D01*
X1463848Y105590D01*
Y85558D01*
X1500704Y48702D01*
X1573682D01*
X1580192Y42192D01*
X1595050D01*
X1607061Y30181D01*
X1753764D01*
X1755869Y28076D01*
X1758518D01*
X1760042Y29600D01*
X1770405D01*
X1784741Y15264D01*
X1813866D01*
X1814702Y16100D01*
X1818390D01*
X1821200Y13290D01*
Y8971D01*
X1822971Y7200D01*
X1826100D01*
X1829635Y10735D01*
X1829888D01*
G01X1502165Y251200D02*
Y250388D01*
X1502000Y250223D01*
Y238720D01*
X1505168Y235552D01*
Y222435D01*
X1503267Y220534D01*
Y218956D01*
X1503268Y218955D01*
Y217683D01*
X1494381Y208796D01*
X1488273D01*
X1472138Y192661D01*
X1469560D01*
X1464132Y187233D01*
Y184655D01*
X1457849Y178372D01*
Y136363D01*
X1456290Y134804D01*
Y110454D01*
X1461944Y104800D01*
Y84768D01*
X1499914Y46798D01*
X1572892D01*
X1579402Y40288D01*
X1594260D01*
G01X1594887Y39661D02*
X1606272Y28276D01*
X1607060D01*
X1607061Y28277D01*
X1752974D01*
X1755079Y26172D01*
X1759308D01*
X1760661Y27525D01*
X1769786D01*
X1772700Y24611D01*
Y21085D01*
X1785366Y8419D01*
Y8100D01*
G01X1452232Y109500D02*
X1458942Y102790D01*
Y86142D01*
X1460792Y84292D01*
Y84290D01*
X1499436Y45646D01*
X1499438D01*
X1499634Y45450D01*
X1561499D01*
X1572609Y34340D01*
X1596559D01*
X1603774Y27125D01*
X1605793D01*
X1605794Y27124D01*
X1607538D01*
X1607539Y27125D01*
X1640801D01*
X1645126Y22800D01*
X1718580D01*
X1721796Y19584D01*
X1734567D01*
X1736489Y17662D01*
X1767123D01*
X1778261Y6524D01*
X1808124D01*
X1809671Y8071D01*
X1817228D01*
X1824299Y1000D01*
X1825324D01*
G01X1786865Y22375D02*
X1781671D01*
X1758960Y45086D01*
X1735402D01*
X1729623Y50865D01*
X1728835D01*
X1728834Y50864D01*
X1685442D01*
X1679423Y56883D01*
X1655540D01*
X1646457Y47800D01*
X1582606D01*
X1575896Y54510D01*
X1503508D01*
X1471237Y86781D01*
Y106772D01*
X1471238Y106773D01*
Y107561D01*
X1464344Y114455D01*
Y132230D01*
X1465361Y133247D01*
Y174973D01*
X1472291Y181903D01*
Y183349D01*
X1484747Y195805D01*
X1485535D01*
X1485536Y195804D01*
X1494075D01*
X1499549Y201278D01*
X1502473D01*
X1513387Y212192D01*
X1515428D01*
X1519983Y216747D01*
Y224405D01*
X1528261Y232683D01*
Y237880D01*
X1526591Y239550D01*
Y245645D01*
X1527874Y246928D01*
Y250705D01*
X1524747Y253832D01*
Y267436D01*
X1519434Y272749D01*
Y279698D01*
X1523149Y283413D01*
Y313098D01*
X1528120Y318069D01*
Y326097D01*
X1531938Y329915D01*
Y353169D01*
X1529731Y355376D01*
Y358193D01*
X1527199Y360725D01*
Y368486D01*
X1531995Y373282D01*
Y378165D01*
X1530796Y379364D01*
Y382296D01*
X1532000Y383500D01*
Y385000D01*
X1533945Y386945D01*
Y388355D01*
X1532000Y390300D01*
Y392000D01*
X1530045Y393955D01*
Y395065D01*
X1527610Y397500D01*
X1526659D01*
G01X1528475Y394414D02*
X1528844Y394045D01*
Y389556D01*
X1530045Y388355D01*
Y386945D01*
X1528846Y385746D01*
Y382744D01*
X1530045Y381545D01*
Y380155D01*
X1528095Y378205D01*
Y374765D01*
X1526226Y372896D01*
Y360261D01*
X1528779Y357708D01*
Y354981D01*
X1530333Y353427D01*
Y347562D01*
X1528210Y345439D01*
Y335972D01*
X1529430Y334752D01*
Y329220D01*
X1527010Y326800D01*
Y318306D01*
X1522197Y313493D01*
Y283808D01*
X1518482Y280093D01*
Y271718D01*
X1521999Y268201D01*
Y248962D01*
X1525541Y245420D01*
Y236061D01*
X1521999Y232519D01*
Y228051D01*
X1518830Y224882D01*
Y216941D01*
X1515233Y213344D01*
X1512193D01*
X1501279Y202430D01*
X1499320D01*
X1493647Y196757D01*
X1484352D01*
X1471339Y183744D01*
Y182298D01*
X1464409Y175368D01*
Y133642D01*
X1463392Y132625D01*
Y114060D01*
X1470285Y107167D01*
Y86386D01*
X1503113Y53558D01*
X1575501D01*
X1582211Y46848D01*
X1646852D01*
X1655787Y55783D01*
X1675219D01*
X1687171Y43831D01*
X1758868D01*
X1783135Y19564D01*
X1790350D01*
X1790351Y19563D01*
X1794016D01*
X1797047Y22594D01*
X1798353D01*
X1799276Y21671D01*
Y19583D01*
X1802643Y16216D01*
X1813471D01*
X1814308Y17053D01*
X1818794D01*
X1823600Y12247D01*
Y8800D01*
G01X1843426Y9528D02*
Y11674D01*
X1837801Y17299D01*
X1830532D01*
X1827881Y19950D01*
Y22511D01*
X1827116Y23276D01*
X1819184D01*
X1813076Y17168D01*
X1804138D01*
X1800229Y21077D01*
Y22065D01*
X1798748Y23546D01*
X1796652D01*
X1795196Y22090D01*
X1789551D01*
X1787581Y24060D01*
X1781333D01*
X1755917Y49476D01*
X1732360D01*
X1727887Y53949D01*
X1721220D01*
X1721153Y54016D01*
X1719847D01*
X1719780Y53949D01*
X1684816D01*
X1680597Y58168D01*
X1655478D01*
X1646062Y48752D01*
X1583001D01*
X1576291Y55462D01*
X1503903D01*
X1472190Y87175D01*
Y107166D01*
X1472191Y107167D01*
Y107955D01*
X1465296Y114850D01*
Y131835D01*
X1466313Y132852D01*
Y174578D01*
X1473243Y181508D01*
Y182954D01*
X1485141Y194852D01*
X1497584D01*
X1510100Y207368D01*
X1513178D01*
X1514101Y208291D01*
Y208602D01*
X1520935Y215436D01*
Y224010D01*
X1529213Y232288D01*
Y241126D01*
X1531428Y243341D01*
Y246132D01*
X1529626Y247934D01*
Y250510D01*
X1525699Y254437D01*
Y268036D01*
X1520386Y273349D01*
Y279303D01*
X1524101Y283018D01*
Y296100D01*
X1528587Y300586D01*
Y309690D01*
X1532128Y313231D01*
Y321402D01*
X1530348Y323182D01*
Y326978D01*
X1532890Y329520D01*
Y353564D01*
X1530683Y355771D01*
Y358722D01*
X1528253Y361152D01*
Y367506D01*
X1532746Y371999D01*
Y378946D01*
X1534000Y380200D01*
Y381700D01*
X1535900Y383600D01*
Y385000D01*
X1537845Y386945D01*
Y388355D01*
X1535900Y390300D01*
Y391800D01*
X1533945Y393755D01*
Y395065D01*
X1536275Y397395D01*
Y401174D01*
G01X1524575Y380894D02*
X1523460Y379779D01*
Y378900D01*
X1524195Y378165D01*
Y361397D01*
X1523170Y360372D01*
Y353096D01*
X1523917Y352349D01*
Y336773D01*
X1523918Y336772D01*
Y335818D01*
X1523917Y335817D01*
Y330808D01*
X1521356Y328247D01*
Y324448D01*
X1521245Y324337D01*
Y284203D01*
X1517530Y280488D01*
Y260169D01*
X1512612Y255251D01*
Y242812D01*
X1511155Y241355D01*
Y238505D01*
X1513806Y235854D01*
Y221036D01*
X1513003Y220233D01*
Y219373D01*
X1494530Y200900D01*
X1487148D01*
X1470387Y184139D01*
Y182693D01*
X1463457Y175763D01*
Y134037D01*
X1462440Y133020D01*
Y113665D01*
X1469333Y106772D01*
Y85991D01*
X1502718Y52606D01*
X1575106D01*
X1581816Y45896D01*
X1647247D01*
X1656033Y54682D01*
X1674897D01*
X1686700Y42879D01*
X1758473D01*
X1782740Y18612D01*
X1789955D01*
X1789956Y18611D01*
X1794411D01*
X1794412Y18612D01*
X1796648D01*
X1797700Y19664D01*
Y21018D01*
G01X1669500Y51500D02*
X1667663Y53337D01*
X1656318D01*
X1647725Y44744D01*
X1581250D01*
X1574540Y51454D01*
X1502240D01*
X1468181Y85513D01*
Y106294D01*
X1461164Y113311D01*
Y133374D01*
X1462305Y134515D01*
Y176241D01*
X1469235Y183171D01*
Y183661D01*
X1469234Y183662D01*
Y184616D01*
X1486670Y202052D01*
X1494052D01*
X1511851Y219851D01*
Y236179D01*
X1510003Y238027D01*
Y241833D01*
X1511460Y243290D01*
Y255740D01*
X1513906Y258186D01*
Y281453D01*
X1516981Y284528D01*
X1518821D01*
X1520093Y285800D01*
Y324815D01*
X1520204Y324926D01*
Y333734D01*
X1522765Y336295D01*
Y351510D01*
X1522018Y352257D01*
Y359958D01*
X1518056Y363920D01*
Y368331D01*
X1522625Y372900D01*
Y377514D01*
G01X1474439Y207621D02*
X1471609Y204791D01*
Y201249D01*
X1458903Y188543D01*
Y187704D01*
X1458908Y187699D01*
G01X1473083Y393770D02*
X1475100Y391753D01*
Y375437D01*
X1474163Y374500D01*
X1472050D01*
X1468500Y370950D01*
X1464850D01*
X1459300Y376500D01*
X1456054D01*
X1454504Y374950D01*
Y364604D01*
X1442634Y352734D01*
Y330570D01*
X1438678Y326614D01*
Y314909D01*
X1440603Y305288D01*
Y286064D01*
X1440008Y285469D01*
Y273820D01*
X1441695Y272133D01*
X1453432D01*
X1454902Y273603D01*
G01X1442304D02*
X1443984Y275283D01*
X1449283D01*
X1450100Y276100D01*
Y308889D01*
X1449255Y309734D01*
X1448081D01*
X1447000Y310815D01*
Y312400D01*
X1444025Y315375D01*
Y318329D01*
X1444058Y318362D01*
Y318381D01*
X1444919Y319242D01*
X1444938D01*
X1446294Y320598D01*
Y329392D01*
X1444890Y330796D01*
Y342750D01*
X1452000Y349860D01*
Y355050D01*
X1451600Y355450D01*
Y358800D01*
X1455724Y362924D01*
Y374253D01*
X1456647Y375176D01*
X1457953D01*
X1463579Y369550D01*
X1472950D01*
X1477200Y373800D01*
Y387800D01*
X1481400Y392000D01*
X1490170D01*
X1490774Y392604D01*
X1492076D01*
X1492180Y392500D01*
X1494570D01*
X1494674Y392604D01*
X1495976D01*
X1496080Y392500D01*
X1498470D01*
X1498574Y392604D01*
X1499365D01*
X1501175Y394414D01*
G01X1461300Y270400D02*
X1462800Y271900D01*
Y280900D01*
X1463482Y281582D01*
X1464960D01*
X1466100Y282722D01*
Y316226D01*
X1468681Y318807D01*
Y322582D01*
X1469851Y323752D01*
X1472012D01*
X1475308Y327048D01*
Y354768D01*
X1477550Y357010D01*
X1478781D01*
X1480276Y358505D01*
Y366840D01*
X1482621Y369185D01*
X1485317D01*
X1492995Y376863D01*
Y378293D01*
X1494945Y380243D01*
Y382433D01*
X1493755Y383623D01*
Y384925D01*
X1494490Y385660D01*
Y386539D01*
X1493375Y387654D01*
G01X1445100Y374900D02*
X1447750Y372250D01*
Y368293D01*
X1436525Y357068D01*
Y332755D01*
X1433870Y330100D01*
Y313957D01*
X1435798Y304307D01*
Y291727D01*
X1429123Y285052D01*
Y272438D01*
X1433548Y268013D01*
Y265203D01*
X1441276Y257475D01*
Y251647D01*
X1440679Y251050D01*
X1438250D01*
X1436400Y252900D01*
X1434652D01*
X1434300Y252548D01*
Y251600D01*
G01X1470100Y392350D02*
X1465975Y388225D01*
X1464525D01*
X1461904Y385604D01*
Y384775D01*
X1457403Y380274D01*
X1456174D01*
X1452600Y376700D01*
Y367538D01*
X1440500Y355438D01*
Y331382D01*
X1437174Y328056D01*
Y314290D01*
X1439101Y304664D01*
Y286688D01*
X1438506Y286093D01*
Y269021D01*
X1441694Y265833D01*
X1452361D01*
X1452697Y266169D01*
X1454056D01*
G01X1447154Y251710D02*
Y251926D01*
X1453252Y258024D01*
X1454674D01*
X1459572Y262922D01*
Y280351D01*
X1460803Y281582D01*
X1461811D01*
X1462881Y282652D01*
Y299419D01*
X1461202Y301098D01*
Y301948D01*
G01X1448603Y270454D02*
X1447133Y268984D01*
X1441694D01*
X1439257Y271421D01*
Y285781D01*
X1439852Y286376D01*
Y304745D01*
X1437926Y314365D01*
Y326926D01*
X1441882Y330882D01*
Y355256D01*
X1453600Y366974D01*
Y375900D01*
X1456900Y379200D01*
X1463350D01*
X1466950Y382800D01*
Y385630D01*
X1471670Y390350D01*
Y393029D01*
X1470800Y393899D01*
Y395200D01*
G01X1441750Y236800D02*
X1447300Y242350D01*
Y247470D01*
X1445260Y249510D01*
Y252186D01*
X1447622Y254548D01*
X1448712D01*
X1450828Y256664D01*
Y259636D01*
X1446364Y264100D01*
X1442135D01*
X1433362Y272873D01*
Y278244D01*
G01X1451850Y262200D02*
X1452121D01*
X1453697Y263776D01*
X1455826D01*
X1456582Y264532D01*
Y280511D01*
X1457443Y281372D01*
X1459309D01*
X1459732Y281795D01*
Y294931D01*
X1459600Y295063D01*
Y312998D01*
X1458052Y314546D01*
G01X1444850Y242730D02*
X1444180Y243400D01*
Y252170D01*
X1447310Y255300D01*
X1448329D01*
X1450076Y257047D01*
Y258353D01*
X1445629Y262800D01*
X1442371D01*
X1431700Y273471D01*
Y283500D01*
X1438350Y290150D01*
Y304574D01*
X1436422Y314215D01*
Y328368D01*
X1439100Y331046D01*
Y355668D01*
X1451500Y368068D01*
Y376900D01*
X1452500Y377900D01*
Y385429D01*
X1457371Y390300D01*
X1463950D01*
X1464400Y390750D01*
Y390800D01*
G01X1447685Y352025D02*
Y347881D01*
X1443386Y343582D01*
Y330258D01*
X1441935Y328807D01*
Y328564D01*
X1441924Y328553D01*
Y327247D01*
X1441935Y327236D01*
Y321925D01*
X1439430Y319420D01*
Y315295D01*
X1440760Y313965D01*
Y310869D01*
X1440834Y310795D01*
Y310788D01*
X1441695Y309927D01*
X1441702D01*
X1441875Y309754D01*
X1443039D01*
X1443939Y308854D01*
Y287508D01*
X1440788Y284357D01*
Y279339D01*
X1442127Y278000D01*
X1444207D01*
X1445454Y276753D01*
G01X1487525Y384274D02*
X1486897D01*
X1478969Y376346D01*
Y373406D01*
X1473212Y367649D01*
X1469081D01*
X1468678Y367246D01*
X1468676D01*
X1466021Y364591D01*
Y360732D01*
X1466353Y360400D01*
Y349583D01*
X1464225Y347455D01*
Y334729D01*
X1448603Y319107D01*
Y317696D01*
G01X1489475Y387654D02*
Y383115D01*
X1482368Y376008D01*
Y375589D01*
X1470576Y363797D01*
Y345197D01*
X1467803Y342424D01*
Y334204D01*
X1458400Y324801D01*
Y318500D01*
G01X1467323Y315405D02*
Y281622D01*
X1465603Y279902D01*
X1464351D01*
G01X1454902Y301948D02*
X1456554Y303600D01*
Y325994D01*
X1465377Y334817D01*
Y346977D01*
X1468100Y349700D01*
Y362497D01*
X1467597Y363000D01*
G01X1461202Y301948D02*
Y302902D01*
X1462672Y304372D01*
Y312028D01*
X1464102Y313458D01*
Y317452D01*
X1465349Y318699D01*
Y324109D01*
X1469797Y328557D01*
X1470288D01*
X1474556Y332825D01*
Y355419D01*
X1478107Y358970D01*
X1478495D01*
Y359082D01*
X1478607D01*
G01X1482200Y477800D02*
X1484400Y475600D01*
Y474870D01*
X1487887Y471383D01*
Y463482D01*
X1485884Y461479D01*
Y446438D01*
X1487905Y444417D01*
Y442767D01*
X1485955Y440817D01*
Y439173D01*
X1486192Y438936D01*
Y426013D01*
X1483930Y423751D01*
Y421913D01*
X1486043Y419800D01*
X1491920D01*
X1493400Y418320D01*
Y417300D01*
X1494945Y415755D01*
Y413345D01*
X1493755Y412155D01*
Y410145D01*
X1494945Y408955D01*
Y405445D01*
X1491805Y402305D01*
Y400195D01*
X1493500Y398500D01*
Y397398D01*
X1494914Y395984D01*
X1501826D01*
X1502745Y395065D01*
Y393763D01*
X1500795Y391813D01*
Y390383D01*
X1499876Y389464D01*
X1492964D01*
X1491805Y388305D01*
Y386795D01*
X1492995Y385605D01*
Y382735D01*
X1491805Y381545D01*
Y381003D01*
X1489855Y379053D01*
Y377623D01*
X1484622Y372390D01*
X1483169D01*
X1476800Y366021D01*
Y362299D01*
X1472704Y358203D01*
Y344113D01*
X1470850Y342259D01*
Y334447D01*
X1461306Y324903D01*
Y316694D01*
X1462672Y315328D01*
Y313671D01*
X1461202Y312201D01*
Y311397D01*
G01X1458052Y286202D02*
X1456582Y284732D01*
X1454293D01*
X1453281Y285744D01*
Y306971D01*
X1450073Y310179D01*
Y312006D01*
X1449212Y312867D01*
X1449197D01*
X1448988Y313076D01*
X1447698D01*
X1446970Y313804D01*
Y317135D01*
X1446998Y317163D01*
Y318381D01*
X1446970Y318409D01*
Y318593D01*
X1447236Y318859D01*
Y331564D01*
X1446400Y332400D01*
Y342900D01*
X1456250Y352750D01*
Y358400D01*
X1457850Y360000D01*
Y370100D01*
X1457300Y370650D01*
Y373600D01*
G01X1444311Y324366D02*
X1444176Y324231D01*
Y320090D01*
X1443131Y319045D01*
Y314756D01*
X1445454Y312433D01*
Y311397D01*
G01X1450400Y354300D02*
Y349404D01*
X1444138Y343142D01*
Y330163D01*
X1445076Y329225D01*
Y326999D01*
X1444401Y326324D01*
X1444040D01*
X1442735Y325019D01*
Y323713D01*
X1443211Y323237D01*
Y320188D01*
X1442380Y319357D01*
Y313432D01*
X1443984Y311828D01*
Y310788D01*
X1444563Y310209D01*
Y310187D01*
X1444915Y309835D01*
X1446508D01*
X1447064Y309279D01*
Y284662D01*
X1442304Y279902D01*
G01X1463942Y359742D02*
X1464869Y360669D01*
Y364113D01*
X1464868Y364114D01*
Y365068D01*
X1468198Y368398D01*
X1468678D01*
X1468680Y368400D01*
X1472900D01*
X1477952Y373452D01*
Y386952D01*
X1481233Y390233D01*
X1483868D01*
G01X1414107Y447267D02*
X1414367D01*
X1423076Y455976D01*
X1443026D01*
X1451002Y448000D01*
X1452900D01*
X1458300Y442600D01*
Y442675D01*
G01X1417800Y521500D02*
X1417152Y522148D01*
Y539776D01*
X1430891Y553515D01*
X1433015D01*
X1439452Y559952D01*
Y561738D01*
X1448729Y571015D01*
X1450035D01*
X1451150Y569900D01*
G01Y573200D02*
X1450350Y572400D01*
X1448511D01*
X1438336Y562225D01*
Y560298D01*
X1432706Y554668D01*
X1430414D01*
X1416000Y540254D01*
Y522600D01*
X1414800Y521400D01*
G01X1496660Y-10252D02*
X1496652D01*
X1497300Y-10900D01*
X1507600D01*
X1515240Y-3260D01*
X1544862D01*
X1544872Y-3250D01*
X1568750D01*
X1577908Y-12408D01*
X1611708D01*
X1618300Y-19000D01*
X1671350D01*
X1673500Y-16850D01*
G01X1635337Y73500D02*
X1634388D01*
X1617456Y56568D01*
X1586244D01*
X1573432Y69380D01*
Y72532D01*
X1575292Y74392D01*
Y76392D01*
X1573877Y77807D01*
X1561640D01*
Y77790D01*
X1560210Y76360D01*
Y68610D01*
X1558970Y67370D01*
X1549840D01*
X1544140Y61670D01*
X1507873D01*
X1496945Y72598D01*
Y74721D01*
X1483027Y88639D01*
Y109234D01*
X1493310Y119517D01*
Y120970D01*
X1494837Y122497D01*
X1500714D01*
X1504317Y126100D01*
X1510850D01*
X1511800Y127050D01*
G01X1779750Y36530D02*
X1777201Y39079D01*
X1774976D01*
X1774959Y39096D01*
X1773159D01*
X1755949Y56306D01*
X1732265D01*
X1726235Y62336D01*
X1701405D01*
X1700664Y63077D01*
X1653652D01*
X1644087Y53512D01*
X1584976D01*
X1578265Y60223D01*
X1574317D01*
X1574316Y60222D01*
X1507691D01*
X1495792Y72121D01*
Y74244D01*
X1480565Y89471D01*
Y132462D01*
X1493428Y145325D01*
Y149023D01*
X1490237Y152214D01*
Y156346D01*
X1493363Y159472D01*
Y160153D01*
X1495437Y162227D01*
Y162785D01*
X1501380Y168728D01*
X1507221D01*
X1527834Y189341D01*
Y193296D01*
X1532973Y198435D01*
Y201446D01*
X1555965Y224438D01*
Y239510D01*
X1560425Y243970D01*
X1567878D01*
X1573452Y249544D01*
Y279232D01*
X1576983Y282763D01*
Y296083D01*
X1579056Y298156D01*
Y303967D01*
X1580996Y305907D01*
Y310328D01*
X1580258Y311066D01*
Y323335D01*
X1585596Y328673D01*
Y333564D01*
X1592946Y340914D01*
Y361949D01*
X1587836Y367059D01*
Y391835D01*
X1590000Y393999D01*
Y401602D01*
X1588234Y403368D01*
X1587968D01*
G01X1591430Y409440D02*
Y411442D01*
X1591076Y411796D01*
Y412688D01*
X1590153Y413611D01*
X1586406D01*
X1579579Y406784D01*
Y376430D01*
X1571951Y368802D01*
Y363410D01*
X1573102Y362259D01*
Y339431D01*
X1571939Y338268D01*
Y330411D01*
X1569861Y328333D01*
Y315157D01*
X1571082Y313936D01*
Y311732D01*
X1568150Y308800D01*
Y307328D01*
X1568915Y306563D01*
Y300755D01*
X1562472Y294312D01*
Y284106D01*
X1556719Y278353D01*
Y259623D01*
X1550805Y253709D01*
Y230313D01*
X1526515Y206023D01*
Y199278D01*
X1522130Y194893D01*
Y190938D01*
X1520028Y188836D01*
X1507891D01*
X1496359Y177304D01*
Y177254D01*
X1495436Y176331D01*
X1495404D01*
X1495378Y176305D01*
X1495360D01*
X1494219Y175164D01*
X1491549D01*
X1490537Y174152D01*
X1488247D01*
X1487324Y173229D01*
Y165954D01*
X1485580Y164210D01*
Y141542D01*
X1477709Y133671D01*
Y84350D01*
X1504693Y57366D01*
X1575501D01*
X1575502Y57367D01*
X1577080D01*
X1583791Y50656D01*
X1645272D01*
X1654837Y60221D01*
X1699479D01*
X1700220Y59480D01*
X1725050D01*
X1732499Y52031D01*
X1756056D01*
X1779587Y28500D01*
X1785835D01*
X1790266Y24069D01*
X1794481D01*
X1795862Y25450D01*
X1799538D01*
X1802134Y22854D01*
Y21866D01*
X1804928Y19072D01*
X1811902D01*
X1818011Y25181D01*
X1819973D01*
X1819974Y25180D01*
X1828907D01*
X1829125Y24962D01*
X1840187D01*
X1842865Y22284D01*
Y19036D01*
X1848322Y13579D01*
Y12723D01*
G01X1590581Y404170D02*
X1593006Y406595D01*
Y411247D01*
X1592028Y412225D01*
Y413083D01*
X1590548Y414563D01*
X1582735D01*
X1578598Y410426D01*
Y376738D01*
X1569096Y367236D01*
Y358810D01*
X1572150Y355756D01*
Y340050D01*
X1570987Y338887D01*
Y330806D01*
X1568909Y328728D01*
Y314762D01*
X1570100Y313571D01*
Y312097D01*
X1567198Y309195D01*
Y305630D01*
X1567963Y304865D01*
Y301156D01*
X1561770Y294963D01*
Y294957D01*
X1561520Y294707D01*
Y284501D01*
X1555767Y278748D01*
Y260018D01*
X1549626Y253877D01*
Y230481D01*
X1525562Y206417D01*
Y199672D01*
X1521177Y195287D01*
Y191332D01*
X1519633Y189788D01*
X1508286D01*
X1508285Y189789D01*
X1507497D01*
X1507496Y189788D01*
X1507059D01*
X1503497Y186226D01*
X1497342D01*
X1492079Y180963D01*
X1491816D01*
X1490893Y180040D01*
Y179777D01*
X1490820Y179704D01*
Y175782D01*
X1490142Y175104D01*
X1487852D01*
X1486372Y173624D01*
Y166349D01*
X1484628Y164605D01*
Y141937D01*
X1476757Y134066D01*
Y83955D01*
X1504298Y56414D01*
X1575896D01*
X1575897Y56415D01*
X1576685D01*
X1583396Y49704D01*
X1645667D01*
X1655232Y59269D01*
X1699084D01*
X1699825Y58528D01*
X1724655D01*
X1732423Y50760D01*
X1755980D01*
X1781690Y25050D01*
X1787558D01*
X1787596Y25012D01*
X1787976D01*
X1789871Y23117D01*
X1794876D01*
X1796257Y24498D01*
X1799143D01*
X1801182Y22459D01*
Y21471D01*
X1804533Y18120D01*
X1812483D01*
X1818591Y24228D01*
X1828512D01*
X1828731Y24009D01*
X1829519D01*
X1829520Y24010D01*
X1838910D01*
X1841289Y21631D01*
G01X1791500Y26918D02*
X1789966Y28452D01*
X1788775D01*
X1782370Y34857D01*
X1776033D01*
X1755536Y55354D01*
X1731870D01*
X1725840Y61384D01*
X1701010D01*
X1700269Y62125D01*
X1654047D01*
X1644482Y52560D01*
X1584581D01*
X1577870Y59271D01*
X1574712D01*
X1574711Y59270D01*
X1507296D01*
X1494840Y71726D01*
Y73849D01*
X1479613Y89076D01*
Y132881D01*
X1492476Y145744D01*
Y148628D01*
X1489285Y151819D01*
Y156741D01*
X1491160Y158616D01*
Y162889D01*
X1505771Y177500D01*
X1513299D01*
X1525930Y190131D01*
Y194086D01*
X1531069Y199225D01*
Y205970D01*
X1554061Y228962D01*
Y252358D01*
X1559975Y258272D01*
Y277002D01*
X1566493Y283520D01*
Y287203D01*
X1571744Y292454D01*
Y298945D01*
X1572621Y299822D01*
Y303701D01*
X1574196Y305276D01*
Y310107D01*
X1574338Y310249D01*
Y315287D01*
X1573117Y316508D01*
Y326982D01*
X1575318Y329183D01*
Y332734D01*
X1578362Y335778D01*
Y350139D01*
X1580034Y351811D01*
Y361577D01*
X1584170Y365713D01*
Y390330D01*
X1582700Y391800D01*
Y394500D01*
X1583700Y395500D01*
Y396588D01*
X1583470Y396818D01*
Y404679D01*
X1583208Y404941D01*
G01X1808100Y21800D02*
X1808048Y21852D01*
X1805778D01*
X1804438Y23192D01*
Y23810D01*
X1800448Y27800D01*
X1794611D01*
X1792153Y25342D01*
X1792142D01*
X1791952Y25152D01*
X1790728D01*
X1781975Y33905D01*
X1775638D01*
X1755141Y54402D01*
X1731475D01*
X1725445Y60432D01*
X1700615D01*
X1699874Y61173D01*
X1654442D01*
X1644877Y51608D01*
X1584186D01*
X1577475Y58319D01*
X1575107D01*
X1575106Y58318D01*
X1506901D01*
X1493888Y71331D01*
Y73454D01*
X1478661Y88681D01*
Y133276D01*
X1486532Y141147D01*
Y163681D01*
X1491021Y168170D01*
Y173289D01*
X1491944Y174212D01*
X1493250D01*
X1494185Y173277D01*
X1497366D01*
X1499600Y175511D01*
Y177004D01*
X1510480Y187884D01*
X1520423D01*
X1523082Y190543D01*
Y194498D01*
X1527467Y198883D01*
Y205628D01*
X1551757Y229918D01*
Y253314D01*
X1557671Y259228D01*
Y277958D01*
X1563425Y283712D01*
Y284500D01*
X1563424Y284501D01*
Y293917D01*
X1570317Y300810D01*
Y304657D01*
X1571800Y306140D01*
Y310971D01*
X1572034Y311205D01*
Y314331D01*
X1570813Y315552D01*
Y327938D01*
X1572891Y330016D01*
Y334670D01*
X1575526Y337305D01*
Y355842D01*
X1574298Y357070D01*
Y363737D01*
X1580430Y369869D01*
Y404384D01*
X1583846Y407800D01*
X1585265D01*
X1589500Y412035D01*
G01X1473354Y153246D02*
Y167146D01*
X1468660Y171840D01*
Y175295D01*
X1474883Y181518D01*
Y182275D01*
G01X1475200Y142600D02*
Y146985D01*
X1478337Y150122D01*
Y169102D01*
X1479938Y170703D01*
Y183782D01*
X1488994Y192838D01*
X1500880D01*
X1506298Y198256D01*
X1514690D01*
X1518800Y202366D01*
Y209383D01*
X1526877Y217460D01*
Y228177D01*
X1530165Y231465D01*
Y240703D01*
X1534716Y245254D01*
Y272278D01*
X1540123Y277685D01*
Y313877D01*
X1545438Y319192D01*
Y325522D01*
X1537100Y333860D01*
Y340200D01*
X1540100Y343200D01*
Y369600D01*
X1544400Y373900D01*
Y378998D01*
X1546405Y381003D01*
Y382005D01*
X1547595Y383195D01*
Y384595D01*
X1550100Y387100D01*
Y388600D01*
X1551800Y390300D01*
Y394339D01*
X1551875Y394414D01*
G01X1473200Y118300D02*
X1470550Y120950D01*
Y128912D01*
X1470166Y129296D01*
Y135337D01*
X1479089Y144260D01*
Y168790D01*
X1480690Y170391D01*
Y183470D01*
X1489306Y192086D01*
X1501192D01*
X1506610Y197504D01*
X1515002D01*
X1519552Y202054D01*
Y209071D01*
X1533913Y223432D01*
Y239300D01*
X1535468Y240855D01*
Y271966D01*
X1540875Y277373D01*
Y313565D01*
X1546300Y318990D01*
Y320421D01*
X1548024Y322145D01*
G01X1472500Y123700D02*
X1474800Y126000D01*
Y135081D01*
X1482545Y142826D01*
Y167356D01*
X1484600Y169411D01*
Y177013D01*
X1486687Y179100D01*
Y181427D01*
X1493890Y188630D01*
X1502626D01*
X1505496Y191500D01*
X1511504D01*
X1514023Y194019D01*
X1516407D01*
X1523007Y200619D01*
Y200686D01*
X1523008Y200687D01*
Y207637D01*
X1540010Y224639D01*
Y239888D01*
X1538924Y240974D01*
Y245876D01*
X1554025Y260977D01*
Y276865D01*
X1551002Y279888D01*
Y288159D01*
X1548906Y290255D01*
Y309832D01*
X1554166Y315092D01*
Y322583D01*
X1548000Y328749D01*
Y331361D01*
G01X1547882Y318942D02*
X1542027Y313087D01*
Y277461D01*
X1536220Y271654D01*
Y240543D01*
X1534665Y238988D01*
Y222554D01*
X1520704Y208593D01*
Y201576D01*
X1515480Y196352D01*
X1507088D01*
X1501670Y190934D01*
X1489784D01*
X1481842Y182992D01*
Y170869D01*
X1481843Y170868D01*
Y169914D01*
X1480241Y168312D01*
Y143782D01*
X1471318Y134859D01*
Y129862D01*
X1472230Y128950D01*
X1473100D01*
G01X1512500Y199837D02*
X1505237D01*
X1499100Y193700D01*
X1486627D01*
X1476459Y183532D01*
Y181060D01*
X1469812Y174413D01*
Y172388D01*
X1474930Y167270D01*
Y148440D01*
X1467465Y140975D01*
Y132374D01*
X1467014Y131923D01*
Y130219D01*
X1468755Y128478D01*
G01X1571375Y436786D02*
X1567855Y433266D01*
Y430943D01*
X1569045Y429753D01*
Y427563D01*
X1567855Y426373D01*
Y424183D01*
X1569045Y422993D01*
Y420803D01*
X1567855Y419613D01*
Y417423D01*
X1569579Y415699D01*
Y413381D01*
X1573032Y409928D01*
Y405385D01*
X1569045Y401398D01*
Y400523D01*
X1567855Y399333D01*
Y397143D01*
X1569045Y395953D01*
Y393763D01*
X1567855Y392573D01*
Y390383D01*
X1569045Y389193D01*
Y387003D01*
X1568719Y386677D01*
Y382759D01*
X1569045Y382433D01*
Y379684D01*
X1568014Y378653D01*
Y376719D01*
X1564838Y373543D01*
X1562375D01*
X1555014Y366182D01*
Y360520D01*
X1563627Y351907D01*
Y348450D01*
X1561423Y346246D01*
X1557717D01*
X1553224Y341753D01*
Y329204D01*
X1558826Y323602D01*
Y314096D01*
X1557172Y312442D01*
Y281500D01*
X1554777Y279105D01*
Y260375D01*
X1544476Y250074D01*
Y245103D01*
X1541002Y241629D01*
Y223204D01*
X1524610Y206812D01*
Y200067D01*
X1520225Y195682D01*
Y195071D01*
X1515894Y190740D01*
X1508681D01*
X1508680Y190741D01*
X1507102D01*
X1507101Y190740D01*
X1506664D01*
X1503102Y187178D01*
X1494849D01*
X1489079Y181408D01*
X1488362D01*
X1487439Y180485D01*
Y179179D01*
X1487500Y179118D01*
Y176056D01*
X1487457D01*
X1485420Y174019D01*
Y167019D01*
X1483676Y165275D01*
Y142332D01*
X1475805Y134461D01*
Y123708D01*
X1473096Y120999D01*
G01X1473100Y131900D02*
X1472508Y132492D01*
Y134419D01*
X1481393Y143304D01*
Y167834D01*
X1483448Y169889D01*
Y173322D01*
X1483447Y173323D01*
Y174277D01*
X1483448Y174278D01*
Y177491D01*
X1485500Y179543D01*
Y181899D01*
X1493383Y189782D01*
X1502148D01*
X1507566Y195200D01*
X1515958D01*
X1521856Y201098D01*
Y208115D01*
X1535817Y222076D01*
Y238510D01*
X1537772Y240465D01*
Y246354D01*
X1552873Y261455D01*
Y276387D01*
X1549850Y279410D01*
Y287681D01*
X1547729Y289802D01*
Y310285D01*
X1553014Y315570D01*
Y322086D01*
X1549603Y325497D01*
X1548334D01*
G01X1482455Y124222D02*
X1481517Y125160D01*
Y132067D01*
X1482711Y133261D01*
X1485863D01*
X1487480Y134878D01*
Y136612D01*
X1494435Y143567D01*
Y149363D01*
X1493500Y150298D01*
Y151036D01*
X1494645Y152181D01*
Y153487D01*
X1494633Y153499D01*
Y153501D01*
X1493965Y154169D01*
Y155718D01*
X1498271Y160024D01*
X1498353D01*
X1499276Y160947D01*
Y162253D01*
X1499069Y162460D01*
Y162731D01*
X1498955Y162845D01*
Y164956D01*
X1501775Y167776D01*
X1506323D01*
X1506324Y167775D01*
X1507705D01*
X1529004Y189074D01*
Y193119D01*
X1533925Y198040D01*
Y201051D01*
X1556917Y224043D01*
Y239115D01*
X1560669Y242867D01*
X1568475D01*
X1576242Y250634D01*
Y276422D01*
X1583990Y284170D01*
Y297500D01*
X1581700Y299790D01*
Y304200D01*
X1582700Y305200D01*
Y309625D01*
X1587405Y314330D01*
Y332962D01*
X1594919Y340476D01*
Y362387D01*
X1589968Y367338D01*
Y391368D01*
X1591749Y393149D01*
Y401849D01*
X1595800Y405900D01*
G01X1511100Y186275D02*
X1512743Y184632D01*
X1518801D01*
X1524234Y190065D01*
Y194020D01*
X1528619Y198405D01*
Y205150D01*
X1552909Y229440D01*
Y252836D01*
X1558823Y258750D01*
Y277480D01*
X1565340Y283997D01*
Y287680D01*
X1567170Y289510D01*
Y296033D01*
X1571469Y300332D01*
Y304179D01*
X1573044Y305754D01*
Y310585D01*
X1573186Y310727D01*
Y314809D01*
X1571965Y316030D01*
Y327460D01*
X1574043Y329538D01*
Y333089D01*
X1576765Y335811D01*
Y350395D01*
X1578065Y351695D01*
Y362013D01*
X1581822Y365770D01*
G01X1511100Y186275D02*
Y185331D01*
X1497847Y172078D01*
X1493155D01*
X1492597Y172636D01*
G01X1492136Y199125D02*
X1494385D01*
X1498992Y203732D01*
X1500667D01*
X1511431Y214496D01*
X1514255D01*
X1516628Y216869D01*
Y230331D01*
X1514958Y232001D01*
Y235610D01*
X1518600Y239252D01*
Y241200D01*
X1519300Y241900D01*
Y245196D01*
G01X1493200Y162700D02*
X1507048Y176548D01*
X1513694D01*
X1526882Y189736D01*
Y193691D01*
X1532021Y198830D01*
Y201841D01*
X1555013Y224833D01*
Y251963D01*
X1560927Y257877D01*
Y276176D01*
X1567445Y282694D01*
Y283125D01*
X1567446Y283126D01*
Y283914D01*
X1567445Y283915D01*
Y286808D01*
X1572696Y292059D01*
Y298396D01*
X1574020Y299720D01*
Y303753D01*
X1575148Y304881D01*
Y309712D01*
X1575290Y309854D01*
Y315682D01*
X1574069Y316903D01*
Y326587D01*
X1576270Y328788D01*
Y331243D01*
X1583794Y338767D01*
G01X1538200Y364700D02*
X1536700Y363200D01*
Y346200D01*
X1535900Y345400D01*
Y322432D01*
X1534840Y321372D01*
Y312683D01*
X1531243Y309086D01*
Y302657D01*
X1536500Y297400D01*
Y294300D01*
X1532700Y290500D01*
X1529000D01*
X1525226Y286726D01*
Y281914D01*
X1521962Y278650D01*
G01X1507003Y272249D02*
X1506817Y272435D01*
Y289526D01*
X1507922Y290631D01*
Y300964D01*
X1509024Y302066D01*
Y310149D01*
X1506879Y312294D01*
Y313694D01*
X1511653Y318468D01*
Y319090D01*
X1511652Y319091D01*
Y323752D01*
X1512790Y324890D01*
X1517360D01*
X1519452Y326982D01*
Y338428D01*
X1519303Y338577D01*
Y338735D01*
X1515321Y342717D01*
Y352232D01*
X1520158Y357069D01*
X1520313D01*
G01X1499559Y231173D02*
X1500196Y231810D01*
Y234712D01*
X1497610Y237298D01*
Y244791D01*
X1497584Y244817D01*
Y244868D01*
X1494336Y248116D01*
Y252286D01*
X1497363Y255313D01*
Y259602D01*
X1502672Y264911D01*
Y275100D01*
X1504813Y277241D01*
Y301504D01*
X1503000Y303317D01*
Y313320D01*
X1507090Y317410D01*
Y328250D01*
X1504370Y330970D01*
G01X1559595Y450631D02*
X1559295Y450331D01*
Y445995D01*
X1558105Y444805D01*
Y442595D01*
X1559295Y441405D01*
Y439195D01*
X1558100Y438000D01*
Y434138D01*
X1555710Y431748D01*
Y430460D01*
X1553690Y428440D01*
Y427340D01*
X1552100Y425750D01*
Y423920D01*
X1553610Y422410D01*
Y420136D01*
X1550200Y416726D01*
Y415000D01*
X1547200Y412000D01*
Y409441D01*
X1546879Y409120D01*
Y407087D01*
X1545916Y406124D01*
X1545374D01*
X1544455Y405205D01*
Y404663D01*
X1542776Y402984D01*
X1537574D01*
X1537498Y403060D01*
X1535940D01*
X1534380Y401500D01*
Y400958D01*
X1532785Y399363D01*
G01X1526896Y388333D02*
Y386124D01*
X1528095Y384925D01*
Y383623D01*
X1527176Y382704D01*
X1524164D01*
X1522500Y381040D01*
Y380100D01*
X1521000Y378600D01*
Y376800D01*
X1510400Y366200D01*
Y355910D01*
X1514252Y352058D01*
Y342564D01*
X1518700Y338116D01*
Y327340D01*
X1517090Y325730D01*
X1512510D01*
X1510900Y324120D01*
Y318779D01*
X1506127Y314006D01*
Y311898D01*
X1508252Y309773D01*
Y302358D01*
X1507170Y301276D01*
Y290943D01*
X1506065Y289838D01*
Y273558D01*
X1505410Y272903D01*
Y265878D01*
X1500192Y260660D01*
Y257056D01*
X1499070Y255934D01*
G01X1479000Y254500D02*
Y266323D01*
X1478628Y266695D01*
Y267913D01*
X1479489Y268774D01*
X1481567D01*
X1483247Y270454D01*
G01X1514100Y321792D02*
Y317960D01*
X1518658Y313402D01*
Y294400D01*
X1518656Y294398D01*
Y292146D01*
X1518657Y292145D01*
Y290899D01*
X1515629Y287871D01*
Y286747D01*
X1510625Y281743D01*
Y279417D01*
X1511842Y278200D01*
Y257621D01*
X1506796Y252575D01*
Y242217D01*
X1509050Y239963D01*
Y220126D01*
X1507524Y218600D01*
G01X1495810Y341200D02*
Y345269D01*
X1493452Y347627D01*
Y364452D01*
X1501270Y372270D01*
Y378392D01*
X1503000Y380122D01*
Y381500D01*
X1501500Y383000D01*
X1500499D01*
X1499225Y384274D01*
G01X1503538Y318068D02*
X1495092D01*
X1489800Y323360D01*
Y330500D01*
X1487000Y333300D01*
G01X1499225Y377514D02*
X1488760Y367049D01*
X1484172D01*
X1484151Y367070D01*
X1482849D01*
X1481800Y366021D01*
Y353599D01*
X1477200Y348999D01*
Y326440D01*
X1471661Y320901D01*
Y319743D01*
X1467323Y315405D01*
G01X1500840Y319870D02*
X1500520Y320190D01*
Y330560D01*
X1503245Y333285D01*
X1508915D01*
X1509910Y334280D01*
Y337510D01*
X1508150Y339270D01*
Y345430D01*
X1502970Y350610D01*
G01X1492540Y328250D02*
X1496240Y331950D01*
X1498750D01*
X1503177Y336377D01*
Y342470D01*
X1500330Y345317D01*
Y355421D01*
X1498246Y357505D01*
G01X1487904Y337500D02*
X1489019Y338615D01*
Y338651D01*
X1489838Y339470D01*
Y350011D01*
G01X1483740Y359550D02*
X1483973D01*
X1485924Y357599D01*
Y355306D01*
X1486655Y354575D01*
Y348346D01*
X1480058Y341749D01*
Y323568D01*
X1483111Y320515D01*
X1486780D01*
X1488000Y319295D01*
Y312943D01*
X1489546Y311397D01*
G01X1487525Y480726D02*
Y476187D01*
X1489095Y474617D01*
Y473656D01*
X1491243Y471508D01*
Y469626D01*
X1489866Y468249D01*
Y468248D01*
X1489601Y467983D01*
Y466360D01*
X1491194Y464767D01*
Y462588D01*
X1489528Y460922D01*
Y459861D01*
X1487307Y457640D01*
Y456384D01*
X1489095Y454596D01*
Y452452D01*
X1487571Y450928D01*
Y447041D01*
X1489496Y445116D01*
X1490126D01*
X1491045Y444197D01*
Y442895D01*
X1489095Y440945D01*
Y439515D01*
X1486943Y437363D01*
Y426836D01*
X1487609Y426170D01*
X1488151D01*
X1489070Y425251D01*
Y423657D01*
X1489703Y423024D01*
X1494026D01*
X1494945Y422105D01*
Y420675D01*
X1499000Y416620D01*
Y413600D01*
X1497400Y412000D01*
Y410300D01*
X1498948Y408752D01*
Y406749D01*
X1495000Y402801D01*
Y401000D01*
X1496500Y399500D01*
X1502000D01*
X1502514Y400014D01*
X1504014D01*
X1504695Y399333D01*
Y397095D01*
X1503505Y395905D01*
Y393763D01*
X1504695Y392573D01*
Y390383D01*
X1503776Y389464D01*
Y388576D01*
X1503505Y388305D01*
Y387505D01*
X1502000Y386000D01*
X1497247D01*
X1496895Y385648D01*
Y382763D01*
X1495705Y381573D01*
Y380243D01*
X1496895Y379053D01*
Y376863D01*
X1488148Y368116D01*
X1482616D01*
X1481028Y366528D01*
Y354227D01*
X1476400Y349599D01*
Y326704D01*
X1472696Y323000D01*
X1471328D01*
X1470257Y321929D01*
G01X1483664Y362914D02*
X1483659D01*
Y362464D01*
X1486676Y359447D01*
Y356215D01*
X1487786Y355105D01*
Y348336D01*
X1480810Y341360D01*
Y323880D01*
X1483423Y321267D01*
X1488750D01*
X1491100Y318917D01*
Y312976D01*
X1492700Y311376D01*
G01X1476948Y286202D02*
Y287272D01*
X1478546Y288870D01*
Y299279D01*
X1478419Y299406D01*
Y314581D01*
X1476886Y316114D01*
Y320317D01*
X1478649Y322080D01*
Y342696D01*
X1485593Y349640D01*
Y353895D01*
X1483867Y355621D01*
Y356753D01*
G01X1524575Y387654D02*
X1523267Y386346D01*
X1522246D01*
X1520400Y384500D01*
Y383000D01*
X1518400Y381000D01*
Y379500D01*
X1516400Y377500D01*
Y374439D01*
X1509200Y367239D01*
Y355540D01*
X1513030Y351710D01*
Y342320D01*
X1516578Y338772D01*
Y330542D01*
X1517115Y330005D01*
G01X1507200Y358700D02*
X1502286Y363614D01*
Y366928D01*
X1509562Y374204D01*
X1511204D01*
X1512875Y375875D01*
Y377579D01*
G02X1513850Y379204I1950J-65D01*
G03X1514825Y380829I-975J1690D01*
G01Y380959D01*
G02X1515800Y382584I1950J-65D01*
G03X1516775Y384209I-975J1690D01*
G01Y384339D01*
G02X1517750Y385964I1950J-65D01*
G03X1518725Y387589I-975J1690D01*
G01Y387719D01*
G02X1520027Y389494I1950J-65D01*
G01X1482958Y486118D02*
X1486676Y482400D01*
X1535300D01*
X1536655Y481045D01*
Y480075D01*
X1537000Y479730D01*
Y479100D01*
X1538500Y477600D01*
Y476500D01*
X1540175Y474825D01*
Y470586D01*
G01X1835600Y3900D02*
Y1864D01*
X1831298Y-2438D01*
Y-5002D01*
X1825620Y-10680D01*
X1825073D01*
X1825072Y-10681D01*
X1823494D01*
X1823493Y-10680D01*
X1767378D01*
X1763648Y-6950D01*
Y-4248D01*
X1754138Y5262D01*
X1679662D01*
X1678458Y4058D01*
Y3158D01*
X1667996Y-7304D01*
X1643000D01*
X1636396Y-700D01*
X1604500D01*
X1602400Y-2800D01*
X1578148D01*
X1571948Y3400D01*
X1569000D01*
G01X1573076Y75328D02*
X1572280Y74532D01*
Y68902D01*
X1585766Y55416D01*
X1642518D01*
X1648948Y61846D01*
Y64449D01*
X1648276Y65121D01*
Y65221D01*
G01X1570511Y75396D02*
X1571328Y74579D01*
Y68790D01*
X1585454Y54664D01*
X1642830D01*
X1649900Y61734D01*
Y64161D01*
X1650876Y65137D01*
Y65237D01*
G01X1593241Y134295D02*
Y132905D01*
X1591527Y131191D01*
Y120689D01*
X1587868Y117030D01*
Y109852D01*
X1592845Y104875D01*
Y92144D01*
X1591476Y90775D01*
Y83400D01*
X1588258Y80182D01*
Y79242D01*
X1587386Y78370D01*
Y73859D01*
X1592004Y69241D01*
X1593159D01*
X1593700Y68700D01*
X1615870D01*
X1619281Y72111D01*
X1623103D01*
X1625075Y74083D01*
Y80182D01*
G01X1579290Y131104D02*
X1581055Y129339D01*
Y118657D01*
X1576300Y113902D01*
Y108566D01*
X1579550Y105316D01*
Y103857D01*
X1575119Y99426D01*
Y95119D01*
X1578566Y91672D01*
Y79682D01*
X1582407Y75841D01*
G01X1579310Y128604D02*
X1580000Y127914D01*
Y118949D01*
X1575502Y114451D01*
Y108017D01*
X1578798Y104721D01*
Y104169D01*
X1574315Y99686D01*
Y94859D01*
X1577814Y91360D01*
Y79370D01*
X1579807Y77377D01*
Y75841D01*
G01X1594565Y148720D02*
Y144098D01*
X1596082Y142581D01*
Y130090D01*
X1597336Y128836D01*
Y121875D01*
X1591463Y116002D01*
Y107865D01*
X1593600Y105728D01*
Y91500D01*
X1592393Y90293D01*
Y83253D01*
X1589109Y79969D01*
Y79029D01*
X1588138Y78058D01*
Y76750D01*
X1588962Y75926D01*
G01X1587620Y135921D02*
X1587251Y136290D01*
Y153068D01*
X1586436Y153883D01*
Y158635D01*
X1590451Y162650D01*
X1593950D01*
X1597203Y165903D01*
Y168600D01*
X1599308Y170705D01*
X1601805D01*
X1603256Y172156D01*
Y175644D01*
X1606956Y179344D01*
X1609944D01*
X1612250Y181650D01*
X1615750D01*
X1617332Y180068D01*
X1619568D01*
X1620600Y181100D01*
X1630715D01*
X1633197Y178618D01*
X1637118D01*
X1639324Y180824D01*
X1640614D01*
X1643290Y183500D01*
X1644800D01*
X1646418Y185118D01*
Y186678D01*
X1649353Y189613D01*
X1651202D01*
X1653212Y191623D01*
Y200011D01*
X1661400Y208199D01*
Y214592D01*
X1669269Y222461D01*
Y236069D01*
X1669268Y236070D01*
Y237940D01*
X1671976Y240648D01*
Y248846D01*
X1675705Y252575D01*
Y259262D01*
X1669359Y265608D01*
Y310812D01*
X1669360Y310813D01*
Y311739D01*
X1671885Y314264D01*
Y438802D01*
X1678887Y445804D01*
X1682404D01*
X1688408Y451808D01*
Y461492D01*
X1694743Y467827D01*
X1704572D01*
X1717442Y454957D01*
X1726373D01*
X1728700Y452630D01*
Y451050D01*
X1736112Y443638D01*
X1847239D01*
X1857980Y454379D01*
X1861468D01*
X1863137Y452710D01*
G01X1859059Y448076D02*
X1853805D01*
X1847799Y442070D01*
X1735430D01*
X1729746Y447754D01*
X1722246D01*
X1703677Y466323D01*
X1695607D01*
X1690200Y460916D01*
Y450772D01*
X1673389Y433961D01*
Y313640D01*
X1670864Y311115D01*
Y310189D01*
X1670863Y310188D01*
Y304744D01*
X1670864Y304743D01*
Y266231D01*
X1677209Y259886D01*
Y251951D01*
X1673480Y248222D01*
Y240024D01*
X1670773Y237317D01*
Y214074D01*
X1654971Y198272D01*
Y191254D01*
X1651635Y187918D01*
X1649989D01*
X1648100Y186029D01*
Y184628D01*
X1646501Y183029D01*
Y181158D01*
X1644665Y179322D01*
X1640187D01*
X1637800Y176935D01*
X1632267D01*
X1630817Y178385D01*
Y178386D01*
X1629684Y179519D01*
X1621197D01*
X1620207Y178529D01*
X1616669D01*
X1615074Y180124D01*
X1612850D01*
X1610568Y177842D01*
X1607977D01*
X1604758Y174623D01*
Y171532D01*
X1602423Y169197D01*
X1599926D01*
X1598705Y167976D01*
Y165279D01*
X1594571Y161145D01*
X1592411D01*
X1590404Y159138D01*
Y156509D01*
X1592045Y154868D01*
Y145555D01*
X1595331Y142269D01*
Y137206D01*
X1594322Y136197D01*
X1592375D01*
X1591666Y135488D01*
Y134239D01*
X1590775Y133348D01*
Y121000D01*
X1586500Y116725D01*
Y113900D01*
X1582500Y109900D01*
G01X1858633Y452803D02*
X1857468D01*
X1847551Y442886D01*
X1735800D01*
X1727833Y450853D01*
Y452433D01*
X1726061Y454205D01*
X1716859D01*
X1703989Y467075D01*
X1695295D01*
X1689448Y461228D01*
Y451084D01*
X1672637Y434273D01*
Y313952D01*
X1670112Y311427D01*
Y310501D01*
X1670111Y310500D01*
Y304432D01*
X1670112Y304431D01*
Y265919D01*
X1676457Y259574D01*
Y252263D01*
X1672728Y248534D01*
Y240336D01*
X1670021Y237629D01*
Y221861D01*
X1665373Y217213D01*
Y210826D01*
X1653964Y199417D01*
Y191311D01*
X1651323Y188670D01*
X1649677D01*
X1647244Y186237D01*
Y184836D01*
X1645749Y183341D01*
Y181470D01*
X1644352Y180073D01*
X1639875D01*
X1637488Y177686D01*
X1632580D01*
X1629995Y180271D01*
X1620886D01*
X1619895Y179280D01*
X1617005D01*
X1615386Y180899D01*
X1612562D01*
X1610256Y178593D01*
X1607492D01*
X1604007Y175108D01*
Y171844D01*
X1602111Y169948D01*
X1599614D01*
X1597954Y168288D01*
Y165591D01*
X1594260Y161897D01*
X1592046D01*
X1589652Y159503D01*
Y156988D01*
X1588052Y155388D01*
Y138012D01*
X1589355Y136709D01*
Y135376D01*
X1589880Y134851D01*
G01X1582699Y252646D02*
X1581553Y251500D01*
X1578172D01*
X1568455Y241783D01*
X1564612D01*
X1563000Y240171D01*
Y235859D01*
X1561396Y234255D01*
X1561104D01*
G01X1587683Y397414D02*
Y397083D01*
X1584300Y393700D01*
Y392600D01*
X1586568Y390332D01*
Y366697D01*
X1591794Y361471D01*
Y341392D01*
X1584444Y334042D01*
Y329744D01*
X1579106Y324406D01*
Y311544D01*
X1579105Y311543D01*
Y310589D01*
X1579844Y309850D01*
Y306385D01*
X1577903Y304444D01*
Y300985D01*
X1577904Y300984D01*
Y298793D01*
X1575476Y296365D01*
Y283907D01*
X1567198Y275629D01*
Y259758D01*
X1567000Y259560D01*
G01X1563157Y258164D02*
X1562500Y258821D01*
Y276685D01*
X1568213Y282398D01*
Y286512D01*
X1573448Y291747D01*
Y297208D01*
X1575450Y299210D01*
Y304119D01*
X1575900Y304569D01*
Y309099D01*
X1577601Y310800D01*
Y330345D01*
X1585370Y338114D01*
Y340830D01*
X1583512Y342688D01*
X1581760D01*
X1580365Y341293D01*
G01X1568120Y251710D02*
Y252008D01*
X1565400Y254728D01*
Y260400D01*
X1563500Y262300D01*
Y276621D01*
X1568965Y282086D01*
Y286200D01*
X1574200Y291435D01*
Y296389D01*
X1576430Y298619D01*
Y304035D01*
X1579092Y306697D01*
Y309538D01*
X1578353Y310277D01*
Y325079D01*
X1582908Y329634D01*
Y333892D01*
X1586122Y337106D01*
Y345508D01*
X1584924Y346706D01*
Y364023D01*
X1585150Y364249D01*
Y390450D01*
X1583500Y392100D01*
Y394200D01*
X1585150Y395850D01*
Y397400D01*
G01X1561719Y375389D02*
X1553356Y367026D01*
Y360050D01*
X1562123Y351283D01*
Y349074D01*
X1560799Y347750D01*
X1555880D01*
X1550951Y342821D01*
Y329349D01*
X1554918Y325382D01*
Y307386D01*
X1550619Y303087D01*
G01X1559997Y310317D02*
Y326631D01*
X1558448Y328180D01*
Y338853D01*
X1559267Y339672D01*
Y343026D01*
X1564379Y348138D01*
Y352219D01*
X1555766Y360832D01*
Y365871D01*
X1562397Y372502D01*
X1566305D01*
X1573155Y379352D01*
Y388695D01*
X1571430Y390420D01*
Y392248D01*
X1573784Y394602D01*
Y436598D01*
X1571786Y438596D01*
X1564874D01*
X1563955Y439515D01*
Y443499D01*
G01X1533589Y366361D02*
X1535566Y364384D01*
Y363696D01*
X1535548Y363678D01*
Y349993D01*
X1534100Y348545D01*
Y329100D01*
X1531500Y326500D01*
Y323660D01*
X1533280Y321880D01*
Y312753D01*
X1529739Y309212D01*
Y300690D01*
X1534400Y296029D01*
G01X1542200Y324600D02*
X1541080D01*
X1536760Y320280D01*
Y309223D01*
X1532850Y305307D01*
Y303950D01*
G01X1583773Y436137D02*
X1585741Y434169D01*
X1590612D01*
X1591824Y432957D01*
Y414634D01*
X1592980Y413478D01*
Y412620D01*
X1594000Y411600D01*
Y405359D01*
X1590997Y402356D01*
Y393497D01*
X1588788Y391288D01*
Y367454D01*
X1594167Y362075D01*
Y340788D01*
X1586548Y333169D01*
Y319908D01*
X1583903Y317263D01*
Y315957D01*
X1581224Y313278D01*
Y311447D01*
X1581948Y310723D01*
Y305512D01*
X1580008Y303572D01*
Y295017D01*
X1581266Y293759D01*
Y289266D01*
X1578572Y286572D01*
Y284804D01*
X1578577Y284799D01*
G01X1565244Y300934D02*
X1566811Y302501D01*
Y304387D01*
X1566046Y305152D01*
Y311824D01*
X1564590Y313280D01*
X1564010D01*
X1562835Y314455D01*
Y319137D01*
X1566948Y323250D01*
Y337651D01*
X1568702Y339405D01*
Y354798D01*
X1564755Y358745D01*
Y365845D01*
X1567456Y368546D01*
X1568690D01*
X1577775Y377631D01*
Y415528D01*
X1578999Y416752D01*
X1583208D01*
G01X1587238Y432593D02*
Y426338D01*
X1576823Y415923D01*
Y378026D01*
X1568295Y369498D01*
X1567061D01*
X1563803Y366240D01*
Y358350D01*
X1567750Y354403D01*
Y339800D01*
X1566000Y338050D01*
Y323366D01*
X1562083Y319449D01*
Y314143D01*
X1562790Y313436D01*
Y307150D01*
X1565235Y304705D01*
Y303734D01*
G01X1559800Y285300D02*
X1557924Y287176D01*
Y302978D01*
X1561976Y307030D01*
Y313186D01*
X1561331Y313831D01*
Y319761D01*
X1561976Y320406D01*
Y333571D01*
X1561424Y334123D01*
Y342489D01*
X1565131Y346196D01*
Y354939D01*
X1563051Y357019D01*
Y366551D01*
X1566749Y370249D01*
X1567241D01*
X1576072Y379080D01*
Y439156D01*
X1573900Y441328D01*
Y443242D01*
X1571401Y445741D01*
X1570610D01*
X1569425Y446926D01*
G01X1584568Y281339D02*
X1585585Y282356D01*
Y297804D01*
X1585200Y298189D01*
Y310778D01*
X1588357Y313935D01*
Y321834D01*
X1589476Y322953D01*
G01X1542932Y355740D02*
X1542834D01*
Y355210D01*
X1540900Y353276D01*
Y331872D01*
X1546758Y326014D01*
Y324844D01*
X1547681Y323921D01*
X1548851D01*
X1549664Y323108D01*
Y319500D01*
X1550700Y318464D01*
Y315654D01*
X1548273Y313227D01*
G01X1546612Y287812D02*
X1546550D01*
Y287873D01*
X1543900Y290523D01*
Y311363D01*
X1543864Y311399D01*
G01X1567475Y436786D02*
X1563955Y433266D01*
Y430391D01*
X1565527Y428819D01*
Y427053D01*
X1567095Y425485D01*
Y424183D01*
X1565905Y422993D01*
Y420938D01*
X1563620Y418653D01*
Y417528D01*
X1561680Y415588D01*
Y413480D01*
X1563332Y411828D01*
Y410921D01*
X1565360Y408893D01*
Y400180D01*
X1567095Y398445D01*
Y397143D01*
X1565905Y395953D01*
Y392875D01*
X1567095Y391685D01*
Y390383D01*
X1565905Y389193D01*
Y386115D01*
X1567095Y384925D01*
Y383623D01*
X1565905Y382433D01*
Y379847D01*
X1567095Y378657D01*
Y376863D01*
X1564632Y374400D01*
X1562169D01*
X1554262Y366493D01*
Y361103D01*
X1554261Y361102D01*
Y360209D01*
X1562875Y351595D01*
Y348762D01*
X1561111Y346998D01*
X1557405D01*
X1552472Y342065D01*
Y328892D01*
X1555670Y325694D01*
Y296223D01*
X1554775Y295328D01*
G01X1557534Y353400D02*
X1557460Y353326D01*
X1554297D01*
X1548700Y358923D01*
Y369075D01*
X1553825Y374200D01*
Y377514D01*
G01X1543300Y360900D02*
X1545506Y363106D01*
Y369959D01*
X1548346Y372799D01*
Y378284D01*
X1549554Y379492D01*
Y381682D01*
X1551495Y383623D01*
Y385053D01*
X1553825Y387383D01*
Y391034D01*
G01X1532367Y356530D02*
X1531635Y357262D01*
Y366935D01*
X1540500Y375800D01*
Y377700D01*
X1541900Y379100D01*
Y381100D01*
X1544100Y383300D01*
Y385100D01*
X1546000Y387000D01*
Y391009D01*
X1546025Y391034D01*
G01X1558950Y363050D02*
X1560810Y364910D01*
Y365373D01*
X1566437Y371000D01*
X1566929D01*
X1575321Y379392D01*
Y437187D01*
X1570532Y441976D01*
X1566824D01*
X1565905Y442895D01*
Y444197D01*
X1567095Y445387D01*
Y448465D01*
X1565525Y450035D01*
Y453686D01*
G01X1558980Y360130D02*
X1557174Y361936D01*
Y366216D01*
X1562709Y371751D01*
X1566617D01*
X1574570Y379704D01*
Y436875D01*
X1571279Y440166D01*
X1569425D01*
G01X1545200Y585724D02*
X1544376Y584900D01*
Y584402D01*
X1544928Y583850D01*
X1555000D01*
X1561400Y590250D01*
X1573600D01*
X1577150Y593800D01*
X1590353D01*
X1596498Y599945D01*
Y602698D01*
X1599450Y605650D01*
Y613146D01*
X1601800Y615496D01*
Y617400D01*
X1600950Y618250D01*
G01X1542600Y585724D02*
X1543424Y584900D01*
Y584007D01*
X1544533Y582898D01*
X1555395D01*
X1561795Y589298D01*
X1573995D01*
X1577545Y592848D01*
X1590748D01*
X1597450Y599550D01*
Y602303D01*
X1600402Y605255D01*
Y612751D01*
X1602752Y615101D01*
Y617452D01*
X1603550Y618250D01*
G01X1540477Y620308D02*
X1540715Y620546D01*
X1547202D01*
X1550948Y616800D01*
X1578200D01*
X1581500Y620100D01*
X1586700D01*
G01X1570660Y601563D02*
X1574317Y597906D01*
X1582188D01*
X1583282Y599000D01*
X1590800D01*
X1598040Y606240D01*
Y618600D01*
X1599466Y620026D01*
X1604286D01*
X1605326Y618986D01*
Y617514D01*
X1604191Y616379D01*
Y611417D01*
X1608325Y607283D01*
X1621726D01*
X1624009Y605000D01*
X1638743D01*
X1640185Y603558D01*
X1641657D01*
X1643029Y604930D01*
X1644856D01*
G01X1573260Y601600D02*
X1575440Y599420D01*
X1581308D01*
X1582688Y600800D01*
X1590608D01*
X1596632Y606824D01*
Y620424D01*
X1597642Y621434D01*
X1613454D01*
X1617400Y617488D01*
Y613800D01*
X1624400Y606800D01*
X1639455D01*
X1640921Y605334D01*
G01X1660800Y181900D02*
Y180500D01*
X1650764Y170464D01*
X1631374D01*
X1631170Y170260D01*
X1620706D01*
X1620494Y170472D01*
X1619271D01*
X1617099Y168300D01*
X1609790D01*
X1603600Y162110D01*
Y157970D01*
X1602552Y156922D01*
Y152736D01*
X1602775Y152513D01*
Y152187D01*
X1602777Y152185D01*
Y141088D01*
X1601104Y139415D01*
Y133857D01*
X1607682Y127279D01*
Y126785D01*
X1608052Y126415D01*
X1608053D01*
X1608917Y125551D01*
Y124327D01*
X1608916Y124326D01*
Y124195D01*
X1609647Y123464D01*
X1609978D01*
X1609979Y123463D01*
X1611151D01*
X1612220Y122394D01*
Y117842D01*
X1611362Y116984D01*
X1609726D01*
X1608985Y116243D01*
Y111685D01*
X1605493Y108193D01*
Y99607D01*
X1609738Y95362D01*
Y82137D01*
X1607001Y79400D01*
X1600550D01*
X1598000Y76850D01*
X1596800D01*
X1596050Y76100D01*
Y75400D01*
G01X1613741Y159585D02*
Y158725D01*
X1612120Y157104D01*
Y155413D01*
X1611722Y155015D01*
X1611257D01*
X1611203Y154961D01*
X1610054D01*
X1608917Y153824D01*
Y152694D01*
X1608916Y152693D01*
Y152674D01*
X1607754Y151512D01*
Y149054D01*
X1608917Y147891D01*
Y142741D01*
X1607356Y141180D01*
Y140080D01*
X1605858Y138582D01*
Y133292D01*
X1606225Y132925D01*
X1606818D01*
X1606829Y132914D01*
X1607888D01*
X1608917Y131885D01*
Y129105D01*
X1608961Y129061D01*
Y127359D01*
X1609906Y126414D01*
X1609978D01*
X1609979Y126415D01*
X1611203D01*
X1612214Y125404D01*
Y124378D01*
X1613078Y123514D01*
X1613092D01*
X1613204Y123402D01*
X1614346D01*
X1615216Y122532D01*
Y122403D01*
X1615217Y122402D01*
Y118028D01*
X1614156Y116967D01*
X1613129D01*
X1612067Y115905D01*
Y111729D01*
X1611203Y110865D01*
X1611201D01*
X1611002Y110666D01*
X1609980D01*
X1609116Y109802D01*
Y106275D01*
X1610588Y104803D01*
Y80733D01*
X1613697Y77624D01*
X1621376D01*
X1623200Y75800D01*
G01X1593000Y78140D02*
Y78723D01*
X1595300Y81023D01*
Y88201D01*
X1601024Y93925D01*
X1604000D01*
G01X1613741Y134389D02*
X1615322Y132808D01*
Y127307D01*
X1616015Y126614D01*
X1617301D01*
X1617501Y126414D01*
X1617503D01*
X1620419Y123498D01*
X1622545D01*
X1622578Y123465D01*
X1623802D01*
X1623835Y123498D01*
X1625694D01*
X1625727Y123465D01*
X1626951D01*
X1626984Y123498D01*
X1627461D01*
X1628358Y122601D01*
Y120299D01*
X1628059Y120000D01*
Y119297D01*
X1628014Y119252D01*
Y118028D01*
X1628059Y117983D01*
Y116806D01*
X1627857Y116604D01*
Y105557D01*
X1635084Y98330D01*
Y94832D01*
X1640723Y89193D01*
X1649757D01*
X1659150Y79800D01*
X1683992D01*
X1687900Y75892D01*
X1691397D01*
X1692144Y75145D01*
X1701548D01*
X1703489Y73204D01*
X1710273D01*
X1713217Y76148D01*
X1727535D01*
X1731027Y72656D01*
X1753939D01*
X1756239Y70356D01*
X1762121D01*
X1766333Y66144D01*
Y59116D01*
G01X1626339Y109191D02*
Y96761D01*
X1630700Y92400D01*
X1635524D01*
X1640139Y87785D01*
X1649173D01*
X1657999Y78959D01*
X1682841D01*
X1687850Y73950D01*
X1690500D01*
G01X1648386Y165885D02*
X1646905Y164404D01*
X1634846D01*
X1631617Y161175D01*
X1626008D01*
X1625893Y161060D01*
X1625727D01*
X1624864Y160197D01*
Y159040D01*
X1623684Y157860D01*
X1616577D01*
X1615322Y156605D01*
Y152607D01*
X1614454Y151739D01*
X1609981D01*
X1609038Y150796D01*
Y149603D01*
X1610179Y148462D01*
X1611203D01*
X1611223Y148442D01*
X1611524D01*
X1612258Y147708D01*
Y143198D01*
X1611295Y142235D01*
X1609971D01*
X1608916Y141180D01*
Y133200D01*
X1612215Y129901D01*
Y126979D01*
X1612677Y126517D01*
X1614250D01*
X1614301Y126466D01*
X1614302D01*
X1615166Y125602D01*
Y125601D01*
X1615415Y125352D01*
Y123682D01*
X1618504Y120593D01*
Y117956D01*
X1617548Y117000D01*
X1616098D01*
X1615363Y116265D01*
Y104885D01*
X1612214Y101736D01*
Y82934D01*
X1615624Y79524D01*
X1621636D01*
X1624624Y82512D01*
X1628356D01*
X1632488Y78380D01*
X1646820D01*
X1649549Y75651D01*
X1667264D01*
X1673801Y69114D01*
X1713974D01*
X1714664Y68424D01*
X1721445D01*
X1724047Y71026D01*
X1727050D01*
X1729950Y68126D01*
X1747144D01*
X1751270Y64000D01*
X1754890D01*
X1772123Y46767D01*
X1780875D01*
X1789356Y38286D01*
G01X1718587Y444550D02*
X1712098Y438061D01*
X1682311D01*
X1676797Y432547D01*
Y309091D01*
X1674272Y306566D01*
Y267645D01*
X1680618Y261299D01*
Y250204D01*
X1676888Y246474D01*
Y238610D01*
X1676156Y237878D01*
Y210002D01*
X1668053Y201899D01*
Y199903D01*
X1665897Y197747D01*
Y193817D01*
X1659903Y187823D01*
Y186689D01*
X1657722Y184508D01*
Y183033D01*
X1657723Y183032D01*
Y180922D01*
X1657722Y180921D01*
Y180659D01*
X1652480Y175417D01*
X1641287D01*
X1639051Y173181D01*
X1630363D01*
X1629133Y174411D01*
X1624355D01*
X1623417Y173473D01*
Y172626D01*
X1622553Y171762D01*
X1621330D01*
X1620997Y172095D01*
X1618595D01*
X1616500Y170000D01*
X1609364D01*
X1598673Y159309D01*
Y130688D01*
X1602700Y126661D01*
Y120232D01*
X1607441Y115491D01*
G01X1721990Y444521D02*
X1720261Y446250D01*
X1711858D01*
X1705573Y439965D01*
X1681521D01*
X1674893Y433337D01*
Y313016D01*
X1672368Y310491D01*
Y309565D01*
X1672367Y309564D01*
Y305368D01*
X1672368Y305367D01*
Y266855D01*
X1678713Y260510D01*
Y256138D01*
X1678714Y256137D01*
Y250994D01*
X1674984Y247264D01*
Y239400D01*
X1672373Y236789D01*
Y212846D01*
X1666149Y206622D01*
Y200693D01*
X1660841Y195385D01*
Y192800D01*
X1653456Y185415D01*
Y178519D01*
X1651970Y177033D01*
X1640777D01*
X1638427Y174683D01*
X1631132D01*
X1629902Y175913D01*
X1623471D01*
X1623141Y175583D01*
X1619665D01*
X1618371Y174289D01*
X1615362D01*
X1614426Y175225D01*
X1608972D01*
X1607140Y173393D01*
Y170558D01*
X1607141Y170557D01*
Y169935D01*
X1607140Y169934D01*
Y169902D01*
X1605886Y168648D01*
X1605883D01*
X1597436Y160201D01*
X1596401D01*
X1594952Y158752D01*
Y154608D01*
X1597171Y152389D01*
Y130064D01*
X1601100Y126135D01*
Y111376D01*
X1600490Y110766D01*
G01X1610591Y118640D02*
X1608979Y120252D01*
X1606893D01*
X1603822Y123323D01*
Y126602D01*
X1599424Y131000D01*
Y139270D01*
X1601945Y141791D01*
Y144712D01*
X1601593Y145064D01*
X1599852D01*
X1599500Y145416D01*
Y146120D01*
X1599852Y146472D01*
X1601593D01*
X1601945Y146824D01*
Y152280D01*
X1601659Y152566D01*
Y157092D01*
X1602813Y158246D01*
Y162386D01*
X1609627Y169200D01*
X1616800D01*
X1618823Y171223D01*
X1620806D01*
X1621018Y171011D01*
X1630857D01*
X1632110Y172264D01*
X1639197D01*
X1641313Y174380D01*
X1652506D01*
X1658474Y180348D01*
Y184197D01*
X1667049Y192772D01*
Y197269D01*
X1669973Y200193D01*
Y202189D01*
X1677308Y209524D01*
Y237400D01*
X1678040Y238132D01*
Y245996D01*
X1681770Y249726D01*
Y261777D01*
X1675424Y268123D01*
Y306088D01*
X1677949Y308613D01*
Y432069D01*
X1682789Y436909D01*
X1716978D01*
X1724590Y444521D01*
G01X1607441Y112341D02*
X1601948Y117834D01*
Y126350D01*
X1597922Y130376D01*
Y159621D01*
X1602640Y164339D01*
Y164342D01*
X1606195Y167897D01*
X1606198D01*
X1607891Y169590D01*
Y169622D01*
X1609334Y171065D01*
X1616466D01*
X1620121Y174720D01*
X1623341D01*
X1623783Y175162D01*
X1629590D01*
X1630820Y173932D01*
X1638739D01*
X1641014Y176207D01*
X1652207D01*
X1656971Y180971D01*
Y181233D01*
X1656972Y181234D01*
Y182720D01*
X1656971Y182721D01*
Y184820D01*
X1658751Y186600D01*
Y188301D01*
X1661593Y191143D01*
Y195073D01*
X1666901Y200381D01*
Y206310D01*
X1673184Y212593D01*
Y236536D01*
X1675736Y239088D01*
Y246952D01*
X1679466Y250682D01*
Y256449D01*
X1679465Y256450D01*
Y260822D01*
X1673120Y267167D01*
Y305679D01*
X1673119Y305680D01*
Y309252D01*
X1673120Y309253D01*
Y310179D01*
X1675645Y312704D01*
Y433025D01*
X1681833Y439213D01*
X1710700D01*
X1716037Y444550D01*
G01X1839873Y159358D02*
X1839672Y159157D01*
X1837160D01*
X1834731Y156728D01*
X1828338D01*
X1822922Y151312D01*
X1822410D01*
X1822403Y151305D01*
X1818893D01*
X1818886Y151312D01*
X1818110D01*
X1818103Y151305D01*
X1814593D01*
X1814586Y151312D01*
X1804557D01*
X1802306Y153563D01*
X1797963D01*
X1792444Y148044D01*
X1765355D01*
X1758781Y154618D01*
X1748875D01*
X1747912Y155581D01*
X1711126D01*
X1710790Y155245D01*
X1694802D01*
X1693410Y153853D01*
X1680232D01*
X1671856Y145477D01*
X1648738D01*
X1647991Y146224D01*
X1628269D01*
X1624448Y142403D01*
X1613151D01*
X1611436Y140688D01*
X1610591D01*
G01Y137538D02*
X1611066D01*
X1612599Y139071D01*
X1627001D01*
X1629309Y141379D01*
X1643948D01*
X1644911Y142342D01*
X1671412D01*
X1681685Y152615D01*
X1693625D01*
X1695933Y150307D01*
X1707414D01*
X1711736Y154629D01*
X1712685D01*
X1712776Y154720D01*
X1747230D01*
X1748295Y153655D01*
X1757542D01*
X1764544Y146653D01*
X1792459D01*
X1796166Y150360D01*
X1814191D01*
X1814198Y150353D01*
X1822798D01*
X1822805Y150360D01*
X1823317D01*
X1828080Y155123D01*
X1841532D01*
X1844883Y151772D01*
X1849675D01*
X1849676Y151773D01*
X1850464D01*
X1850478Y151759D01*
X1854169D01*
X1857849Y148079D01*
G01X1854942Y181655D02*
X1852321D01*
X1841273Y170607D01*
Y164891D01*
X1836691Y160309D01*
X1836682D01*
X1834253Y157880D01*
X1827860D01*
X1822444Y152464D01*
X1821932D01*
X1821925Y152457D01*
X1819371D01*
X1819364Y152464D01*
X1817632D01*
X1817625Y152457D01*
X1815071D01*
X1815064Y152464D01*
X1805484D01*
X1803193Y154755D01*
X1797504D01*
X1791945Y149196D01*
X1766771D01*
X1760197Y155770D01*
X1750643D01*
X1749942Y156471D01*
X1748912D01*
X1748636Y156747D01*
X1748635D01*
X1748593Y156789D01*
X1710654D01*
X1710262Y156397D01*
X1694324D01*
X1692932Y155005D01*
X1679754D01*
X1679718Y154969D01*
X1679423D01*
X1673094Y148640D01*
X1650559D01*
X1649886Y147967D01*
X1636372D01*
X1635714Y148625D01*
X1612983D01*
X1611471Y150137D01*
X1610591D01*
G01X1613741Y137538D02*
X1626999D01*
X1629965Y140504D01*
X1648362D01*
X1649765Y139101D01*
X1670464D01*
X1682174Y150811D01*
X1692035D01*
X1693915Y148931D01*
X1707721D01*
X1712444Y153654D01*
X1742409D01*
X1744304Y151759D01*
X1753475D01*
X1754056Y152340D01*
X1756779D01*
X1763699Y145420D01*
X1803633D01*
X1804181Y144872D01*
X1804969D01*
X1804970Y144873D01*
X1809820D01*
X1811425Y146478D01*
X1828637D01*
X1829735Y147576D01*
X1837606D01*
X1839667Y149637D01*
Y151994D01*
G01X1595390Y151778D02*
X1594174Y152994D01*
Y159175D01*
X1595951Y160952D01*
X1597124D01*
X1605571Y169399D01*
X1605574D01*
X1606389Y170214D01*
Y173706D01*
X1608723Y176040D01*
X1614674D01*
X1615674Y175040D01*
X1618059D01*
X1619353Y176334D01*
X1622829D01*
X1623579Y177084D01*
X1629794D01*
X1631444Y175434D01*
X1638115D01*
X1641043Y178362D01*
X1648409D01*
X1652705Y182658D01*
Y185727D01*
X1653820Y186842D01*
Y186843D01*
X1659810Y192833D01*
Y196203D01*
X1664304Y200697D01*
Y201077D01*
X1664390Y201163D01*
G01X1833629Y170807D02*
X1829828D01*
X1825940Y166919D01*
Y158088D01*
X1821820Y153968D01*
X1821308D01*
X1821301Y153961D01*
X1819995D01*
X1819988Y153968D01*
X1817008D01*
X1817001Y153961D01*
X1815695D01*
X1815688Y153968D01*
X1807495D01*
X1804904Y156559D01*
X1795700D01*
X1790472Y151331D01*
X1769986D01*
X1760816Y160501D01*
X1751467D01*
X1749783Y162185D01*
X1713554D01*
X1709491Y158122D01*
X1672119D01*
X1668798Y154801D01*
X1619449D01*
X1618486Y153838D01*
Y152568D01*
X1617593Y151675D01*
X1616263D01*
X1614725Y150137D01*
X1613741D01*
G01X1836932Y170486D02*
X1836916D01*
X1838888Y168514D01*
Y164063D01*
X1833647Y158822D01*
X1827738D01*
X1822132Y153216D01*
X1821620D01*
X1821613Y153209D01*
X1819683D01*
X1819676Y153216D01*
X1817320D01*
X1817313Y153209D01*
X1815383D01*
X1815376Y153216D01*
X1806658D01*
X1804067Y155807D01*
X1796567D01*
X1791174Y150414D01*
X1768977D01*
X1762710Y156681D01*
X1751053D01*
X1750512Y157222D01*
X1749224D01*
X1748695Y157751D01*
X1710241D01*
X1709783Y157293D01*
X1674195D01*
X1670065Y153163D01*
X1666828D01*
X1665290Y151625D01*
X1649055D01*
X1649042Y151638D01*
X1647818D01*
X1647805Y151625D01*
X1624675D01*
X1623200Y153100D01*
G01X1604292Y137538D02*
X1603373Y138457D01*
Y138955D01*
X1605900Y141482D01*
Y147594D01*
X1606776Y148470D01*
Y151402D01*
X1605461Y152717D01*
Y153915D01*
X1606439Y154893D01*
X1608304D01*
X1609116Y155705D01*
Y163347D01*
X1610169Y164400D01*
X1621100D01*
X1621600Y164900D01*
Y166600D01*
X1622400Y167400D01*
X1623981D01*
X1625206Y168625D01*
X1631662D01*
X1631999Y168962D01*
X1656462D01*
X1666289Y178789D01*
Y180502D01*
X1665720Y181071D01*
Y181072D01*
X1665432Y181360D01*
Y182820D01*
X1666487Y183875D01*
X1667361D01*
X1673981Y190495D01*
Y191445D01*
X1678500Y195964D01*
Y199153D01*
X1683228Y203881D01*
Y228091D01*
X1686750Y231613D01*
Y236273D01*
X1682880Y240143D01*
Y241497D01*
X1683729Y242346D01*
G01X1680769Y242605D02*
X1682128Y241246D01*
Y239831D01*
X1685998Y235961D01*
Y231925D01*
X1682476Y228403D01*
Y204512D01*
X1676206Y198242D01*
X1673413D01*
X1672490Y197319D01*
Y196013D01*
X1672677Y195826D01*
Y191706D01*
X1664681Y183710D01*
Y180766D01*
X1665202Y180245D01*
Y178974D01*
X1655941Y169713D01*
X1631687D01*
X1631483Y169509D01*
X1631482D01*
X1631481Y169508D01*
X1630859D01*
X1630858Y169509D01*
X1623310D01*
X1621163Y167362D01*
X1609915D01*
X1605918Y163365D01*
Y155933D01*
X1604391Y154406D01*
Y152325D01*
X1605359Y151357D01*
Y151157D01*
X1605767Y150749D01*
Y149525D01*
X1604904Y148662D01*
X1603679D01*
X1603528Y148511D01*
Y140776D01*
X1603500Y140748D01*
Y140335D01*
X1601945Y138780D01*
Y134637D01*
X1605224Y131358D01*
X1607239D01*
G01X1642084Y115494D02*
X1643600Y113978D01*
Y107440D01*
X1650275Y100765D01*
X1653723D01*
X1654415Y101457D01*
X1664475D01*
X1665616Y100316D01*
X1678896D01*
X1680139Y99073D01*
G01X1678400Y103000D02*
X1676702Y104698D01*
X1649965D01*
X1646906Y107757D01*
Y110493D01*
X1648387Y111974D01*
Y112341D01*
G01X1645237Y109191D02*
Y107663D01*
X1649058Y103842D01*
X1664504D01*
X1667164Y101182D01*
X1672882D01*
X1674800Y103100D01*
G01X1719080Y236152D02*
Y235451D01*
X1716352Y232723D01*
Y227021D01*
X1716353Y227020D01*
Y226066D01*
X1688722Y198435D01*
Y191344D01*
X1686710Y189332D01*
X1680571D01*
X1678741Y187502D01*
Y186556D01*
X1678740Y186555D01*
Y182659D01*
X1678741Y182658D01*
Y177862D01*
X1675172Y174293D01*
X1673606D01*
X1664980Y165667D01*
Y164488D01*
X1661665Y161173D01*
X1643924D01*
X1642348Y162749D01*
X1642101D01*
G01X1610591Y156436D02*
Y157068D01*
X1612067Y158544D01*
Y159997D01*
X1612265Y160195D01*
Y160197D01*
X1613129Y161061D01*
X1613131D01*
X1613191Y161121D01*
X1624321D01*
X1624800Y161600D01*
Y166911D01*
X1625616Y167727D01*
X1631934D01*
X1632418Y168211D01*
X1657111D01*
X1671688Y182788D01*
Y182925D01*
G01X1816125Y169492D02*
X1815146D01*
X1811478Y165824D01*
Y161544D01*
X1809460Y159526D01*
X1763778D01*
X1761503Y161801D01*
X1751797D01*
X1750261Y163337D01*
X1713127D01*
X1713014Y163224D01*
X1712963D01*
X1709013Y159274D01*
X1664221D01*
X1662972Y158025D01*
X1628178D01*
X1626618Y159585D01*
X1626339D01*
G01Y165884D02*
X1627814Y164409D01*
X1631830D01*
X1634844Y167423D01*
X1657423D01*
X1669389Y179389D01*
X1673529D01*
X1676487Y182347D01*
Y185847D01*
X1675985Y186349D01*
Y189765D01*
X1679979Y193759D01*
X1681258D01*
X1685566Y198067D01*
Y199744D01*
X1711958Y226136D01*
Y249921D01*
X1714016Y251979D01*
X1720804D01*
X1722251Y250532D01*
G01X1643662Y172609D02*
X1645056Y171215D01*
X1650404D01*
X1659225Y180036D01*
Y183885D01*
X1661055Y185715D01*
X1661622D01*
X1668201Y192294D01*
Y193635D01*
X1668202Y193636D01*
Y194590D01*
X1668201Y194591D01*
Y196560D01*
X1669986Y198345D01*
Y198357D01*
X1671125Y199496D01*
Y201711D01*
X1672570Y203156D01*
X1677578D01*
X1679528Y205106D01*
Y212248D01*
X1678460Y213316D01*
Y236922D01*
X1679192Y237654D01*
Y245518D01*
X1683615Y249941D01*
Y250493D01*
G01X1624798Y241937D02*
Y242098D01*
X1627311Y244611D01*
Y246886D01*
X1629299Y248874D01*
Y260888D01*
X1630474Y262063D01*
Y262192D01*
X1631600Y263318D01*
Y280100D01*
X1631300Y280400D01*
G01X1606849Y241210D02*
X1601839Y236200D01*
X1594242D01*
X1593295Y237147D01*
X1592125D01*
X1591865Y237407D01*
G01X1681500Y482000D02*
X1679132D01*
X1678635Y481503D01*
X1675570D01*
X1674395Y482678D01*
Y494222D01*
X1673016Y495601D01*
X1672829D01*
X1672812Y495618D01*
X1671506D01*
X1671489Y495601D01*
X1671297D01*
X1653641Y513257D01*
X1647325D01*
X1645969Y514613D01*
Y514870D01*
G01X1856040Y588704D02*
Y588720D01*
X1853095Y591665D01*
X1852684D01*
X1840139Y604210D01*
X1825573D01*
X1820363Y599000D01*
X1798100D01*
X1792600Y604500D01*
X1767650D01*
X1763621Y608529D01*
X1720473D01*
X1718444Y606500D01*
X1671609D01*
X1660743Y617366D01*
X1651115D01*
X1644630Y610881D01*
Y608670D01*
X1646632Y606668D01*
Y604194D01*
X1645244Y602806D01*
X1643051D01*
X1642395Y602150D01*
X1639304D01*
X1638376Y603078D01*
X1625041D01*
X1620908Y598945D01*
Y593872D01*
X1622330Y592450D01*
Y592325D01*
G01X1668000Y81600D02*
X1671724Y85324D01*
X1685444D01*
X1687904Y82864D01*
X1701979D01*
X1705356Y79487D01*
X1728907D01*
X1732600Y75794D01*
X1754405D01*
X1754732Y76121D01*
X1761648D01*
X1763689Y74080D01*
X1771654D01*
X1773531Y72203D01*
Y67104D01*
X1780821Y59814D01*
Y51649D01*
X1790022Y42448D01*
X1819940D01*
X1822554Y39834D01*
Y38528D01*
X1823477Y37605D01*
X1827395D01*
X1828790Y36210D01*
X1833050D01*
X1834140Y37300D01*
X1839300D01*
X1841060Y35540D01*
G01X1660944Y36761D02*
X1662781Y34924D01*
X1689653D01*
X1691077Y33500D01*
X1733500D01*
X1737500Y37500D01*
X1745152D01*
X1746552Y38900D01*
G01X1807127Y26918D02*
X1802337Y31708D01*
X1789535D01*
X1783630Y37613D01*
Y38139D01*
X1779434Y42335D01*
X1771550D01*
X1756427Y57458D01*
X1756296D01*
X1752792Y60962D01*
X1750000D01*
X1746435Y64527D01*
X1728220D01*
X1727459Y65288D01*
X1702802D01*
X1702061Y66029D01*
X1666699D01*
X1664350Y68378D01*
Y69962D01*
G01Y72462D02*
Y72191D01*
X1665926Y70615D01*
Y69186D01*
X1668331Y66781D01*
X1702373D01*
X1703114Y66040D01*
X1727771D01*
X1728459Y65352D01*
X1746862D01*
X1750500Y61714D01*
X1753598D01*
X1771912Y43400D01*
X1779433D01*
X1784382Y38451D01*
Y37925D01*
X1789735Y32572D01*
X1798799D01*
X1798809Y32562D01*
X1800739D01*
X1800749Y32572D01*
X1803835D01*
X1809822Y26585D01*
G01X1878789Y213663D02*
X1878266Y213140D01*
Y211478D01*
X1874848Y208060D01*
Y191225D01*
X1864424Y180801D01*
Y176517D01*
X1859372Y171465D01*
Y169272D01*
X1856300Y166200D01*
Y161330D01*
X1859372Y158258D01*
Y156735D01*
X1865208Y150899D01*
Y148692D01*
X1868856Y145044D01*
Y131968D01*
X1870557Y130267D01*
Y129645D01*
X1870558Y129644D01*
Y127734D01*
X1870556Y127732D01*
Y117908D01*
X1855448Y102800D01*
X1842334D01*
X1831609Y92075D01*
Y76884D01*
X1829032Y74307D01*
Y63404D01*
X1833984Y58452D01*
X1842755D01*
X1847035Y54172D01*
X1854758D01*
X1865102Y43828D01*
Y36472D01*
X1860420Y31790D01*
X1852380D01*
X1851680Y32490D01*
X1844613D01*
X1842921Y30798D01*
X1813668D01*
X1812070Y29200D01*
X1808271D01*
X1804147Y33324D01*
X1800437D01*
X1800427Y33314D01*
X1799121D01*
X1799111Y33324D01*
X1790047D01*
X1785134Y38237D01*
Y38763D01*
X1779497Y44400D01*
X1772104D01*
X1753912Y62592D01*
X1750686D01*
X1747174Y66104D01*
X1746863D01*
X1746483Y66484D01*
X1728391D01*
X1728083Y66792D01*
X1704614D01*
X1703821Y67585D01*
X1669303D01*
X1667774Y69114D01*
Y72141D01*
X1665877Y74038D01*
X1659524D01*
X1659100Y73614D01*
G01X1826900Y40400D02*
Y41499D01*
X1825583Y42816D01*
X1821749D01*
X1820965Y43600D01*
X1806400D01*
X1804096Y45904D01*
X1788196D01*
X1781973Y52127D01*
Y60292D01*
X1774683Y67582D01*
Y72681D01*
X1772132Y75232D01*
X1764167D01*
X1762124Y77275D01*
X1754256D01*
X1753952Y76971D01*
X1733053D01*
X1729385Y80639D01*
X1706518D01*
X1703141Y84016D01*
X1688842D01*
X1684207Y88651D01*
X1672349D01*
X1669000Y92000D01*
G01X1846527Y34435D02*
X1844684D01*
X1842801Y32552D01*
X1807037D01*
X1799527Y40062D01*
X1789714D01*
X1778917Y50859D01*
Y59024D01*
X1771626Y66315D01*
Y71414D01*
X1770864Y72176D01*
X1764809D01*
X1764615Y71982D01*
X1756448D01*
X1754622Y73808D01*
X1731892D01*
X1728119Y77581D01*
X1712658D01*
X1709780Y74703D01*
X1705156D01*
X1703155Y76704D01*
X1700967D01*
X1697775Y79896D01*
X1688178D01*
X1688163Y79911D01*
X1686280D01*
X1682921Y83270D01*
X1677170D01*
X1675500Y81600D01*
G01X1673000D02*
X1675972Y84572D01*
X1685132D01*
X1688656Y81048D01*
X1698253D01*
X1701445Y77856D01*
X1703633D01*
X1705397Y76092D01*
X1709512D01*
X1712153Y78733D01*
X1728597D01*
X1732288Y75042D01*
X1754717D01*
X1755005Y75330D01*
X1761375D01*
X1763377Y73328D01*
X1771342D01*
X1772778Y71892D01*
Y66793D01*
X1780069Y59502D01*
Y51337D01*
X1789755Y41651D01*
X1809348D01*
X1810493Y40506D01*
Y36156D01*
X1812945Y33704D01*
X1842323D01*
X1844630Y36011D01*
X1847442D01*
X1849027Y34426D01*
G01X1784341Y64841D02*
X1784078D01*
X1779752Y69167D01*
Y74303D01*
X1772303Y81752D01*
X1764301D01*
X1763576Y82477D01*
X1752519D01*
X1751568Y83428D01*
X1733250D01*
X1731335Y85343D01*
X1712652D01*
X1709184Y88811D01*
G01X1720100Y46100D02*
X1718392Y47808D01*
X1686364D01*
X1679556Y54616D01*
X1678627D01*
G01X1659000Y88000D02*
X1660012D01*
X1666365Y94353D01*
X1670703D01*
X1671451Y93605D01*
X1677060D01*
X1679646Y91019D01*
X1686511D01*
X1689414Y88116D01*
X1702368D01*
X1707493Y82991D01*
X1730360D01*
X1732275Y81076D01*
X1750593D01*
X1752042Y79627D01*
X1763099D01*
X1763326Y79400D01*
X1771328D01*
X1777212Y73516D01*
Y68380D01*
X1784947Y60645D01*
Y59954D01*
X1795493Y49408D01*
X1810592D01*
X1812748Y47252D01*
X1822270D01*
X1823202Y46320D01*
X1837907D01*
X1842879Y41348D01*
X1850600D01*
G01X1853467Y35000D02*
Y36860D01*
X1852850Y37477D01*
Y41610D01*
X1850759Y43701D01*
X1843853D01*
X1838882Y48672D01*
X1824177D01*
X1823245Y49604D01*
X1813796D01*
X1811640Y51760D01*
X1799614D01*
X1790588Y60786D01*
Y62666D01*
X1784456Y68798D01*
Y76263D01*
X1776415Y84304D01*
X1770694D01*
X1767274Y87724D01*
X1720708D01*
X1717802Y90630D01*
X1707468D01*
X1706089Y92009D01*
X1704000D01*
X1702459Y90468D01*
X1690389D01*
X1687290Y93567D01*
X1680425D01*
X1679415Y94577D01*
X1678976D01*
X1678449Y95104D01*
X1664604D01*
X1661900Y92400D01*
G01X1660400Y98500D02*
X1661898Y97002D01*
X1687182D01*
X1691364Y92820D01*
X1701438D01*
X1702979Y94361D01*
X1707064D01*
X1708443Y92982D01*
X1719763D01*
X1722669Y90076D01*
X1754333D01*
X1757554Y93297D01*
X1765503D01*
X1767047Y91753D01*
X1772293D01*
X1786808Y77238D01*
Y69773D01*
X1790627Y65954D01*
X1798215D01*
X1799767Y64402D01*
Y56421D01*
X1801383Y54805D01*
X1811922D01*
X1814771Y51956D01*
X1824220D01*
X1825152Y51024D01*
X1839857D01*
X1844828Y46053D01*
X1851747D01*
X1855400Y42400D01*
Y40800D01*
G01X1815883Y133277D02*
X1815011Y132405D01*
X1804293D01*
X1802031Y134667D01*
X1767725D01*
X1756258Y146134D01*
X1755364D01*
X1752155Y149343D01*
X1742042D01*
X1740727Y150658D01*
X1713604D01*
X1709570Y146624D01*
Y140140D01*
X1696240Y126810D01*
X1693892D01*
X1680741Y113659D01*
X1675901D01*
X1674937Y114623D01*
X1671302D01*
X1670434Y115491D01*
G01X1667284D02*
Y114671D01*
X1671330Y110625D01*
X1682561D01*
X1697800Y95386D01*
Y94612D01*
G01X1692285D02*
Y99698D01*
X1682447Y109536D01*
X1663818D01*
X1662639Y110715D01*
Y112954D01*
X1661722Y113871D01*
X1659275D01*
X1657835Y112431D01*
Y112341D01*
G01X1664135Y115491D02*
X1664839D01*
X1666492Y117144D01*
X1674778D01*
X1676735Y115187D01*
X1680741D01*
X1693444Y127890D01*
X1695792D01*
X1708490Y140588D01*
Y146980D01*
X1713248Y151738D01*
X1741357D01*
X1743001Y150094D01*
X1752467D01*
X1755633Y146928D01*
X1756992D01*
X1768173Y135747D01*
X1804315D01*
X1805700Y134362D01*
X1812610D01*
X1814322Y136074D01*
X1819703D01*
X1822944Y132833D01*
X1853374D01*
X1853924Y133383D01*
X1854763D01*
X1854993Y133613D01*
X1854962D01*
G01X1848100Y134750D02*
Y136489D01*
X1846925Y137664D01*
X1838230D01*
X1836396Y135830D01*
X1823983D01*
X1821691Y138122D01*
X1768122D01*
X1758246Y147998D01*
X1755708D01*
X1752773Y150933D01*
X1743264D01*
X1741643Y152554D01*
X1712872D01*
X1707674Y147356D01*
Y140926D01*
X1695454Y128706D01*
X1692693D01*
X1689844Y125857D01*
X1672882D01*
X1670497Y123472D01*
X1663617D01*
X1662460Y122315D01*
Y121061D01*
X1660985Y119586D01*
Y118640D01*
G01X1681352Y196092D02*
Y199026D01*
X1681880Y199554D01*
Y199681D01*
X1682803Y200604D01*
X1682930D01*
X1689943Y207617D01*
Y242793D01*
X1685236Y247500D01*
X1683760D01*
X1681760Y245500D01*
G01X1687550Y213751D02*
X1683980Y210181D01*
Y203569D01*
X1679252Y198841D01*
Y195652D01*
X1674733Y191133D01*
Y183179D01*
X1674912Y183000D01*
G01X1663400Y179475D02*
Y183492D01*
X1666586Y186678D01*
Y187386D01*
X1671425Y192225D01*
Y195307D01*
X1671238Y195494D01*
Y196800D01*
X1671237Y196801D01*
Y197837D01*
X1672894Y199494D01*
X1675687D01*
X1680780Y204587D01*
Y211729D01*
X1680781Y211730D01*
Y212766D01*
X1679721Y213826D01*
Y236187D01*
X1681116Y237582D01*
Y238614D01*
G01X1719080Y232852D02*
Y225580D01*
X1705666Y212166D01*
Y198055D01*
G01X1903032Y228368D02*
Y228332D01*
X1899600Y224900D01*
X1894558D01*
X1892182Y222524D01*
X1878284D01*
X1867797Y212037D01*
X1867392D01*
X1864600Y209245D01*
Y206157D01*
X1862072Y203629D01*
Y200606D01*
X1862071Y200605D01*
Y199983D01*
X1862072Y199982D01*
Y197515D01*
X1855657Y191100D01*
X1849900D01*
X1847700Y193300D01*
X1717635D01*
X1712962Y191365D01*
X1709900Y188303D01*
Y187300D01*
G01X1660985Y165885D02*
X1666738Y171638D01*
Y173220D01*
X1672122Y178604D01*
X1673807D01*
X1677238Y182035D01*
Y186555D01*
X1677237Y186556D01*
Y189246D01*
X1680438Y192447D01*
X1681717D01*
X1686818Y197548D01*
Y199225D01*
X1714447Y226854D01*
Y242716D01*
X1715837Y244106D01*
Y246178D01*
G01X1660440Y200789D02*
Y201977D01*
X1671525Y213062D01*
Y237005D01*
X1674232Y239712D01*
Y247576D01*
X1677961Y251305D01*
Y260198D01*
X1671616Y266543D01*
Y305055D01*
X1671615Y305056D01*
Y309876D01*
X1671616Y309877D01*
Y310803D01*
X1674141Y313328D01*
Y433649D01*
X1681209Y440717D01*
X1705261D01*
X1711546Y447002D01*
X1729398D01*
X1735210Y441190D01*
X1855361D01*
X1863647Y449476D01*
X1864426D01*
X1866050Y451100D01*
G01X1660985Y162735D02*
X1671605Y173355D01*
Y176993D01*
X1672313Y177701D01*
X1673967D01*
X1677990Y181724D01*
Y182346D01*
X1677989Y182347D01*
Y188934D01*
X1680612Y191557D01*
X1681891D01*
X1687570Y197236D01*
Y198913D01*
X1715200Y226543D01*
Y236451D01*
X1722444Y243695D01*
Y244422D01*
X1724181Y246159D01*
G01X1870815Y453022D02*
X1869116Y451323D01*
Y447287D01*
X1861833Y440004D01*
X1731439D01*
X1727592Y436157D01*
X1683101D01*
X1678701Y431757D01*
Y308301D01*
X1676176Y305776D01*
Y268435D01*
X1689809Y254802D01*
X1835640D01*
X1845947Y244495D01*
Y233623D01*
X1862056Y217514D01*
X1871926D01*
X1878512Y224100D01*
X1881900D01*
G01X1871521Y153593D02*
X1871800Y153872D01*
Y155500D01*
X1870676Y156624D01*
X1861254D01*
X1860624Y157254D01*
Y170946D01*
X1861598Y171920D01*
X1864620D01*
X1865724Y173024D01*
X1865753D01*
X1866329Y173600D01*
X1868100D01*
X1868822Y174322D01*
Y183207D01*
X1876256Y190641D01*
Y204695D01*
X1880600Y209039D01*
Y218142D01*
X1882376Y219918D01*
X1894889D01*
X1895071Y220100D01*
X1904800D01*
X1906250Y221550D01*
Y233121D01*
X1905215Y234156D01*
X1901390D01*
X1899626Y232392D01*
X1885421D01*
X1879729Y226700D01*
X1877682D01*
X1872394Y221412D01*
X1861788D01*
X1849552Y233648D01*
Y239981D01*
X1849553Y239982D01*
Y241018D01*
X1849552Y241019D01*
Y242661D01*
X1829644Y262569D01*
X1684284D01*
X1677848Y269005D01*
Y269796D01*
X1677428Y270216D01*
Y305257D01*
X1679953Y307782D01*
Y431238D01*
X1683620Y434905D01*
X1868732D01*
X1880076Y446249D01*
Y459436D01*
X1876945Y462567D01*
Y471316D01*
G01X1932998Y119438D02*
Y121981D01*
X1936300Y125283D01*
Y129900D01*
X1933893Y132307D01*
Y138864D01*
X1930900Y141857D01*
Y150229D01*
X1940047Y159376D01*
X1940652D01*
X1946387Y165111D01*
Y203156D01*
X1937288Y212255D01*
X1932358D01*
X1909739Y234874D01*
X1908066D01*
X1903805Y239135D01*
X1879506D01*
X1876582Y236211D01*
Y228718D01*
X1871480Y223616D01*
X1862864D01*
X1856564Y229916D01*
Y249401D01*
X1855533Y250432D01*
X1852961D01*
X1852953Y250424D01*
X1851647D01*
X1851639Y250432D01*
X1844132D01*
X1830743Y263821D01*
X1684803D01*
X1679100Y269524D01*
Y271300D01*
G01X1829300Y572900D02*
X1830756D01*
X1833776Y569880D01*
X1842120D01*
X1843966Y568034D01*
Y554697D01*
X1845475Y553188D01*
Y551854D01*
X1845676Y551653D01*
Y550347D01*
X1845475Y550146D01*
Y535570D01*
X1847383Y533662D01*
Y522677D01*
X1867196Y502864D01*
Y493566D01*
X1855227Y481597D01*
Y473687D01*
X1851620Y470080D01*
Y454870D01*
X1847944Y451194D01*
X1840875D01*
X1839525Y452544D01*
X1838115D01*
X1836011Y454648D01*
X1737652D01*
X1730321Y461979D01*
X1721739D01*
X1710563Y473155D01*
X1683169D01*
X1681218Y475106D01*
X1679406D01*
X1678001Y473701D01*
Y473205D01*
G01X1872860Y450550D02*
X1873615Y451305D01*
Y454898D01*
X1871965Y456548D01*
X1856558D01*
X1845552Y445542D01*
X1737185D01*
X1730952Y451775D01*
Y453375D01*
X1725575Y458752D01*
X1720135D01*
X1708472Y470415D01*
X1667534D01*
X1667097Y470852D01*
X1654143Y483804D01*
X1652804D01*
X1651867Y484741D01*
G01X1872860Y447950D02*
X1871230Y449580D01*
Y451179D01*
X1872500Y452449D01*
Y454666D01*
X1871570Y455596D01*
X1856953D01*
X1846147Y444790D01*
X1736590D01*
X1730000Y451380D01*
Y452980D01*
X1725180Y457800D01*
X1719740D01*
X1707920Y469620D01*
X1666980D01*
X1653748Y482852D01*
X1652581D01*
X1651926Y482197D01*
G01X1839126Y583354D02*
X1841446D01*
X1845118Y579682D01*
Y559082D01*
X1847117Y557083D01*
Y539822D01*
X1849474Y537465D01*
Y522216D01*
X1860294Y511396D01*
X1864808D01*
X1868348Y507856D01*
Y493048D01*
X1860800Y485500D01*
Y478700D01*
X1861850Y477650D01*
Y474350D01*
X1854020Y466520D01*
Y457290D01*
X1852772Y456042D01*
Y454392D01*
X1848422Y450042D01*
X1846772D01*
X1843424Y446694D01*
X1829777D01*
X1827000Y449471D01*
Y452200D01*
X1825704Y453496D01*
X1736924D01*
X1729593Y460827D01*
X1721261D01*
X1710224Y471864D01*
X1681961D01*
X1680500Y473325D01*
G01X1758100Y119100D02*
Y116100D01*
X1767500Y106700D01*
X1768900D01*
X1769900Y105700D01*
X1775000D01*
X1785515Y95185D01*
X1788815D01*
X1792700Y91300D01*
Y72298D01*
X1794100Y70898D01*
G01X1761300Y119100D02*
Y115003D01*
X1768116Y108187D01*
X1769516D01*
X1770516Y107187D01*
X1775616D01*
X1786174Y96629D01*
X1789474D01*
X1794187Y91916D01*
Y74307D01*
X1796100Y72394D01*
Y68800D01*
G01X1803280Y232611D02*
X1801885Y234006D01*
X1799654D01*
X1793948Y228300D01*
X1740001D01*
X1738721Y229580D01*
Y232231D01*
X1737618Y233334D01*
X1736847D01*
G01X1806083Y232584D02*
X1803909Y234758D01*
X1799015D01*
X1793509Y229252D01*
X1740396D01*
X1739673Y229975D01*
Y233160D01*
X1739847Y233334D01*
G01X1746900Y249804D02*
Y247000D01*
X1741650Y241750D01*
X1738350D01*
X1733900Y237300D01*
G01X1751900Y249700D02*
X1742400Y240200D01*
X1739300D01*
X1736400Y237300D01*
G01X1753807Y548183D02*
X1755392Y549768D01*
X1760355D01*
X1767900Y542223D01*
Y537435D01*
X1769683Y535652D01*
X1779678D01*
X1780530Y534800D01*
X1782000D01*
X1782900Y535700D01*
X1814400D01*
X1817200Y538500D01*
X1830000D01*
X1831100Y537400D01*
Y535800D01*
X1827800Y532500D01*
X1823116D01*
X1818509Y527893D01*
G01X1757478Y548192D02*
X1766748Y538922D01*
Y536959D01*
X1766747Y536958D01*
X1769205Y534500D01*
X1779200D01*
X1785700Y528000D01*
X1795400D01*
X1796600Y526800D01*
X1803900D01*
X1804500Y526200D01*
G01X1736003Y588244D02*
Y584344D01*
X1737280Y583067D01*
Y570720D01*
X1743500Y564500D01*
G01X1739179Y592070D02*
X1737425D01*
X1734026Y588671D01*
Y584857D01*
X1736498Y582385D01*
Y570079D01*
X1740864Y565713D01*
Y556189D01*
X1738930Y554255D01*
X1738498D01*
G01X1739714Y604967D02*
X1744300D01*
X1753418Y595849D01*
X1786881D01*
X1793492Y589238D01*
X1814149D01*
X1815907Y587480D01*
X1816458D01*
G01X1792170Y583900D02*
X1784140Y591930D01*
X1781512D01*
X1779003Y594439D01*
X1753060D01*
X1745999Y601500D01*
X1718900D01*
X1716950Y603450D01*
G01X1886093Y202184D02*
Y198438D01*
X1885195Y197540D01*
X1881635D01*
X1880100Y196005D01*
Y185371D01*
X1873334Y178605D01*
Y174967D01*
X1883652Y164649D01*
Y151880D01*
X1881754Y149982D01*
Y133840D01*
X1878028Y130114D01*
Y114564D01*
X1869952Y106488D01*
Y102774D01*
X1873289Y99437D01*
Y73047D01*
X1869608Y69366D01*
Y50010D01*
X1874455Y45163D01*
Y41673D01*
X1874454Y41672D01*
Y33316D01*
X1876270Y31500D01*
Y27651D01*
X1872456Y23837D01*
Y22311D01*
X1867121Y16976D01*
X1866574D01*
X1858484Y8886D01*
X1851862D01*
X1850958Y7982D01*
X1848645D01*
X1841446Y783D01*
X1835583D01*
X1832050Y-2750D01*
Y-5451D01*
X1827108Y-10393D01*
Y-15144D01*
X1822406Y-19846D01*
X1814350D01*
X1809504Y-15000D01*
G01X1813118Y127976D02*
Y126661D01*
X1820700Y119079D01*
Y100149D01*
X1818474Y97923D01*
Y96725D01*
X1818729Y96470D01*
Y87886D01*
X1802119Y71276D01*
Y56581D01*
G01X1884340Y217866D02*
X1882009Y215535D01*
Y205619D01*
X1877844Y201454D01*
Y190237D01*
X1870500Y182893D01*
Y174400D01*
X1873435Y171465D01*
Y157574D01*
X1873097Y157236D01*
Y149466D01*
X1874601Y147962D01*
Y137417D01*
X1871310Y134126D01*
Y127422D01*
X1871308Y127420D01*
Y117596D01*
X1855627Y101915D01*
X1843289D01*
X1834504Y93130D01*
Y78715D01*
X1829784Y73995D01*
Y63716D01*
X1834296Y59204D01*
X1843067D01*
X1847347Y54924D01*
X1855070D01*
X1865854Y44140D01*
Y42678D01*
X1867619Y40913D01*
Y39779D01*
G01X1815637Y54775D02*
X1816500Y55638D01*
Y81300D01*
X1858671Y123471D01*
Y134071D01*
X1860969Y136369D01*
G01X1818396Y54752D02*
X1817655Y55493D01*
Y81313D01*
X1859423Y123081D01*
Y132223D01*
X1860969Y133769D01*
G01X1857400Y175900D02*
Y174694D01*
X1850048Y167342D01*
Y159320D01*
X1853836Y155532D01*
X1855217D01*
X1865902Y144847D01*
Y139009D01*
X1864373Y137480D01*
Y132127D01*
X1867500Y129000D01*
Y121200D01*
X1866600Y120300D01*
X1857706D01*
X1829733Y92327D01*
Y80733D01*
X1825976Y76976D01*
Y60430D01*
X1832006Y54400D01*
X1839808D01*
X1843205Y51003D01*
X1853275D01*
X1860786Y43492D01*
Y41200D01*
G01X1862000Y177500D02*
Y177000D01*
X1860900Y175900D01*
X1859670D01*
X1850800Y167030D01*
Y159632D01*
X1854148Y156284D01*
X1855529D01*
X1866696Y145117D01*
Y138000D01*
X1865595Y136899D01*
Y131969D01*
X1868253Y129311D01*
Y128689D01*
X1868252Y128688D01*
Y120888D01*
X1866911Y119547D01*
X1866289D01*
X1866288Y119548D01*
X1858018D01*
X1830485Y92015D01*
Y80185D01*
X1826728Y76428D01*
Y60742D01*
X1831670Y55800D01*
X1839472D01*
X1843404Y51868D01*
X1853732D01*
X1862600Y43000D01*
Y40500D01*
X1861308Y39208D01*
X1860098D01*
X1858198Y41108D01*
G01X1863650Y189750D02*
Y188419D01*
X1860276Y185045D01*
Y184362D01*
X1859667Y183753D01*
Y182447D01*
X1860276Y181838D01*
Y179705D01*
X1859106Y178535D01*
X1853035D01*
X1844000Y169500D01*
Y163714D01*
X1848436Y159278D01*
Y155771D01*
X1849971Y154236D01*
X1854115D01*
X1859603Y148748D01*
Y137324D01*
X1857290Y135011D01*
Y132118D01*
X1857033Y131861D01*
Y131839D01*
X1856389Y131195D01*
X1856367D01*
X1855444Y130272D01*
Y129726D01*
X1855070Y129352D01*
X1851848D01*
X1851100Y130100D01*
X1805109D01*
X1803509Y128500D01*
G01X1776828Y155211D02*
X1779428Y157811D01*
X1809584D01*
X1813892Y162119D01*
Y163410D01*
X1816707Y166225D01*
X1821048D01*
X1829884Y175061D01*
Y180379D01*
X1833446Y183941D01*
X1851912D01*
X1854214Y186243D01*
X1854472D01*
X1867267Y199038D01*
Y208743D01*
X1868524Y210000D01*
X1872665D01*
X1875862Y213197D01*
Y213361D01*
X1879347Y216846D01*
Y218660D01*
X1881857Y221170D01*
X1882099D01*
X1882163Y221234D01*
X1892663D01*
X1894982Y223553D01*
X1900797D01*
X1903020Y225776D01*
G01X1854115Y131121D02*
X1855229D01*
X1856538Y132430D01*
Y134342D01*
X1855430Y135450D01*
X1854140D01*
X1852020Y137570D01*
Y148870D01*
X1850070Y150820D01*
X1844220D01*
X1841260Y153780D01*
X1838927D01*
X1836553Y151406D01*
X1836437D01*
X1833559Y148528D01*
X1829137D01*
X1828039Y147430D01*
X1812270D01*
X1810360Y149340D01*
X1801520D01*
X1800420Y148240D01*
G01X1874236Y213800D02*
X1873628D01*
X1873284Y213456D01*
Y212789D01*
X1872361Y211866D01*
X1871753D01*
X1871708Y211821D01*
X1871649D01*
X1871113Y211285D01*
X1867704D01*
X1865659Y209240D01*
Y206161D01*
X1865352Y205854D01*
Y205845D01*
X1862824Y203317D01*
Y196624D01*
X1856884Y190684D01*
X1856880D01*
X1855016Y188820D01*
Y188816D01*
X1853227Y187027D01*
X1831275D01*
X1825298Y181050D01*
Y177998D01*
X1824200Y176900D01*
G01X1803280Y232611D02*
X1807591Y228300D01*
X1844836D01*
X1852800Y220336D01*
Y210412D01*
X1855670Y207542D01*
Y206430D01*
G01X1806083Y232584D02*
X1809415Y229252D01*
X1845231D01*
X1853752Y220731D01*
Y210807D01*
X1858224Y206335D01*
X1858470D01*
G01X1840300Y239300D02*
X1839497Y240103D01*
X1803103D01*
X1795500Y232500D01*
X1793700D01*
G01X1793600Y235100D02*
X1796470D01*
X1802246Y240876D01*
X1840953D01*
X1842829Y239000D01*
X1843600D01*
G01X1842450Y507520D02*
X1839250Y504320D01*
Y504300D01*
X1828300D01*
X1825100Y501100D01*
X1820400D01*
G01X1804500Y526200D02*
X1806100D01*
X1810080Y530180D01*
X1811580D01*
X1817200Y535800D01*
X1828485D01*
X1829000Y536315D01*
G01X1840700Y563800D02*
X1842510Y561990D01*
Y544258D01*
X1838750Y540498D01*
Y532806D01*
X1836744Y530800D01*
X1827800D01*
X1822700Y525700D01*
X1816800D01*
G01X1780394Y561076D02*
Y561004D01*
X1780845Y561455D01*
X1781174D01*
X1784643Y564924D01*
X1793170D01*
X1809067Y580821D01*
X1836035D01*
X1837534Y579322D01*
G01X1836700Y-18900D02*
X1839600Y-16000D01*
Y-2127D01*
X1848957Y7230D01*
X1851270D01*
X1852174Y8134D01*
X1858796D01*
X1866886Y16224D01*
X1867433D01*
X1873208Y21999D01*
Y23525D01*
X1877022Y27339D01*
Y31812D01*
X1875206Y33628D01*
Y41360D01*
X1875207Y41361D01*
Y45475D01*
X1870360Y50322D01*
Y69054D01*
X1874589Y73283D01*
Y99490D01*
X1875985Y100886D01*
Y102535D01*
X1878102Y104652D01*
Y113005D01*
X1878780Y113683D01*
Y129109D01*
X1882698Y133027D01*
Y148048D01*
X1886081Y151431D01*
X1886050D01*
G01X1868843Y207920D02*
X1869782Y206981D01*
Y199427D01*
X1861437Y191082D01*
Y187977D01*
X1858547Y185087D01*
Y183076D01*
X1856324Y180853D01*
Y180808D01*
X1855311Y179795D01*
X1852937D01*
X1842770Y169628D01*
Y159684D01*
X1839944Y156858D01*
X1839941D01*
G01X1883800Y213436D02*
X1886732Y216368D01*
X1893110D01*
X1895589Y218847D01*
X1905318D01*
X1907511Y221040D01*
Y233631D01*
X1902959Y238183D01*
X1879901D01*
X1877534Y235816D01*
Y228323D01*
X1871875Y222664D01*
X1862307D01*
X1854374Y230597D01*
Y248790D01*
G01X1891378Y197078D02*
X1901622D01*
X1904825Y193875D01*
X1912894D01*
X1915294Y191475D01*
G01X1875066Y175782D02*
X1875110D01*
Y175826D01*
X1875135Y175801D01*
X1876657D01*
G01X1890786Y197830D02*
X1902327D01*
X1905530Y194627D01*
X1912336D01*
G01X1864305Y253825D02*
X1864828Y254348D01*
X1868360D01*
X1881458Y241250D01*
X1903037D01*
X1908461Y235826D01*
X1915194D01*
X1930321Y220699D01*
X1938199D01*
X1943500Y226000D01*
X1944924D01*
Y226001D01*
X1944925D01*
G01X1861605Y253925D02*
X1863180Y255500D01*
X1868838D01*
X1881936Y242402D01*
X1903609D01*
X1909016Y236995D01*
X1916487D01*
X1931631Y221851D01*
X1937721D01*
X1944328Y228458D01*
X1944463D01*
G01X1942000Y440500D02*
X1887400D01*
X1884353Y443547D01*
Y458085D01*
X1883717Y458721D01*
Y482683D01*
X1871800Y494600D01*
Y508430D01*
X1861870Y518360D01*
X1859490D01*
X1856220Y521630D01*
Y530630D01*
X1856924Y531334D01*
Y546945D01*
X1857326Y547347D01*
Y549890D01*
X1857108Y550108D01*
G01X1856573Y576534D02*
X1855805Y575766D01*
Y557767D01*
X1852938Y554900D01*
X1852400D01*
G01X1857812Y557245D02*
X1861062D01*
X1878212Y574395D01*
X1880015D01*
X1891985Y586365D01*
X1895523D01*
G01X1935600Y176300D02*
Y157100D01*
X1929939Y151439D01*
Y141166D01*
X1932941Y138164D01*
Y124482D01*
X1931022Y122563D01*
Y116618D01*
X1937599Y110041D01*
Y104027D01*
X1936152Y102580D01*
Y98278D01*
X1933914Y96040D01*
G01X1934256Y99459D02*
X1935000Y100203D01*
Y103058D01*
X1936447Y104505D01*
Y109563D01*
X1929870Y116140D01*
Y123041D01*
X1931789Y124960D01*
Y137543D01*
X1928787Y140545D01*
Y152186D01*
X1934000Y157399D01*
Y179144D01*
X1932837Y180307D01*
Y186700D01*
G01X1944609Y149184D02*
X1948493Y145300D01*
X1950275D01*
X1950281Y145306D01*
X1951587D01*
X1951593Y145300D01*
X1970824D01*
X1973004Y143120D01*
G01X1964382Y147318D02*
X1955379D01*
X1953600Y149097D01*
X1947203D01*
X1944600Y151700D01*
G01X1942328Y508712D02*
X1944400Y510784D01*
Y526700D01*
X1931300Y539800D01*
X1908100D01*
X1899800Y548100D01*
G54D28*
G01X34300Y482890D02*
Y483190D01*
X32488Y485002D01*
X29415D01*
X26667Y482254D01*
X9271D01*
X5065Y486460D01*
X2416D01*
X-10500Y499376D01*
Y512370D01*
X-12200Y514070D01*
Y526930D01*
X-11174Y527956D01*
G01X6200Y567300D02*
Y566400D01*
X3300Y563500D01*
X-8500D01*
G01X-8318Y542216D02*
Y544698D01*
X-13100Y549480D01*
Y558900D01*
X-8500Y563500D01*
G01D02*
X-12119Y567119D01*
Y574681D01*
X-8200Y578600D01*
G01X-11174Y527956D02*
X-10042Y529088D01*
X-4624D01*
X-212Y533500D01*
X4512D01*
X6200Y531812D01*
Y531300D01*
G01X-11174Y527956D02*
X-13670Y530452D01*
Y536864D01*
X-8318Y542216D01*
G01X61800Y191600D02*
Y196200D01*
X53700Y204300D01*
Y211400D01*
X58050Y215750D01*
X75090D01*
X80002Y220662D01*
Y267616D01*
X74281Y273337D01*
X60599D01*
X55997Y277939D01*
Y288151D01*
X50800Y293348D01*
Y316528D01*
X55500Y321228D01*
Y327900D01*
X53000Y330400D01*
X52500D01*
X50300Y332600D01*
Y338200D01*
X52000Y339900D01*
Y342000D01*
X54200Y344200D01*
X63900D01*
X66300Y346600D01*
Y347900D01*
X66350Y347950D01*
G01X713970Y310860D02*
X711760D01*
X706219Y305319D01*
X705159D01*
X700190Y300350D01*
Y283991D01*
X697255Y281056D01*
Y267098D01*
G01X725725Y241560D02*
X723240D01*
X720368Y244432D01*
X716045D01*
X711579Y248898D01*
X702002D01*
X697255Y253645D01*
Y267098D01*
G01X1380890Y615820D02*
X1379334Y614264D01*
Y613234D01*
X1378177Y612077D01*
Y588855D01*
X1378200Y588832D01*
Y587925D01*
X1379789Y586336D01*
Y582600D01*
X1379053Y581864D01*
G01X1743000Y574500D02*
X1744903Y576403D01*
G01D02*
X1750200Y581700D01*
X1760600D01*
X1762300Y580000D01*
X1775490D01*
X1788590Y566900D01*
X1792100D01*
G01X1739211Y596711D02*
X1740767Y598267D01*
X1743223D01*
X1744903Y596587D01*
Y576403D01*
G01X1739211Y596711D02*
X1736422Y599500D01*
X1725500D01*
X1721500Y595500D01*
Y594000D01*
X1719502Y592002D01*
X1718008D01*
G01X1792100Y566900D02*
X1791540Y567460D01*
Y571610D01*
X1788380Y574770D01*
Y580740D01*
X1785050Y584070D01*
Y584550D01*
G54D19*
X82643Y105000D03*
X77721D03*
G54D38*
G01X146299Y-42355D02*
X443147D01*
G02Y-45915I0J-1780D01*
G01X145585D01*
X144200Y-47300D01*
X125550D01*
X120500Y-42250D01*
G01X130313Y17157D02*
X129192Y16036D01*
Y13100D01*
X132092Y10200D01*
Y8232D01*
X130559Y6699D01*
Y5500D01*
X131809Y4250D01*
Y3350D01*
X130459Y2000D01*
Y701D01*
X132092Y-932D01*
Y-3233D01*
X132959Y-4100D01*
G01X130313Y17157D02*
Y18479D01*
X129880Y18912D01*
Y23489D01*
X132180Y25789D01*
Y28461D01*
X131030Y29611D01*
Y34239D01*
X132380Y35589D01*
Y36912D01*
X131792Y37500D01*
Y45612D01*
X132380Y46200D01*
Y47564D01*
X131030Y48914D01*
Y53138D01*
X132380Y54488D01*
Y66061D01*
X131030Y67411D01*
Y72039D01*
X132380Y73389D01*
Y74812D01*
X131592Y75600D01*
Y83312D01*
X132380Y84100D01*
Y85364D01*
X131030Y86714D01*
Y90938D01*
X132192Y92100D01*
Y93588D01*
X130492Y95288D01*
Y153757D01*
X131535Y154800D01*
X133525D01*
X134692Y155967D01*
Y157957D01*
X135735Y159000D01*
X138493D01*
X139392Y159899D01*
Y162657D01*
X140535Y163800D01*
X144192D01*
X144892Y164500D01*
Y166495D01*
X145635Y167238D01*
X149563D01*
X150064Y167739D01*
Y173329D01*
X238365Y261630D01*
X260369D01*
G01X160431Y17157D02*
X159503Y16229D01*
Y13101D01*
X162303Y10301D01*
Y8432D01*
X160920Y7049D01*
Y5650D01*
X162370Y4200D01*
Y3000D01*
X160870Y1500D01*
Y301D01*
X162303Y-1132D01*
Y-3012D01*
X163391Y-4100D01*
G01X160431Y17157D02*
X162391Y19117D01*
Y28501D01*
X161491Y29401D01*
Y34299D01*
X162292Y35100D01*
Y36900D01*
X161492Y37700D01*
Y45200D01*
X162292Y46000D01*
Y47813D01*
X161592Y48513D01*
Y53515D01*
X162292Y54215D01*
Y66300D01*
X161492Y67100D01*
Y72100D01*
X162292Y72900D01*
Y75000D01*
X161992Y75300D01*
Y83600D01*
X162292Y83900D01*
Y85613D01*
X161592Y86313D01*
Y91199D01*
X162480Y92087D01*
Y147071D01*
X252351Y236942D01*
X257250D01*
G01X163477Y12114D02*
X164703Y10888D01*
Y-2125D01*
X165478Y-2900D01*
Y-4524D01*
X163902Y-6100D01*
X162678D01*
X160431Y-8347D01*
Y-9901D01*
G01X163477Y12114D02*
X161592Y13999D01*
Y15499D01*
X164492Y18399D01*
Y28000D01*
X165341Y28849D01*
Y33800D01*
X165239Y34500D01*
X165192Y34822D01*
Y37601D01*
X165592Y38001D01*
Y45700D01*
X164991Y46301D01*
Y47500D01*
X165341Y49900D01*
Y53614D01*
X165091Y53864D01*
Y66399D01*
X165341Y66649D01*
Y71600D01*
X165092Y73900D01*
Y74400D01*
X165416Y75500D01*
X165592Y76100D01*
Y83499D01*
X164991Y84100D01*
Y84800D01*
X165289Y87266D01*
X165341Y87700D01*
Y95600D01*
X166392Y96651D01*
Y98049D01*
X165341Y99100D01*
Y146396D01*
X253387Y234442D01*
X257448D01*
G01X132959Y12114D02*
X134432Y10641D01*
Y-2484D01*
X135048Y-3100D01*
Y-4444D01*
X133592Y-5900D01*
X132192D01*
X130313Y-7779D01*
Y-9901D01*
G01X132959Y12114D02*
X130886Y14187D01*
Y15194D01*
X132380Y16688D01*
Y22689D01*
X134880Y25189D01*
Y37300D01*
X135446Y37866D01*
Y45446D01*
X134880Y46012D01*
Y74988D01*
X135492Y75600D01*
Y83388D01*
X134880Y84000D01*
Y94600D01*
X132992Y96488D01*
Y151601D01*
X136196Y154804D01*
X137791Y156400D01*
X139873D01*
X147844Y164371D01*
X149362D01*
X152332Y167341D01*
Y172061D01*
X239401Y259130D01*
X260086D01*
G01X153738Y17157D02*
X152617Y16036D01*
Y13100D01*
X155959Y9758D01*
Y8700D01*
X154159Y6900D01*
Y5325D01*
X155359Y4125D01*
Y2999D01*
X154159Y1799D01*
Y426D01*
X155517Y-932D01*
Y-2133D01*
X157084Y-3700D01*
G01X153738Y17157D02*
X154692Y18111D01*
Y25712D01*
X155980Y27000D01*
Y28199D01*
X155180Y28999D01*
Y34687D01*
X155680Y35187D01*
Y36800D01*
X155092Y37388D01*
Y45700D01*
X155680Y46288D01*
Y48014D01*
X155080Y48614D01*
Y53314D01*
X156030Y54264D01*
Y65949D01*
X155180Y66799D01*
Y72587D01*
X155680Y73087D01*
Y74912D01*
X155192Y75400D01*
Y83612D01*
X155680Y84100D01*
Y85814D01*
X155080Y86414D01*
Y91114D01*
X155692Y91726D01*
Y100801D01*
X156828Y101937D01*
Y128099D01*
X156268Y128659D01*
X154652D01*
X154092Y129219D01*
Y130659D01*
X154652Y131219D01*
X156268D01*
X156828Y131779D01*
Y149153D01*
X186503Y178828D01*
Y179690D01*
X184530Y181663D01*
Y182525D01*
X185394Y183389D01*
X186256D01*
X188229Y181416D01*
X189091D01*
X189955Y182280D01*
Y183142D01*
X187982Y185115D01*
Y185977D01*
X188846Y186841D01*
X189708D01*
X191681Y184868D01*
X192543D01*
X193407Y185732D01*
Y186594D01*
X191434Y188567D01*
Y189429D01*
X192298Y190293D01*
X193160D01*
X195133Y188320D01*
X195995D01*
X196859Y189184D01*
Y190046D01*
X194886Y192019D01*
Y192881D01*
X195750Y193745D01*
X196612D01*
X198585Y191772D01*
X199447D01*
X200311Y192636D01*
Y193498D01*
X198338Y195471D01*
Y196333D01*
X199202Y197197D01*
X200064D01*
X202037Y195224D01*
X202899D01*
X203763Y196088D01*
Y196950D01*
X201790Y198923D01*
Y199785D01*
X202654Y200649D01*
X203516D01*
X205489Y198676D01*
X206351D01*
X207215Y199540D01*
Y200402D01*
X205242Y202375D01*
Y203237D01*
X206106Y204101D01*
X206968D01*
X208941Y202128D01*
X209803D01*
X211496Y203821D01*
Y209800D01*
X232768Y231072D01*
X236280D01*
X248688Y243480D01*
X259009D01*
G01X157084Y12114D02*
X158473Y10725D01*
Y-2288D01*
X159085Y-2900D01*
Y-4300D01*
X157285Y-6100D01*
X156285D01*
X154985Y-7400D01*
Y-8654D01*
X153738Y-9901D01*
G01X157084Y12114D02*
X155180Y14018D01*
Y15614D01*
X158530Y18964D01*
Y22062D01*
X157392Y23200D01*
Y24500D01*
X158530Y25638D01*
Y28699D01*
X159080Y29249D01*
Y34911D01*
X158480Y35511D01*
Y37100D01*
X159092Y37712D01*
Y45500D01*
X158480Y46112D01*
Y48064D01*
X158991Y48575D01*
Y53453D01*
X158530Y53914D01*
Y66499D01*
X159030Y66999D01*
Y72461D01*
X158480Y73011D01*
Y75200D01*
X158892Y75612D01*
Y83600D01*
X158480Y84012D01*
Y85914D01*
X159180Y86614D01*
Y91274D01*
X158192Y92262D01*
Y94139D01*
X159188Y95135D01*
Y148130D01*
X216794Y205736D01*
Y206598D01*
X214639Y208753D01*
Y209615D01*
X215503Y210479D01*
X216365D01*
X218520Y208324D01*
X219382D01*
X220246Y209188D01*
Y210050D01*
X218091Y212205D01*
Y213067D01*
X218955Y213931D01*
X219817D01*
X221972Y211776D01*
X222834D01*
X223698Y212640D01*
Y213502D01*
X221543Y215657D01*
Y216519D01*
X222407Y217383D01*
X223269D01*
X225424Y215228D01*
X226286D01*
X227150Y216092D01*
Y216954D01*
X224995Y219109D01*
Y219971D01*
X225859Y220835D01*
X226721D01*
X228876Y218680D01*
X229738D01*
X230602Y219544D01*
Y220406D01*
X228447Y222561D01*
Y223423D01*
X229311Y224287D01*
X230173D01*
X232328Y222132D01*
X233190D01*
X234054Y222996D01*
Y223858D01*
X231899Y226013D01*
Y226875D01*
X232763Y227739D01*
X233625D01*
X235780Y225584D01*
X236642D01*
X252038Y240980D01*
X259087D01*
G01X126580Y-4100D02*
X125492Y-3012D01*
Y-1132D01*
X124059Y301D01*
Y1500D01*
X125559Y3000D01*
Y4200D01*
X124109Y5650D01*
Y7049D01*
X125492Y8432D01*
Y10301D01*
X122692Y13101D01*
Y16229D01*
X123620Y17157D01*
G01X259321Y266630D02*
X237821D01*
X125492Y154301D01*
Y92026D01*
X124680Y91214D01*
Y86414D01*
X125680Y85414D01*
Y83988D01*
X124992Y83300D01*
Y75400D01*
X125680Y74712D01*
Y73099D01*
X124680Y72099D01*
Y67111D01*
X125580Y66211D01*
Y54314D01*
X124680Y53414D01*
Y48614D01*
X125680Y47614D01*
Y46300D01*
X124992Y45612D01*
Y37800D01*
X125680Y37112D01*
Y35587D01*
X124680Y34587D01*
Y29411D01*
X125580Y28511D01*
Y27087D01*
X123620Y25127D01*
Y17157D01*
G01X126666Y12114D02*
X124792Y13988D01*
Y15626D01*
X125858Y16692D01*
X128392Y28156D01*
Y37400D01*
X128792Y37800D01*
Y45700D01*
X128292Y46200D01*
Y48426D01*
X128492Y48626D01*
Y53652D01*
X128280Y53864D01*
Y64800D01*
X128392Y66144D01*
Y83788D01*
X128180Y84000D01*
Y84900D01*
X128530Y87500D01*
Y90360D01*
X127992Y93160D01*
Y153993D01*
X144646Y170647D01*
X146936D01*
X147496Y171207D01*
Y173497D01*
X238129Y264130D01*
X260368D01*
G01X123620Y-9901D02*
Y-8347D01*
X125867Y-6100D01*
X127091D01*
X128667Y-4524D01*
Y-2900D01*
X127892Y-2125D01*
Y10888D01*
X126666Y12114D01*
G01X150391Y-3700D02*
X148917Y-2226D01*
Y-1132D01*
X147484Y301D01*
Y1524D01*
X148984Y3024D01*
Y4376D01*
X147484Y5876D01*
Y6999D01*
X149159Y8674D01*
Y10059D01*
X146117Y13101D01*
Y16229D01*
X147045Y17157D01*
G01D02*
X149080Y19192D01*
Y28311D01*
X148480Y28911D01*
Y35087D01*
X149280Y35887D01*
Y37012D01*
X148692Y37600D01*
Y45712D01*
X149280Y46300D01*
Y47914D01*
X148480Y48714D01*
Y53414D01*
X148880Y53814D01*
Y66499D01*
X148480Y66899D01*
Y72687D01*
X149280Y73487D01*
Y74712D01*
X148492Y75500D01*
Y83312D01*
X149280Y84100D01*
Y85714D01*
X148480Y86514D01*
Y91214D01*
X148880Y91614D01*
Y98812D01*
X143092Y104600D01*
Y124300D01*
X143892Y125100D01*
X145492D01*
X146292Y124300D01*
Y111900D01*
X147192Y111000D01*
X148692D01*
X149492Y111800D01*
Y148584D01*
X164600Y163692D01*
Y164554D01*
X162170Y166984D01*
Y167846D01*
X163034Y168710D01*
X163896D01*
X166326Y166280D01*
X167188D01*
X168973Y168065D01*
Y174349D01*
X231274Y236650D01*
X233168D01*
X245003Y248485D01*
X258506D01*
G01X150391Y12114D02*
X148542Y13963D01*
Y15650D01*
X151892Y19000D01*
Y28499D01*
X152680Y29287D01*
Y34611D01*
X151780Y35511D01*
Y36900D01*
X152492Y37612D01*
Y45600D01*
X151780Y46312D01*
Y47914D01*
X152580Y48714D01*
Y53214D01*
X151880Y53914D01*
Y66499D01*
X152680Y67299D01*
Y72211D01*
X151780Y73111D01*
Y74788D01*
X152292Y75300D01*
Y83388D01*
X151780Y83900D01*
Y85714D01*
X152580Y86514D01*
Y91014D01*
X151880Y91714D01*
Y104600D01*
X151380Y105100D01*
X146392D01*
X145592Y105900D01*
Y106957D01*
X146435Y107800D01*
X151032D01*
X151592Y108360D01*
Y134200D01*
X154433Y137041D01*
Y138990D01*
X153873Y139550D01*
X152152D01*
X151592Y140110D01*
Y141550D01*
X152152Y142110D01*
X153873D01*
X154433Y142670D01*
Y144110D01*
X153873Y144670D01*
X152152D01*
X151592Y145230D01*
Y146670D01*
X152152Y147230D01*
X153873D01*
X154433Y147790D01*
Y149685D01*
X174362Y169614D01*
Y170476D01*
X172207Y172631D01*
Y173493D01*
X173071Y174357D01*
X173933D01*
X176088Y172202D01*
X176950D01*
X177814Y173066D01*
Y173928D01*
X175659Y176083D01*
Y176945D01*
X176523Y177809D01*
X177385D01*
X179540Y175654D01*
X180402D01*
X181775Y177027D01*
Y183615D01*
X231700Y233540D01*
X234264D01*
X246704Y245980D01*
X257772D01*
G01X147045Y-9901D02*
X148292Y-8654D01*
Y-7400D01*
X149592Y-6100D01*
X150592D01*
X152392Y-4300D01*
Y-2900D01*
X151780Y-2288D01*
Y10725D01*
X150391Y12114D01*
G01X167124Y17157D02*
Y24732D01*
X168991Y26599D01*
Y28451D01*
X167841Y29601D01*
Y34249D01*
X169191Y35599D01*
Y36800D01*
X168392Y37599D01*
Y45500D01*
X169191Y46299D01*
Y47564D01*
X167841Y48914D01*
Y53248D01*
X169191Y54598D01*
Y66051D01*
X167841Y67401D01*
Y72149D01*
X169191Y73499D01*
Y74601D01*
X168492Y75300D01*
Y83601D01*
X169191Y84300D01*
Y85364D01*
X167841Y86714D01*
Y90998D01*
X168992Y92149D01*
Y100468D01*
X168241Y101219D01*
Y145760D01*
X190865Y168384D01*
X191727D01*
X193021Y167090D01*
X193882D01*
X194746Y167954D01*
Y168816D01*
X193453Y170109D01*
Y170972D01*
X194317Y171836D01*
X195178D01*
X196522Y170492D01*
X197384D01*
X198248Y171356D01*
Y172219D01*
X196905Y173562D01*
Y174424D01*
X254023Y231542D01*
X257128D01*
G01X169770Y-4100D02*
X168903Y-3233D01*
Y-932D01*
X167270Y701D01*
Y2000D01*
X168620Y3350D01*
Y4250D01*
X167370Y5500D01*
Y6699D01*
X168903Y8232D01*
Y10200D01*
X166003Y13100D01*
Y16036D01*
X167124Y17157D01*
G01X169770Y12114D02*
X167697Y14187D01*
Y15204D01*
X169191Y16698D01*
Y22999D01*
X171691Y25499D01*
Y37200D01*
X172292Y37801D01*
Y45650D01*
X171691Y46251D01*
Y74799D01*
X172292Y75400D01*
Y83199D01*
X171691Y83800D01*
Y101516D01*
X170253Y102954D01*
Y144236D01*
X189817Y163800D01*
X193697D01*
X200846Y170949D01*
Y174829D01*
X255059Y229042D01*
X257128D01*
G01X167124Y-9901D02*
Y-7779D01*
X169003Y-5900D01*
X170403D01*
X171859Y-4444D01*
Y-3100D01*
X171243Y-2484D01*
Y10641D01*
X169770Y12114D01*
G01X141880Y14514D02*
X143706Y16340D01*
Y17900D01*
X141686Y19920D01*
Y20788D01*
X144960Y24062D01*
Y98403D01*
X140472Y102891D01*
Y126939D01*
X141344Y127811D01*
X145496D01*
X146988Y129303D01*
Y132579D01*
X145396Y134171D01*
X142093D01*
X140670Y135594D01*
Y137521D01*
X141569Y138420D01*
X143729D01*
X144960Y139651D01*
Y147892D01*
X159371Y162303D01*
Y168451D01*
X232693Y241773D01*
X233329D01*
X234037Y242481D01*
Y243117D01*
X234979Y244059D01*
X235615D01*
X236323Y244767D01*
Y245403D01*
X237516Y246596D01*
X238153D01*
X238861Y247304D01*
Y247941D01*
X240349Y249429D01*
X240985D01*
X241693Y250137D01*
Y250773D01*
X242400Y251480D01*
X245113D01*
X245563Y251030D01*
X246563D01*
X247013Y251480D01*
X248177D01*
X248627Y251030D01*
X249627D01*
X250077Y251480D01*
X251240D01*
X251690Y251030D01*
X252690D01*
X253140Y251480D01*
X255401D01*
X255851Y251030D01*
X256851D01*
X257301Y251480D01*
X261014D01*
G01X141880Y-7260D02*
X145072Y-4068D01*
Y11322D01*
X141880Y14514D01*
G01X136780Y14300D02*
X138506Y16026D01*
Y18100D01*
X137706Y18900D01*
X136706D01*
X135986Y19620D01*
Y20688D01*
X139860Y24562D01*
Y37780D01*
X140484Y38404D01*
Y39396D01*
X139860Y40020D01*
Y40780D01*
X140484Y41404D01*
Y42396D01*
X139860Y43020D01*
Y43780D01*
X140484Y44404D01*
Y45396D01*
X139860Y46020D01*
Y55680D01*
X140484Y56304D01*
Y57296D01*
X139860Y57920D01*
Y78536D01*
X140772Y79448D01*
Y82940D01*
X139860Y83852D01*
Y96403D01*
X136672Y99591D01*
Y110189D01*
X137122Y110639D01*
Y111639D01*
X136672Y112089D01*
Y113436D01*
X137122Y113886D01*
Y114886D01*
X136672Y115336D01*
Y117825D01*
X137122Y118275D01*
Y119275D01*
X136672Y119725D01*
Y122718D01*
X137122Y123168D01*
Y124168D01*
X136672Y124618D01*
Y128648D01*
X138017Y129993D01*
Y132875D01*
X136672Y134220D01*
Y141307D01*
X137544Y142179D01*
X138743D01*
X140487Y143923D01*
Y146667D01*
X138366Y148788D01*
Y152364D01*
X138874Y152872D01*
X145506D01*
X148068Y155434D01*
Y160428D01*
X149066Y161426D01*
X153417D01*
X155576Y163585D01*
Y170098D01*
X230069Y244591D01*
X230705D01*
X231413Y245299D01*
Y245935D01*
X232120Y246642D01*
X232757D01*
X233465Y247350D01*
Y247987D01*
X234178Y248700D01*
X234815D01*
X235523Y249408D01*
Y250045D01*
X236533Y251055D01*
X237170D01*
X237878Y251763D01*
Y252400D01*
X238807Y253329D01*
X239443D01*
X240151Y254037D01*
Y254673D01*
X240858Y255380D01*
X242964D01*
X243414Y254930D01*
X244414D01*
X244864Y255380D01*
X246073D01*
X246523Y254930D01*
X247523D01*
X247973Y255380D01*
X249300D01*
X249750Y254930D01*
X250750D01*
X251200Y255380D01*
X252200D01*
X252650Y254930D01*
X253650D01*
X254100Y255380D01*
X255892D01*
X256342Y254930D01*
X257342D01*
X257792Y255380D01*
X258792D01*
G01X136806Y-7050D02*
X137576Y-6280D01*
X138558D01*
X139886Y-4952D01*
Y11194D01*
X136780Y14300D01*
G01X141880Y11914D02*
X140156Y13638D01*
Y18365D01*
X140626Y18835D01*
Y21231D01*
X143900Y24505D01*
Y97960D01*
X139412Y102448D01*
Y127382D01*
X140901Y128871D01*
X145056D01*
X145928Y129743D01*
Y132139D01*
X144956Y133111D01*
X141653D01*
X139610Y135154D01*
Y137961D01*
X141129Y139480D01*
X143289D01*
X143900Y140091D01*
Y148332D01*
X158311Y162743D01*
Y168891D01*
X241960Y252540D01*
X261014D01*
G01X141880Y-4651D02*
X142989D01*
X144012Y-3628D01*
Y-1007D01*
X143305Y-300D01*
X142507D01*
X141906Y301D01*
Y1499D01*
X142507Y2100D01*
X143205D01*
X144012Y2907D01*
Y4280D01*
X143292Y5000D01*
X142792D01*
X142092Y5700D01*
Y6700D01*
X142792Y7400D01*
X143306D01*
X144012Y8106D01*
Y10881D01*
X142978Y11915D01*
X141880D01*
Y11914D01*
G01X136780Y11700D02*
X134926Y13554D01*
Y21131D01*
X138800Y25005D01*
Y78979D01*
X139712Y79891D01*
Y82497D01*
X138800Y83409D01*
Y95960D01*
X135612Y99148D01*
Y129088D01*
X136957Y130433D01*
Y132435D01*
X135612Y133780D01*
Y141747D01*
X137104Y143239D01*
X138303D01*
X139423Y144359D01*
Y146231D01*
X137306Y148348D01*
Y152804D01*
X138434Y153932D01*
X145066D01*
X147008Y155874D01*
Y160868D01*
X148626Y162486D01*
X152977D01*
X154516Y164025D01*
Y170538D01*
X240418Y256440D01*
X258792D01*
G01X136780Y-4401D02*
X137599Y-5220D01*
X138115D01*
X138826Y-4509D01*
Y-1220D01*
X136906Y700D01*
Y1700D01*
X137506Y2300D01*
X138006D01*
X138826Y3120D01*
Y4080D01*
X138106Y4800D01*
X137394D01*
X136892Y5302D01*
Y6634D01*
X137508Y7250D01*
X137856D01*
X138826Y8220D01*
Y10753D01*
X137879Y11700D01*
X136780D01*
G01X252888Y342428D02*
X246401D01*
X203462Y385367D01*
Y387931D01*
X191143Y400250D01*
X169550D01*
X164092Y405708D01*
Y413301D01*
X154892Y422501D01*
Y424701D01*
X137293Y442300D01*
X135287D01*
X132192Y445395D01*
Y498800D01*
X130426Y500566D01*
Y507434D01*
X132380Y509388D01*
Y510711D01*
X131159Y511932D01*
Y516568D01*
X132492Y517901D01*
Y519288D01*
X131992Y519788D01*
Y527200D01*
X132380Y527588D01*
Y529267D01*
X131030Y530617D01*
Y535238D01*
X132380Y536588D01*
Y537700D01*
X131992Y538088D01*
Y546300D01*
X132380Y546688D01*
Y548507D01*
X131030Y549857D01*
Y554107D01*
X132180Y555257D01*
Y557100D01*
X131992Y557288D01*
Y565400D01*
X132180Y565588D01*
Y567267D01*
X131080Y568367D01*
Y573089D01*
X132230Y574239D01*
Y575600D01*
X131992Y575838D01*
Y584400D01*
X132230Y584638D01*
Y586457D01*
X128880Y589807D01*
Y592324D01*
X130313Y593757D01*
G01X256398Y338600D02*
X244896D01*
X199692Y383804D01*
Y386201D01*
X189643Y396250D01*
X167643D01*
X159792Y404101D01*
X157317Y410075D01*
X155644Y411748D01*
X152765Y415541D01*
X150792Y420302D01*
Y423300D01*
X136892Y437200D01*
X134995D01*
X127192Y445003D01*
Y495384D01*
X125811Y498717D01*
X125492Y499488D01*
Y510716D01*
X125374Y511000D01*
X125208Y511400D01*
X124680Y512677D01*
Y516083D01*
X125580Y518256D01*
Y528650D01*
X124680Y530824D01*
Y534863D01*
X125492Y536824D01*
Y548745D01*
X124853Y550288D01*
Y553917D01*
X125580Y555672D01*
Y566560D01*
X124755Y568552D01*
Y572875D01*
X125325Y574251D01*
Y586137D01*
X124626Y587825D01*
X123155Y589296D01*
Y593292D01*
X123620Y593757D01*
G01X126666Y588714D02*
X128180Y587200D01*
Y584512D01*
X128692Y584000D01*
Y575712D01*
X128180Y575200D01*
Y573256D01*
X128780Y572656D01*
Y568497D01*
X128280Y567997D01*
Y565612D01*
X128692Y565200D01*
Y557612D01*
X128280Y557200D01*
Y555257D01*
X128530Y555007D01*
Y548807D01*
X128180Y548457D01*
Y547012D01*
X128692Y546500D01*
Y538100D01*
X128180Y537588D01*
Y535542D01*
X128530Y535192D01*
Y530242D01*
X128280Y529992D01*
Y528112D01*
X128692Y527700D01*
Y519812D01*
X128280Y519400D01*
Y517457D01*
X128530Y517207D01*
Y511747D01*
X128037Y511254D01*
Y499555D01*
X129692Y497900D01*
Y445185D01*
X135326Y439551D01*
X137341D01*
X152992Y423900D01*
Y420019D01*
X154123Y417288D01*
X155655Y414995D01*
X156950Y413700D01*
X160893D01*
X161692Y412901D01*
Y405000D01*
X168342Y398350D01*
X190243D01*
X201577Y387016D01*
Y384585D01*
X245662Y340500D01*
X256756D01*
G01X254448Y367427D02*
X254421Y367400D01*
X249328D01*
X232592Y384136D01*
Y393256D01*
X163292Y462556D01*
Y500100D01*
X160792Y502600D01*
Y507600D01*
X162163Y508971D01*
Y511125D01*
X161491Y511797D01*
Y516457D01*
X162233Y517199D01*
Y519658D01*
X162092Y519799D01*
Y527801D01*
X162232Y527941D01*
Y529661D01*
X161491Y530402D01*
Y535242D01*
X162299Y536050D01*
Y537792D01*
X162092Y537999D01*
Y546000D01*
X162491Y546399D01*
Y548557D01*
X161491Y549557D01*
Y554257D01*
X162391Y555157D01*
Y557000D01*
X162092Y557299D01*
Y565400D01*
X162391Y565699D01*
Y567201D01*
X161343Y568249D01*
Y572944D01*
X162341Y573942D01*
Y575600D01*
X162092Y575849D01*
Y583800D01*
X162341Y584049D01*
Y586457D01*
X159191Y589607D01*
Y592517D01*
X160431Y593757D01*
G01X253558Y369931D02*
X253389Y370100D01*
X249294D01*
X234492Y384902D01*
Y394892D01*
X166325Y463059D01*
Y466400D01*
X165292Y467433D01*
Y468767D01*
X166325Y469800D01*
Y474268D01*
X165292Y475301D01*
Y476899D01*
X166325Y477932D01*
Y480068D01*
X165392Y481001D01*
Y482367D01*
X166325Y483300D01*
Y487500D01*
X165192Y488633D01*
Y490867D01*
X166325Y492000D01*
Y495468D01*
X165292Y496501D01*
Y497799D01*
X166325Y498832D01*
Y502377D01*
X165522Y503180D01*
X164092D01*
X163592Y503680D01*
Y505880D01*
X164092Y506380D01*
X165783D01*
X166351Y506948D01*
Y508258D01*
X165091Y509518D01*
Y511497D01*
X165809Y512215D01*
Y516291D01*
X164729Y517371D01*
Y520162D01*
X165492Y520925D01*
Y527364D01*
X164828Y528028D01*
Y529729D01*
X165341Y530242D01*
Y535192D01*
X164759Y535774D01*
Y537814D01*
X165492Y538547D01*
Y546200D01*
X164991Y546701D01*
Y548457D01*
X165341Y548807D01*
Y554417D01*
X164617Y555141D01*
Y556626D01*
X165492Y557501D01*
Y565500D01*
X165091Y565901D01*
Y567997D01*
X165591Y568497D01*
Y572656D01*
X164991Y573256D01*
Y575400D01*
X165492Y575901D01*
Y583800D01*
X164991Y584301D01*
Y587200D01*
X163477Y588714D01*
G01X252989Y344928D02*
X246567D01*
X205347Y386148D01*
Y389014D01*
X192211Y402150D01*
X171542D01*
X169700Y403992D01*
Y410493D01*
X156892Y423301D01*
Y425401D01*
X140792Y441501D01*
Y444200D01*
X140092Y444900D01*
X135592D01*
X134692Y445800D01*
Y448268D01*
X135252Y448828D01*
X141232D01*
X141792Y449388D01*
Y450828D01*
X141232Y451388D01*
X135252D01*
X134692Y451948D01*
Y459800D01*
X136192Y461300D01*
Y462900D01*
X134692Y464400D01*
Y499300D01*
X135292Y499900D01*
Y502422D01*
X134682Y503032D01*
X133472D01*
X132862Y503642D01*
Y505622D01*
X133472Y506232D01*
X134682D01*
X135292Y506842D01*
Y508400D01*
X134880Y508812D01*
Y518888D01*
X135392Y519400D01*
Y527500D01*
X134880Y528012D01*
Y537688D01*
X135392Y538200D01*
Y546100D01*
X134880Y546612D01*
Y556188D01*
X135292Y556600D01*
Y565500D01*
X134880Y565912D01*
Y575600D01*
X135292Y576012D01*
Y583700D01*
X134880Y584112D01*
Y586443D01*
X132959Y588364D01*
Y588714D01*
G01X249621Y360856D02*
X249577Y360900D01*
X247792D01*
X220092Y388600D01*
Y396562D01*
X199954Y416700D01*
X190903D01*
X179406Y428197D01*
Y429129D01*
X180537Y430260D01*
X181869D01*
X193094Y419035D01*
X194226D01*
X195357Y420166D01*
Y421298D01*
X182069Y434586D01*
X180837D01*
X177443Y431192D01*
X176411D01*
X156292Y451311D01*
Y454400D01*
X158473Y456581D01*
Y458182D01*
X156292Y460363D01*
Y499000D01*
X155142Y500150D01*
Y508450D01*
X155680Y508988D01*
Y511157D01*
X155180Y511657D01*
Y516489D01*
X156292Y517601D01*
Y529154D01*
X155080Y530366D01*
Y535688D01*
X156092Y536700D01*
Y538000D01*
X155392Y538700D01*
Y546700D01*
X156092Y547400D01*
Y549101D01*
X155180Y550013D01*
Y554389D01*
X156192Y555401D01*
Y556888D01*
X155392Y557688D01*
Y564700D01*
X156192Y565500D01*
Y567085D01*
X154880Y568397D01*
Y573142D01*
X155992Y574254D01*
Y576400D01*
X155192Y577200D01*
Y584000D01*
X155780Y584588D01*
Y586507D01*
X152380Y589907D01*
Y592399D01*
X153738Y593757D01*
G01X249205Y363373D02*
X248419D01*
X222692Y389100D01*
Y397499D01*
X182008Y438183D01*
X180876D01*
X177482Y434789D01*
X176350D01*
X158881Y452258D01*
Y453390D01*
X160012Y454521D01*
X161144D01*
X176512Y439153D01*
X177644D01*
X178775Y440284D01*
Y441416D01*
X158792Y461399D01*
Y464038D01*
X159988Y465234D01*
Y467238D01*
X158792Y468434D01*
Y470438D01*
X159988Y471634D01*
Y473638D01*
X158792Y474834D01*
Y476838D01*
X159988Y478034D01*
Y480038D01*
X158792Y481234D01*
Y483238D01*
X159988Y484434D01*
Y486438D01*
X158792Y487634D01*
Y489638D01*
X159988Y490834D01*
Y492838D01*
X158792Y494034D01*
Y496038D01*
X159988Y497234D01*
Y499204D01*
X157795Y501397D01*
Y510972D01*
X159080Y512257D01*
Y516807D01*
X158192Y517695D01*
Y520496D01*
X159292Y521596D01*
Y523056D01*
X158192Y524156D01*
Y529478D01*
X159180Y530466D01*
Y535712D01*
X158292Y536600D01*
Y539600D01*
X159492Y540800D01*
Y543300D01*
X158292Y544500D01*
Y549269D01*
X159080Y550057D01*
Y554607D01*
X158530Y555157D01*
Y558800D01*
X159692Y559962D01*
Y562638D01*
X158530Y563800D01*
Y567647D01*
X159380Y568497D01*
Y573012D01*
X158380Y574012D01*
Y576800D01*
X159292Y577712D01*
Y581488D01*
X158380Y582400D01*
Y587470D01*
X157084Y588766D01*
Y588714D01*
G01X147045Y593757D02*
X146380Y593092D01*
Y589257D01*
X149592Y586045D01*
Y584800D01*
X148692Y583900D01*
Y576088D01*
X149280Y575500D01*
Y574242D01*
X147692Y572654D01*
Y568785D01*
X149268Y567209D01*
Y566076D01*
X148692Y565500D01*
Y557388D01*
X149335Y556745D01*
Y555144D01*
X148092Y553901D01*
Y550245D01*
X149280Y549057D01*
Y546788D01*
X148692Y546200D01*
Y539200D01*
X149543Y538349D01*
Y536851D01*
X147992Y535300D01*
Y530730D01*
X149291Y529431D01*
Y528299D01*
X148692Y527700D01*
Y519788D01*
X149435Y519045D01*
Y517544D01*
X147892Y516001D01*
Y512201D01*
X149492Y510601D01*
Y509700D01*
X147792Y508000D01*
Y500900D01*
X151292Y497400D01*
Y491900D01*
X149892Y490500D01*
Y489004D01*
X151292Y487604D01*
Y442100D01*
X164792Y428600D01*
Y426600D01*
X171632Y419760D01*
X172424D01*
X176582Y423918D01*
X177374D01*
X178393Y422899D01*
Y422107D01*
X174235Y417949D01*
Y417157D01*
X175254Y416138D01*
X176046D01*
X180204Y420296D01*
X180996D01*
X182015Y419277D01*
Y418485D01*
X177857Y414327D01*
Y413535D01*
X178592Y412800D01*
X195956D01*
X214292Y394464D01*
Y388600D01*
X247156Y355736D01*
X249457D01*
G01X249436Y358236D02*
X249072Y358600D01*
X247092D01*
X217192Y388500D01*
Y395100D01*
X197492Y414800D01*
X189266D01*
X173407Y430659D01*
X172615D01*
X170070Y428114D01*
X169178D01*
X168167Y429125D01*
Y429833D01*
X170804Y432470D01*
Y433262D01*
X169785Y434281D01*
X168993D01*
X165848Y431136D01*
X165056D01*
X164037Y432155D01*
Y432947D01*
X167182Y436092D01*
Y436884D01*
X166163Y437903D01*
X165371D01*
X162226Y434758D01*
X161434D01*
X160415Y435777D01*
Y436569D01*
X163560Y439714D01*
Y440506D01*
X162541Y441525D01*
X161749D01*
X158604Y438380D01*
X157812D01*
X156793Y439399D01*
Y440191D01*
X159938Y443336D01*
Y444128D01*
X158919Y445147D01*
X158127D01*
X154982Y442002D01*
X154190D01*
X153171Y443021D01*
Y443813D01*
X156316Y446958D01*
Y447750D01*
X153792Y450274D01*
Y498700D01*
X153014Y499478D01*
Y502454D01*
X152404Y503064D01*
X150343D01*
X149733Y503674D01*
Y505654D01*
X150343Y506264D01*
X152404D01*
X153014Y506874D01*
Y507878D01*
X151780Y509112D01*
Y511257D01*
X152892Y512369D01*
Y516001D01*
X151475Y517418D01*
Y519483D01*
X152759Y520767D01*
Y527033D01*
X151481Y528311D01*
Y529443D01*
X152892Y530854D01*
Y535200D01*
X151492Y536600D01*
Y538300D01*
X152092Y538900D01*
Y546200D01*
X151392Y546900D01*
Y548669D01*
X152792Y550069D01*
Y553901D01*
X151375Y555318D01*
Y556795D01*
X152092Y557512D01*
Y565700D01*
X151604Y566188D01*
Y567321D01*
X152692Y568409D01*
Y573099D01*
X151292Y574499D01*
Y575700D01*
X152092Y576500D01*
Y584200D01*
X151780Y584512D01*
Y587368D01*
X151737D01*
X150391Y588714D01*
G01X253248Y372601D02*
X253149Y372700D01*
X249360D01*
X236792Y385268D01*
Y396128D01*
X168292Y464628D01*
Y492218D01*
X169092Y493018D01*
X169792D01*
X170592Y493818D01*
Y495418D01*
X169792Y496218D01*
X169092D01*
X168292Y497018D01*
Y508100D01*
X168892Y508700D01*
Y511006D01*
X167841Y512057D01*
Y516307D01*
X169191Y517657D01*
Y519600D01*
X167999Y520792D01*
Y526607D01*
X169191Y527799D01*
Y529267D01*
X167841Y530617D01*
Y535350D01*
X169191Y536700D01*
Y537800D01*
X168792Y538199D01*
Y546100D01*
X169191Y546499D01*
Y548507D01*
X167841Y549857D01*
Y554107D01*
X168991Y555257D01*
Y557000D01*
X168792Y557199D01*
Y565500D01*
X168991Y565699D01*
Y567267D01*
X167891Y568367D01*
Y573199D01*
X169041Y574349D01*
Y575500D01*
X168792Y575749D01*
Y584400D01*
X169041Y584649D01*
Y586457D01*
X165691Y589807D01*
Y592324D01*
X167124Y593757D01*
G01X249718Y351676D02*
X246916D01*
X210692Y387900D01*
Y392791D01*
X193643Y409840D01*
X177352D01*
X161832Y425360D01*
Y427360D01*
X147612Y441580D01*
Y468080D01*
X146743Y468949D01*
X143778D01*
X142256Y470471D01*
Y473053D01*
X143712Y474509D01*
X146740D01*
X147612Y475381D01*
Y477077D01*
X146740Y477949D01*
X142960D01*
X141471Y479438D01*
Y482020D01*
X142960Y483509D01*
X146740D01*
X147612Y484381D01*
Y486077D01*
X146740Y486949D01*
X142601D01*
X141112Y488438D01*
Y491020D01*
X142601Y492509D01*
X146560D01*
X147432Y493381D01*
Y495188D01*
X143900Y498720D01*
Y538169D01*
X143427Y538642D01*
Y539642D01*
X143900Y540115D01*
Y541377D01*
X143395Y541882D01*
Y542882D01*
X143900Y543387D01*
Y544502D01*
X143280Y545122D01*
Y546122D01*
X143900Y546742D01*
Y557139D01*
X143280Y557759D01*
Y558759D01*
X143900Y559379D01*
Y560379D01*
X143280Y560999D01*
Y561999D01*
X143900Y562619D01*
Y563619D01*
X143280Y564239D01*
Y565239D01*
X143900Y565859D01*
Y576356D01*
X143280Y576976D01*
Y577976D01*
X143900Y578596D01*
Y579596D01*
X143280Y580216D01*
Y581216D01*
X143900Y581836D01*
Y582836D01*
X143280Y583456D01*
Y584456D01*
X143900Y585076D01*
Y587459D01*
X142845Y588514D01*
X141880D01*
G01X136780Y590900D02*
X136832D01*
X139860Y587872D01*
Y584650D01*
X140480Y584030D01*
Y583030D01*
X139860Y582410D01*
Y581410D01*
X140480Y580790D01*
Y579790D01*
X139860Y579170D01*
Y498637D01*
X138372Y497149D01*
Y467152D01*
X139354Y466170D01*
X143493D01*
X144772Y464891D01*
Y460881D01*
X143283Y459392D01*
X140312D01*
X139812Y458892D01*
Y456452D01*
X140312Y455952D01*
X143283D01*
X144772Y454463D01*
Y441720D01*
X159892Y426600D01*
Y424600D01*
X177192Y407300D01*
X192269D01*
X208292Y391277D01*
Y387370D01*
X246823Y348839D01*
X258105D01*
G01X249718Y352736D02*
X247356D01*
X211752Y388340D01*
Y393231D01*
X194083Y410900D01*
X177792D01*
X162892Y425800D01*
Y427800D01*
X148672Y442020D01*
Y468520D01*
X147183Y470009D01*
X144218D01*
X143316Y470911D01*
Y472613D01*
X144152Y473449D01*
X147180D01*
X148672Y474941D01*
Y477517D01*
X147180Y479009D01*
X143400D01*
X142531Y479878D01*
Y481580D01*
X143400Y482449D01*
X147180D01*
X148672Y483941D01*
Y486520D01*
X147183Y488009D01*
X143044D01*
X142172Y488881D01*
Y490580D01*
X143041Y491449D01*
X147000D01*
X148492Y492941D01*
Y495628D01*
X144960Y499160D01*
Y588070D01*
X141916Y591114D01*
X141880D01*
G01X136780Y588300D02*
X137761D01*
X138800Y587261D01*
Y499080D01*
X137312Y497592D01*
Y466709D01*
X138911Y465110D01*
X143050D01*
X143712Y464448D01*
Y461321D01*
X142843Y460452D01*
X139872D01*
X138752Y459332D01*
Y456012D01*
X139872Y454892D01*
X142843D01*
X143712Y454023D01*
Y441280D01*
X158832Y426160D01*
Y424160D01*
X176752Y406240D01*
X191829D01*
X207232Y390837D01*
Y386930D01*
X246383Y347779D01*
X258105D01*
G01X130313Y593757D02*
X128608Y595462D01*
Y605949D01*
X132959Y610300D01*
G01X160431Y593757D02*
X158726Y595462D01*
Y605635D01*
X163391Y610300D01*
G01X163477Y588714D02*
X163389D01*
X161703Y590400D01*
Y592600D01*
X162203Y593100D01*
Y594999D01*
X161066Y596136D01*
Y597464D01*
X162003Y598401D01*
Y599799D01*
X161066Y600736D01*
Y601964D01*
X162103Y603001D01*
Y603899D01*
X161503Y604499D01*
X160431D01*
G01X132959Y588714D02*
X132871D01*
X131185Y590400D01*
Y592092D01*
X132092Y592999D01*
Y594592D01*
X130948Y595736D01*
Y597156D01*
X131792Y598000D01*
Y599700D01*
X130948Y600544D01*
Y601756D01*
X131892Y602700D01*
Y603900D01*
X131293Y604499D01*
X130313D01*
G01X153738Y593757D02*
X152033Y595462D01*
Y605649D01*
X157084Y610700D01*
G01Y588714D02*
X156996D01*
X155310Y590400D01*
Y592092D01*
X155485Y592267D01*
Y594900D01*
X154373Y596012D01*
Y597088D01*
X155385Y598100D01*
Y599300D01*
X154373Y600312D01*
Y601388D01*
X155510Y602525D01*
Y603799D01*
X154810Y604499D01*
X153738D01*
G01X123620Y593757D02*
X121915Y595462D01*
Y605635D01*
X126580Y610300D01*
G01X126666Y588714D02*
X126578D01*
X124892Y590400D01*
Y592600D01*
X125392Y593100D01*
Y594999D01*
X124255Y596136D01*
Y597464D01*
X125192Y598401D01*
Y599799D01*
X124255Y600736D01*
Y601964D01*
X125292Y603001D01*
Y603899D01*
X124692Y604499D01*
X123620D01*
G01X147045Y593757D02*
X145340Y595462D01*
Y605649D01*
X150391Y610700D01*
G01Y588714D02*
X150303D01*
X148617Y590400D01*
Y592092D01*
X148792Y592267D01*
Y594900D01*
X147680Y596012D01*
Y597088D01*
X148692Y598100D01*
Y599300D01*
X147680Y600312D01*
Y601388D01*
X148817Y602525D01*
Y603799D01*
X148117Y604499D01*
X147045D01*
G01X167124Y593757D02*
X165419Y595462D01*
Y605949D01*
X169770Y610300D01*
G01X167124Y604499D02*
X168104D01*
X168703Y603900D01*
Y602700D01*
X167759Y601756D01*
Y600544D01*
X168603Y599700D01*
Y598000D01*
X167759Y597156D01*
Y595736D01*
X168903Y594592D01*
Y592999D01*
X167996Y592092D01*
Y590400D01*
X169682Y588714D01*
X169770D01*
G01X141880Y588514D02*
X141592D01*
X140175Y589931D01*
Y594900D01*
X139345Y595730D01*
Y602270D01*
X140175Y603100D01*
Y608044D01*
X141880Y609749D01*
G01X136780Y590900D02*
X138492Y592612D01*
Y594200D01*
X137392Y595300D01*
X136442D01*
X135852Y595890D01*
Y597260D01*
X136372Y597780D01*
X136982D01*
X137592Y598390D01*
Y599780D01*
X136982Y600390D01*
X136402D01*
X135852Y600940D01*
Y602360D01*
X136492Y603000D01*
X137510D01*
X138511Y604001D01*
Y605645D01*
X136806Y607350D01*
G01X141880Y591114D02*
X143592Y592826D01*
Y594500D01*
X142592Y595500D01*
X141076D01*
X140405Y596171D01*
Y597448D01*
X140857Y597900D01*
X141192D01*
X141892Y598600D01*
Y599688D01*
X141182Y600398D01*
X140945D01*
X140405Y600938D01*
Y601829D01*
X141176Y602600D01*
X142632D01*
X143692Y603660D01*
Y605328D01*
X141880Y607140D01*
G01X136780Y588300D02*
X136492D01*
X134792Y590000D01*
Y608011D01*
X136780Y609999D01*
G01X190549Y17157D02*
Y19257D01*
X192791Y21499D01*
Y28199D01*
X191991Y28999D01*
Y34899D01*
X192491Y35399D01*
Y36901D01*
X191892Y37500D01*
Y45701D01*
X192491Y46300D01*
Y48014D01*
X191891Y48614D01*
Y53314D01*
X192841Y54264D01*
Y65949D01*
X191991Y66799D01*
Y72599D01*
X192491Y73099D01*
Y74901D01*
X191992Y75400D01*
Y83501D01*
X192491Y84000D01*
Y85814D01*
X191891Y86414D01*
Y91114D01*
X192366Y91589D01*
Y114674D01*
X195092Y117400D01*
Y142242D01*
X197658Y144808D01*
X198450D01*
X199029Y144229D01*
X199821D01*
X200840Y145248D01*
Y146040D01*
X200261Y146619D01*
Y147411D01*
X201280Y148430D01*
X202072D01*
X202651Y147851D01*
X203443D01*
X204462Y148870D01*
Y149662D01*
X203883Y150241D01*
Y151033D01*
X224773Y171923D01*
Y172785D01*
X223258Y174300D01*
Y175162D01*
X224122Y176026D01*
X224984D01*
X226499Y174511D01*
X227361D01*
X228225Y175375D01*
Y176237D01*
X226710Y177752D01*
Y178614D01*
X227574Y179478D01*
X228436D01*
X229951Y177963D01*
X230813D01*
X231677Y178827D01*
Y179689D01*
X230162Y181204D01*
Y182066D01*
X231026Y182930D01*
X231888D01*
X233403Y181415D01*
X234265D01*
X236433Y183583D01*
Y184445D01*
X234872Y186006D01*
Y186868D01*
X235736Y187732D01*
X236598D01*
X238159Y186171D01*
X239021D01*
X239885Y187035D01*
Y187897D01*
X238324Y189458D01*
Y190320D01*
X239188Y191184D01*
X240050D01*
X241611Y189623D01*
X242473D01*
X243337Y190487D01*
Y191349D01*
X241776Y192910D01*
Y193772D01*
X242640Y194636D01*
X243502D01*
X245063Y193075D01*
X245925D01*
X246789Y193939D01*
Y194801D01*
X245228Y196362D01*
Y197224D01*
X246092Y198088D01*
X246954D01*
X248515Y196527D01*
X249377D01*
X250241Y197391D01*
Y198253D01*
X248680Y199814D01*
Y200676D01*
X249544Y201540D01*
X250406D01*
X251967Y199979D01*
X252829D01*
X254659Y201809D01*
Y205011D01*
X261981Y212333D01*
X262828D01*
G01X193895Y-3700D02*
X192328Y-2133D01*
Y-932D01*
X190970Y426D01*
Y1799D01*
X192170Y2999D01*
Y4125D01*
X190970Y5325D01*
Y6900D01*
X192770Y8700D01*
Y9758D01*
X189428Y13100D01*
Y16036D01*
X190549Y17157D01*
G01X193895Y12114D02*
X195284Y10725D01*
Y-2288D01*
X195896Y-2900D01*
Y-4300D01*
X194096Y-6100D01*
X193096D01*
X191796Y-7400D01*
Y-8654D01*
X190549Y-9901D01*
G01X262828Y209833D02*
X258592Y205597D01*
Y202665D01*
X240924Y184997D01*
Y184135D01*
X242410Y182649D01*
Y181787D01*
X241546Y180923D01*
X240684D01*
X239198Y182409D01*
X238336D01*
X237472Y181545D01*
Y180683D01*
X238958Y179197D01*
Y178335D01*
X238094Y177471D01*
X237232D01*
X235746Y178957D01*
X234884D01*
X234020Y178093D01*
Y177231D01*
X235506Y175745D01*
Y174883D01*
X234642Y174019D01*
X233780D01*
X232294Y175505D01*
X231432D01*
X230568Y174641D01*
Y173779D01*
X232054Y172293D01*
Y171431D01*
X231190Y170567D01*
X230328D01*
X228842Y172053D01*
X227980D01*
X227116Y171189D01*
Y170327D01*
X228602Y168841D01*
Y167979D01*
X227738Y167115D01*
X226876D01*
X225390Y168601D01*
X224528D01*
X223664Y167737D01*
Y166875D01*
X225150Y165389D01*
Y164527D01*
X224286Y163663D01*
X223424D01*
X221938Y165149D01*
X221076D01*
X220212Y164285D01*
Y163423D01*
X221783Y161852D01*
Y160991D01*
X220919Y160127D01*
X220056D01*
X218486Y161697D01*
X217624D01*
X215352Y159425D01*
X215353Y158635D01*
X216393Y157595D01*
Y156803D01*
X215374Y155784D01*
X214582Y155783D01*
X213542Y156823D01*
X212750D01*
X211730Y155803D01*
X211731Y155013D01*
X212771Y153973D01*
Y153181D01*
X211752Y152162D01*
X210960Y152161D01*
X209920Y153201D01*
X209128D01*
X207992Y152065D01*
Y149301D01*
X199510Y140819D01*
Y116219D01*
X195391Y112100D01*
Y91874D01*
X195991Y91274D01*
Y86614D01*
X195291Y85914D01*
Y83900D01*
X195892Y83299D01*
Y75800D01*
X195291Y75199D01*
Y73101D01*
X195891Y72501D01*
Y67049D01*
X195341Y66499D01*
Y53864D01*
X195991Y53214D01*
Y48814D01*
X195291Y48114D01*
Y46100D01*
X195992Y45399D01*
Y37500D01*
X195291Y36799D01*
Y35201D01*
X195891Y34601D01*
Y29249D01*
X195341Y28699D01*
Y20200D01*
X193434Y18293D01*
Y17057D01*
X191991Y15614D01*
Y14018D01*
X193895Y12114D01*
G01X183856Y17157D02*
X182928Y16229D01*
Y13101D01*
X185970Y10059D01*
Y8674D01*
X184295Y6999D01*
Y5876D01*
X185795Y4376D01*
Y3024D01*
X184295Y1524D01*
Y301D01*
X185728Y-1132D01*
Y-2226D01*
X187202Y-3700D01*
G01X262828Y217333D02*
X257559D01*
X214420Y174194D01*
Y169342D01*
X195766Y150688D01*
X194974D01*
X193673Y151989D01*
X192881D01*
X191862Y150970D01*
Y150178D01*
X193163Y148877D01*
Y148085D01*
X190292Y145214D01*
Y135500D01*
X189492Y134700D01*
X187892D01*
X187092Y135500D01*
Y142500D01*
X186292Y143300D01*
X184692D01*
X183892Y142500D01*
Y118709D01*
X183192Y118009D01*
X180757D01*
X179957Y117209D01*
Y115609D01*
X180757Y114809D01*
X183292D01*
X184092Y114009D01*
Y112409D01*
X183292Y111609D01*
X180757D01*
X179957Y110809D01*
Y109209D01*
X180757Y108409D01*
X183884D01*
X185691Y106602D01*
Y91614D01*
X185291Y91214D01*
Y86514D01*
X186091Y85714D01*
Y84200D01*
X185492Y83601D01*
Y75500D01*
X186091Y74901D01*
Y73399D01*
X185291Y72599D01*
Y66899D01*
X185691Y66499D01*
Y53814D01*
X185291Y53414D01*
Y48714D01*
X186091Y47914D01*
Y46299D01*
X185292Y45500D01*
Y37799D01*
X186091Y37000D01*
Y35699D01*
X185291Y34899D01*
Y29099D01*
X185692Y28698D01*
Y21215D01*
X183856Y19379D01*
Y17157D01*
G01X187202Y12114D02*
X188591Y10725D01*
Y-2288D01*
X189203Y-2900D01*
Y-4300D01*
X187403Y-6100D01*
X186403D01*
X185103Y-7400D01*
Y-8654D01*
X183856Y-9901D01*
G01X262828Y214833D02*
X257725D01*
X252392Y209500D01*
Y208400D01*
X219595Y175603D01*
Y170587D01*
X192792Y143784D01*
Y120300D01*
X191992Y119500D01*
X190392D01*
X189592Y120300D01*
Y131100D01*
X188792Y131900D01*
X187192D01*
X186392Y131100D01*
Y110401D01*
X188691Y108102D01*
Y91714D01*
X189391Y91014D01*
Y86514D01*
X188591Y85714D01*
Y84100D01*
X189192Y83499D01*
Y75500D01*
X188591Y74899D01*
Y73201D01*
X189491Y72301D01*
Y67299D01*
X188691Y66499D01*
Y53914D01*
X189391Y53214D01*
Y48714D01*
X188591Y47914D01*
Y46101D01*
X188992Y45700D01*
Y37701D01*
X188591Y37300D01*
Y35301D01*
X189491Y34401D01*
Y29499D01*
X188691Y28699D01*
Y20678D01*
X186841Y18828D01*
Y17464D01*
X185391Y16014D01*
Y13925D01*
X187202Y12114D01*
G01X203935Y17157D02*
Y24442D01*
X205802Y26309D01*
Y28444D01*
X204652Y29594D01*
Y34259D01*
X206002Y35609D01*
Y36790D01*
X205392Y37400D01*
Y45790D01*
X206002Y46400D01*
Y47564D01*
X204652Y48914D01*
Y53160D01*
X206002Y54510D01*
Y66067D01*
X204652Y67417D01*
Y72059D01*
X206002Y73409D01*
Y74590D01*
X205192Y75400D01*
Y83200D01*
X206002Y84010D01*
Y85364D01*
X204652Y86714D01*
Y90960D01*
X205792Y92100D01*
Y108316D01*
X208592Y111116D01*
Y135532D01*
X252834Y179774D01*
Y180636D01*
X250912Y182558D01*
Y183420D01*
X251902Y184410D01*
X252764D01*
X254686Y182488D01*
X255548D01*
X257128Y184068D01*
Y184864D01*
X255720Y186272D01*
Y187064D01*
X268487Y199831D01*
X268688D01*
G01X206581Y-4100D02*
X205714Y-3233D01*
Y-932D01*
X204081Y701D01*
Y2000D01*
X205431Y3350D01*
Y4250D01*
X204181Y5500D01*
Y6699D01*
X205714Y8232D01*
Y10200D01*
X202814Y13100D01*
Y16036D01*
X203935Y17157D01*
G01X206581Y12114D02*
X208054Y10641D01*
Y-2484D01*
X208670Y-3100D01*
Y-4444D01*
X207214Y-5900D01*
X205814D01*
X203935Y-7779D01*
Y-9901D01*
G01X270337Y197331D02*
X269523D01*
X259597Y187405D01*
Y183061D01*
X211092Y134556D01*
Y110000D01*
X207892Y106800D01*
Y94900D01*
X208502Y94290D01*
Y84052D01*
X209092Y83462D01*
Y75400D01*
X208502Y74810D01*
Y46200D01*
X209192Y45510D01*
Y37500D01*
X208502Y36810D01*
Y25311D01*
X205792Y22601D01*
Y16500D01*
X204508Y15216D01*
Y14187D01*
X206581Y12114D01*
G01X227360Y17157D02*
X226239Y16036D01*
Y13100D01*
X229581Y9758D01*
Y8700D01*
X227781Y6900D01*
Y5325D01*
X228981Y4125D01*
Y2999D01*
X227781Y1799D01*
Y426D01*
X229139Y-932D01*
Y-2133D01*
X230706Y-3700D01*
G01X288531Y189470D02*
X281961Y182900D01*
X280193D01*
X265998Y168705D01*
Y165106D01*
X263653Y162761D01*
X259415D01*
X257717Y161063D01*
Y160201D01*
X259224Y158694D01*
Y157832D01*
X258360Y156968D01*
X257498D01*
X255991Y158475D01*
X255129D01*
X254265Y157611D01*
Y156749D01*
X255772Y155242D01*
Y154380D01*
X254908Y153516D01*
X254046D01*
X252539Y155023D01*
X251677D01*
X250813Y154159D01*
Y153297D01*
X252320Y151790D01*
Y150928D01*
X246028Y144636D01*
X245236D01*
X244278Y145594D01*
X243486D01*
X242467Y144575D01*
Y143783D01*
X243425Y142825D01*
Y142033D01*
X226402Y125010D01*
Y120254D01*
X227012Y119644D01*
X228764D01*
X229374Y119034D01*
Y117785D01*
X228764Y117175D01*
X227012D01*
X226402Y116565D01*
Y115636D01*
X227012Y115026D01*
X228764D01*
X229374Y114416D01*
Y113441D01*
X228764Y112831D01*
X227012D01*
X226402Y112221D01*
Y111185D01*
X227476Y110111D01*
X228853D01*
X229353Y109611D01*
Y91765D01*
X228702Y91114D01*
Y86414D01*
X229302Y85814D01*
Y84000D01*
X228892Y83590D01*
Y75400D01*
X229302Y74990D01*
Y73111D01*
X228802Y72611D01*
Y66799D01*
X229652Y65949D01*
Y54264D01*
X228702Y53314D01*
Y48614D01*
X229302Y48014D01*
Y46100D01*
X228736Y45534D01*
Y37556D01*
X229302Y36990D01*
Y35411D01*
X228892Y35001D01*
Y28909D01*
X229192Y28609D01*
Y18989D01*
X227360Y17157D01*
G01X230706Y12114D02*
X232095Y10725D01*
Y-2288D01*
X232707Y-2900D01*
Y-4300D01*
X230907Y-6100D01*
X229907D01*
X228607Y-7400D01*
Y-8654D01*
X227360Y-9901D01*
G01X290312Y186920D02*
Y184194D01*
X289180Y183062D01*
X287600D01*
X287100Y182562D01*
Y180982D01*
X285751Y179633D01*
X284578D01*
X283511Y180700D01*
X281192D01*
X280171Y179679D01*
Y178817D01*
X282145Y176843D01*
Y175981D01*
X281281Y175117D01*
X280419D01*
X279463Y176073D01*
X278671D01*
X273064Y170466D01*
X270958D01*
X268376Y167884D01*
Y163449D01*
X231853Y126926D01*
Y125359D01*
X231243Y124749D01*
X229161D01*
X228551Y124139D01*
Y122919D01*
X229161Y122309D01*
X231243D01*
X231853Y121699D01*
Y92223D01*
X232802Y91274D01*
Y86614D01*
X232102Y85914D01*
Y84000D01*
X232492Y83610D01*
Y75000D01*
X232102Y74610D01*
Y73091D01*
X232652Y72541D01*
Y66999D01*
X232152Y66499D01*
Y53914D01*
X232613Y53453D01*
Y48575D01*
X232102Y48064D01*
Y46300D01*
X232792Y45610D01*
Y37600D01*
X232102Y36910D01*
Y35291D01*
X232702Y34691D01*
Y29249D01*
X232152Y28699D01*
Y18964D01*
X228802Y15614D01*
Y14018D01*
X230706Y12114D01*
G01X197242Y17157D02*
Y18149D01*
X199202Y20109D01*
Y28491D01*
X198302Y29391D01*
Y34299D01*
X199302Y35299D01*
Y37200D01*
X198592Y37910D01*
Y45600D01*
X199302Y46310D01*
Y47614D01*
X198302Y48614D01*
Y53414D01*
X199202Y54314D01*
Y66291D01*
X198302Y67191D01*
Y72099D01*
X199302Y73099D01*
Y74790D01*
X198592Y75500D01*
Y83490D01*
X199302Y84200D01*
Y85414D01*
X198302Y86414D01*
Y91214D01*
X199592Y92504D01*
Y110528D01*
X203592Y114528D01*
Y138304D01*
X245606Y180318D01*
Y185214D01*
X267080Y206688D01*
Y206810D01*
G01X200202Y-4100D02*
X199114Y-3012D01*
Y-1132D01*
X197681Y301D01*
Y1500D01*
X199181Y3000D01*
Y4200D01*
X197731Y5650D01*
Y7049D01*
X199114Y8432D01*
Y10301D01*
X196314Y13101D01*
Y16229D01*
X197242Y17157D01*
G01X200288Y12114D02*
X201514Y10888D01*
Y-2125D01*
X202289Y-2900D01*
Y-4524D01*
X200713Y-6100D01*
X199489D01*
X197242Y-8347D01*
Y-9901D01*
G01X268948Y204941D02*
Y204656D01*
X248029Y183737D01*
Y178627D01*
X206092Y136690D01*
Y112914D01*
X202135Y108957D01*
Y91431D01*
X202152Y91414D01*
Y86464D01*
X201802Y86114D01*
Y83900D01*
X202392Y83310D01*
Y75800D01*
X201802Y75210D01*
Y73199D01*
X202152Y72849D01*
Y66649D01*
X201902Y66399D01*
Y53864D01*
X202152Y53614D01*
Y48664D01*
X201802Y48314D01*
Y46000D01*
X202392Y45410D01*
Y37900D01*
X201802Y37310D01*
Y35399D01*
X202152Y35049D01*
Y28849D01*
X201492Y28189D01*
Y18704D01*
X198302Y15514D01*
Y14100D01*
X200288Y12114D01*
G01X220667Y17157D02*
X219739Y16229D01*
Y13101D01*
X222781Y10059D01*
Y8674D01*
X221106Y6999D01*
Y5876D01*
X222606Y4376D01*
Y3024D01*
X221106Y1524D01*
Y301D01*
X222539Y-1132D01*
Y-2226D01*
X224013Y-3700D01*
G01X283489Y191440D02*
X282133D01*
X277901Y187208D01*
X277039D01*
X275691Y188556D01*
X274829D01*
X273965Y187692D01*
Y186830D01*
X275313Y185482D01*
Y184620D01*
X274449Y183756D01*
X273587D01*
X272239Y185104D01*
X271377D01*
X270513Y184240D01*
Y183378D01*
X271861Y182030D01*
Y181168D01*
X232183Y141490D01*
Y140628D01*
X233387Y139424D01*
Y138562D01*
X232523Y137698D01*
X231661D01*
X230457Y138902D01*
X229595D01*
X228731Y138038D01*
Y137176D01*
X229935Y135972D01*
Y135110D01*
X229071Y134246D01*
X228209D01*
X227005Y135450D01*
X226143D01*
X225279Y134586D01*
Y133724D01*
X226483Y132520D01*
Y131658D01*
X225619Y130794D01*
X224757D01*
X223553Y131998D01*
X222691D01*
X221202Y130509D01*
Y97846D01*
X222492Y96556D01*
Y91604D01*
X222102Y91214D01*
Y86514D01*
X222902Y85714D01*
Y84200D01*
X222192Y83490D01*
Y75500D01*
X222902Y74790D01*
Y73411D01*
X222102Y72611D01*
Y66899D01*
X222502Y66499D01*
Y53814D01*
X222102Y53414D01*
Y48714D01*
X222492Y48324D01*
Y46000D01*
X222092Y45600D01*
Y37700D01*
X222492Y37300D01*
Y35201D01*
X222102Y34811D01*
Y29099D01*
X222492Y28709D01*
Y18982D01*
X220667Y17157D01*
G01X224013Y12114D02*
X225402Y10725D01*
Y-2288D01*
X226014Y-2900D01*
Y-4300D01*
X224214Y-6100D01*
X223214D01*
X221914Y-7400D01*
Y-8654D01*
X220667Y-9901D01*
G01X284962Y189437D02*
X281125Y185600D01*
X279493D01*
X247569Y153676D01*
Y152815D01*
X248097Y152287D01*
Y151579D01*
X247079Y150561D01*
X246371D01*
X245844Y151088D01*
X244981D01*
X239388Y145495D01*
Y141696D01*
X223702Y126010D01*
Y109392D01*
X224312Y108782D01*
X225380D01*
X225990Y108172D01*
Y106952D01*
X225380Y106342D01*
X224312D01*
X223702Y105732D01*
Y104512D01*
X224312Y103902D01*
X225380D01*
X225990Y103292D01*
Y102072D01*
X225380Y101462D01*
X224312D01*
X223702Y100852D01*
Y98867D01*
X225492Y97077D01*
Y91724D01*
X226202Y91014D01*
Y86514D01*
X225402Y85714D01*
Y83900D01*
X225992Y83310D01*
Y75400D01*
X225402Y74810D01*
Y73091D01*
X226302Y72191D01*
Y67299D01*
X225502Y66499D01*
Y53914D01*
X226202Y53214D01*
Y48714D01*
X225492Y48004D01*
Y46200D01*
X225792Y45900D01*
Y37600D01*
X225492Y37300D01*
Y35301D01*
X225892Y34901D01*
Y29089D01*
X225492Y28689D01*
Y19304D01*
X222202Y16014D01*
Y13925D01*
X224013Y12114D01*
G01X173591Y14300D02*
X175317Y16026D01*
Y18100D01*
X174517Y18900D01*
X173517D01*
X172797Y19620D01*
Y20688D01*
X177171Y25062D01*
Y26622D01*
X176671Y27122D01*
Y37180D01*
X177291Y37800D01*
Y38800D01*
X176671Y39420D01*
Y40180D01*
X177291Y40800D01*
Y41800D01*
X176671Y42420D01*
Y43180D01*
X177291Y43800D01*
Y44800D01*
X176671Y45420D01*
Y101653D01*
X173472Y104852D01*
Y132916D01*
X174344Y133788D01*
X175840D01*
X176960Y134908D01*
Y139028D01*
X175840Y140148D01*
X174144D01*
X173372Y140920D01*
Y142148D01*
X191424Y160200D01*
X195220D01*
X205256Y170236D01*
Y174032D01*
X216585Y185361D01*
X217222D01*
X217930Y186069D01*
Y186706D01*
X218803Y187579D01*
X219440D01*
X220148Y188287D01*
Y188924D01*
X221204Y189980D01*
X221840D01*
X222548Y190688D01*
Y191324D01*
X223489Y192265D01*
X224126D01*
X224834Y192973D01*
Y193610D01*
X225661Y194437D01*
X226298D01*
X227006Y195145D01*
Y195782D01*
X228062Y196838D01*
X228698D01*
X229406Y197546D01*
Y198182D01*
X230737Y199513D01*
X231373D01*
X232081Y200221D01*
Y200857D01*
X233161Y201937D01*
X233797D01*
X234505Y202645D01*
Y203281D01*
X235218Y203994D01*
X235855D01*
X236563Y204702D01*
Y205339D01*
X237289Y206065D01*
X237925D01*
X238633Y206773D01*
Y207409D01*
X239340Y208116D01*
X239976D01*
X240684Y208824D01*
Y209460D01*
X241391Y210167D01*
X242027D01*
X242735Y210875D01*
Y211511D01*
X243631Y212407D01*
X244268D01*
X244976Y213115D01*
Y213752D01*
X245849Y214625D01*
X246485D01*
X247193Y215333D01*
Y215969D01*
X247906Y216682D01*
X248543D01*
X249251Y217390D01*
Y218027D01*
X250176Y218952D01*
X250812D01*
X251520Y219660D01*
Y220296D01*
X252227Y221003D01*
X252864D01*
X253572Y221711D01*
Y222348D01*
X255404Y224180D01*
X257892D01*
G01X173617Y-7050D02*
X174387Y-6280D01*
X175369D01*
X176697Y-4952D01*
Y11194D01*
X173591Y14300D01*
G01X210402D02*
X213508Y11194D01*
Y-4952D01*
X212180Y-6280D01*
X211198D01*
X210428Y-7050D01*
G01X275141Y197181D02*
X274194Y195507D01*
X270858Y193434D01*
X268373Y190949D01*
Y190312D01*
X267665Y189604D01*
X267028D01*
X265927Y188503D01*
Y187866D01*
X265219Y187158D01*
X264581D01*
X262990Y185567D01*
Y181790D01*
X262213Y181013D01*
Y180377D01*
X261505Y179669D01*
X260869D01*
X259676Y178476D01*
Y177839D01*
X258968Y177131D01*
X258331D01*
X257624Y176424D01*
Y175788D01*
X256916Y175080D01*
X256280D01*
X255573Y174373D01*
Y173737D01*
X254865Y173029D01*
X254229D01*
X253522Y172322D01*
Y171686D01*
X252814Y170978D01*
X252178D01*
X251471Y170271D01*
Y169635D01*
X250763Y168927D01*
X250127D01*
X249420Y168220D01*
Y167584D01*
X248712Y166876D01*
X248076D01*
X247369Y166169D01*
Y165533D01*
X246661Y164825D01*
X246025D01*
X245113Y163913D01*
Y163277D01*
X244405Y162569D01*
X243769D01*
X214772Y133572D01*
Y106194D01*
X213280Y104702D01*
X212649D01*
X211072Y103125D01*
Y100603D01*
X213482Y98193D01*
Y58220D01*
X214102Y57600D01*
Y56600D01*
X213482Y55980D01*
Y45020D01*
X214102Y44400D01*
Y43400D01*
X213482Y42780D01*
Y42020D01*
X214102Y41400D01*
Y40400D01*
X213482Y39780D01*
Y39020D01*
X214102Y38400D01*
Y37400D01*
X213482Y36780D01*
Y24562D01*
X209608Y20688D01*
Y19620D01*
X210328Y18900D01*
X211328D01*
X212128Y18100D01*
Y16026D01*
X210402Y14300D01*
G01X178691Y14514D02*
X180517Y16340D01*
Y17900D01*
X178497Y19920D01*
Y20788D01*
X179471Y21762D01*
X180347D01*
X181055Y22470D01*
Y23346D01*
X182391Y24682D01*
Y25514D01*
X181771Y26134D01*
Y102452D01*
X177272Y106951D01*
Y119442D01*
X178144Y120314D01*
X179383D01*
X180972Y121903D01*
Y125225D01*
X179523Y126674D01*
X178344D01*
X177472Y127546D01*
Y129719D01*
X181272Y133519D01*
Y143279D01*
X192393Y154400D01*
X196693D01*
X201254Y158961D01*
Y160521D01*
X211770Y171037D01*
Y174946D01*
X241733Y204909D01*
X242369D01*
X243077Y205617D01*
Y206253D01*
X243790Y206966D01*
X244427D01*
X245135Y207674D01*
Y208311D01*
X245848Y209024D01*
X246484D01*
X247192Y209732D01*
Y210368D01*
X248774Y211950D01*
X249411D01*
X250119Y212658D01*
Y213295D01*
X251540Y214716D01*
X252177D01*
X252885Y215424D01*
Y216061D01*
X256992Y220168D01*
X257710D01*
G01X178691Y-7260D02*
X181883Y-4068D01*
Y11322D01*
X178691Y14514D01*
G01X215502D02*
X217328Y16340D01*
Y17900D01*
X215308Y19920D01*
Y20788D01*
X216282Y21762D01*
X217158D01*
X217866Y22470D01*
Y23346D01*
X219202Y24682D01*
Y25514D01*
X218582Y26134D01*
Y131897D01*
X266524Y179839D01*
Y183725D01*
X267681Y184882D01*
X268318D01*
X269026Y185590D01*
Y186227D01*
X270333Y187534D01*
X270970D01*
X271678Y188242D01*
Y188879D01*
X272845Y190046D01*
X279103Y195088D01*
X281133Y197119D01*
G01X215502Y-7260D02*
X218694Y-4068D01*
Y11322D01*
X215502Y14514D01*
G01X173591Y11700D02*
X171737Y13554D01*
Y21131D01*
X175611Y25005D01*
Y101210D01*
X172412Y104409D01*
Y133359D01*
X173901Y134848D01*
X175400D01*
X175900Y135348D01*
Y138588D01*
X175400Y139088D01*
X173704D01*
X172312Y140480D01*
Y142588D01*
X190984Y161260D01*
X194780D01*
X204196Y170676D01*
Y174472D01*
X254964Y225240D01*
X257892D01*
G01X173591Y-4401D02*
X174410Y-5220D01*
X174926D01*
X175637Y-4509D01*
Y-1220D01*
X173717Y700D01*
Y1700D01*
X174317Y2300D01*
X174817D01*
X175637Y3120D01*
Y4080D01*
X174917Y4800D01*
X174205D01*
X173703Y5302D01*
Y6634D01*
X174319Y7250D01*
X174667D01*
X175637Y8220D01*
Y10753D01*
X174690Y11700D01*
X173591D01*
G01X210402D02*
X211501D01*
X212448Y10753D01*
Y8220D01*
X211478Y7250D01*
X211130D01*
X210514Y6634D01*
Y5302D01*
X211016Y4800D01*
X211728D01*
X212448Y4080D01*
Y3120D01*
X211628Y2300D01*
X211128D01*
X210528Y1700D01*
Y700D01*
X212448Y-1220D01*
Y-4509D01*
X211737Y-5220D01*
X211221D01*
X210402Y-4401D01*
G01X274218Y197703D02*
X273404Y196265D01*
X270194Y194271D01*
X261930Y186007D01*
Y182230D01*
X213712Y134012D01*
Y106634D01*
X212840Y105762D01*
X212209D01*
X210012Y103565D01*
Y100163D01*
X212422Y97753D01*
Y25005D01*
X208548Y21131D01*
Y13554D01*
X210402Y11700D01*
G01X178691Y11914D02*
X176967Y13638D01*
Y18275D01*
X177437Y18745D01*
Y21231D01*
X180711Y24505D01*
Y102012D01*
X176212Y106511D01*
Y119885D01*
X177701Y121374D01*
X178943D01*
X179912Y122343D01*
Y124785D01*
X179083Y125614D01*
X177904D01*
X176412Y127106D01*
Y130159D01*
X180212Y133959D01*
Y143719D01*
X191953Y155460D01*
X196253D01*
X200194Y159401D01*
Y160961D01*
X210710Y171477D01*
Y175386D01*
X256552Y221228D01*
X257710D01*
G01X178691Y-4651D02*
X179800D01*
X180823Y-3628D01*
Y-1007D01*
X180116Y-300D01*
X179318D01*
X178717Y301D01*
Y1499D01*
X179318Y2100D01*
X180016D01*
X180823Y2907D01*
Y4280D01*
X180103Y5000D01*
X179603D01*
X178903Y5700D01*
Y6700D01*
X179603Y7400D01*
X180117D01*
X180823Y8106D01*
Y10881D01*
X179789Y11915D01*
X178691D01*
Y11914D01*
G01X215502D02*
X213778Y13638D01*
Y18285D01*
X214248Y18755D01*
Y21231D01*
X217522Y24505D01*
Y132337D01*
X265464Y180279D01*
Y184165D01*
X272135Y190836D01*
X278393Y195878D01*
X280384Y197869D01*
G01X215502Y-4651D02*
X216611D01*
X217634Y-3628D01*
Y-1007D01*
X216927Y-300D01*
X216129D01*
X215528Y301D01*
Y1499D01*
X216129Y2100D01*
X216827D01*
X217634Y2907D01*
Y4280D01*
X216914Y5000D01*
X216414D01*
X215714Y5700D01*
Y6700D01*
X216414Y7400D01*
X216928D01*
X217634Y8106D01*
Y10881D01*
X216600Y11915D01*
X215502D01*
Y11914D01*
G01X259499Y393292D02*
X259491Y393300D01*
X257592D01*
X254392Y396500D01*
Y403571D01*
X237844Y420119D01*
Y421251D01*
X238975Y422382D01*
X240107D01*
X251275Y411214D01*
X252407D01*
X253538Y412345D01*
Y413477D01*
X192192Y474823D01*
Y508900D01*
X192892Y509600D01*
Y510756D01*
X191991Y511657D01*
Y516499D01*
X193292Y517800D01*
Y518949D01*
X192192Y520049D01*
Y527700D01*
X192841Y528349D01*
Y529416D01*
X191891Y530366D01*
Y535598D01*
X192904Y536611D01*
Y538087D01*
X192292Y538699D01*
Y546100D01*
X193254Y547062D01*
Y548194D01*
X191991Y549457D01*
Y554857D01*
X192791Y555657D01*
Y557200D01*
X192192Y557799D01*
Y565500D01*
X192791Y566099D01*
Y567297D01*
X191691Y568397D01*
Y573142D01*
X192591Y574042D01*
Y575500D01*
X192192Y575899D01*
Y584200D01*
X192591Y584599D01*
Y586507D01*
X189191Y589907D01*
Y592399D01*
X190549Y593757D01*
G01X259499Y395823D02*
X257192Y398130D01*
Y406745D01*
X256554Y407383D01*
X253830D01*
X253248Y407965D01*
Y409355D01*
X253886Y409993D01*
X256554D01*
X257192Y410631D01*
Y413359D01*
X201292Y469259D01*
Y490100D01*
X200492Y490900D01*
X198892D01*
X198092Y490100D01*
Y474931D01*
X197292Y474131D01*
X195692D01*
X194892Y474931D01*
Y495033D01*
X195476Y495617D01*
X197088D01*
X197846Y496375D01*
Y497975D01*
X197004Y498817D01*
X195898D01*
X195291Y499424D01*
Y511657D01*
X196192Y512558D01*
Y516506D01*
X195341Y517357D01*
Y519200D01*
X195592Y519451D01*
Y526800D01*
X194992Y527400D01*
Y529467D01*
X195991Y530466D01*
Y535502D01*
X194992Y536501D01*
Y538201D01*
X195592Y538801D01*
Y546800D01*
X195291Y547101D01*
Y549457D01*
X195891Y550057D01*
Y554401D01*
X194792Y555500D01*
Y557399D01*
X195592Y558199D01*
Y564800D01*
X194892Y565500D01*
Y567198D01*
X196191Y568497D01*
Y573302D01*
X194792Y574701D01*
Y575801D01*
X195992Y577001D01*
Y583900D01*
X195191Y584701D01*
Y587470D01*
X193895Y588766D01*
Y588714D01*
G01X255997Y387789D02*
X253603D01*
X249592Y391800D01*
Y401199D01*
X204158Y446633D01*
Y447765D01*
X205289Y448896D01*
X206421D01*
X218289Y437028D01*
X219421D01*
X220552Y438159D01*
Y439291D01*
X186892Y472951D01*
Y507100D01*
X185692Y508300D01*
Y511656D01*
X185291Y512057D01*
Y516957D01*
X185691Y517357D01*
Y529842D01*
X185291Y530242D01*
Y535698D01*
X186091Y536498D01*
Y537400D01*
X185492Y537999D01*
Y546500D01*
X186091Y547099D01*
Y549057D01*
X185291Y549857D01*
Y554757D01*
X185891Y555357D01*
Y557300D01*
X185492Y557699D01*
Y565500D01*
X185891Y565899D01*
Y567397D01*
X184818Y568470D01*
Y572969D01*
X185792Y573943D01*
Y575499D01*
X185492Y575799D01*
Y584500D01*
X186091Y585099D01*
Y586357D01*
X183191Y589257D01*
Y593092D01*
X183856Y593757D01*
G01X255677Y390289D02*
X251992Y393974D01*
Y402399D01*
X220857Y433534D01*
Y434666D01*
X221988Y435797D01*
X223120D01*
X235738Y423179D01*
X236970D01*
X238101Y424310D01*
Y425342D01*
X189392Y474051D01*
Y508300D01*
X188492Y509200D01*
Y511158D01*
X189491Y512157D01*
Y516301D01*
X188286Y517506D01*
Y518895D01*
X188892Y519501D01*
Y527600D01*
X188237Y528255D01*
Y529388D01*
X189892Y531043D01*
Y535001D01*
X188192Y536701D01*
Y538001D01*
X188892Y538701D01*
Y546200D01*
X188192Y546900D01*
Y548658D01*
X189792Y550258D01*
Y553700D01*
X187958Y555534D01*
Y556867D01*
X188892Y557801D01*
Y565200D01*
X188159Y565933D01*
Y567065D01*
X189492Y568398D01*
Y573300D01*
X188258Y574534D01*
Y576166D01*
X188892Y576800D01*
Y584299D01*
X188591Y584600D01*
Y587368D01*
X188548D01*
X187202Y588714D01*
G01X269104Y404597D02*
X263972Y409729D01*
Y419308D01*
X210592Y472688D01*
Y494100D01*
X206692Y498000D01*
Y506300D01*
X206002Y506990D01*
Y510707D01*
X204652Y512057D01*
Y516307D01*
X206002Y517657D01*
Y519500D01*
X205592Y519910D01*
Y527800D01*
X206002Y528210D01*
Y529267D01*
X204652Y530617D01*
Y535260D01*
X206002Y536610D01*
Y538490D01*
X205592Y538900D01*
Y546100D01*
X206002Y546510D01*
Y548507D01*
X204652Y549857D01*
Y554107D01*
X205802Y555257D01*
Y557400D01*
X205592Y557610D01*
Y565700D01*
X205802Y565910D01*
Y567267D01*
X204702Y568367D01*
Y573109D01*
X205852Y574259D01*
Y575600D01*
X205592Y575860D01*
Y584300D01*
X205852Y584560D01*
Y586457D01*
X202502Y589807D01*
Y592324D01*
X203935Y593757D01*
G01X270872Y406365D02*
X265857Y411380D01*
Y420959D01*
X214510Y472306D01*
Y474725D01*
X213900Y475335D01*
X213089D01*
X212479Y475945D01*
Y477925D01*
X213089Y478535D01*
X213900D01*
X214510Y479145D01*
Y481125D01*
X213900Y481735D01*
X213089D01*
X212479Y482345D01*
Y484325D01*
X213089Y484935D01*
X214096D01*
X214706Y485545D01*
Y487525D01*
X214096Y488135D01*
X213089D01*
X212479Y488745D01*
Y490725D01*
X213089Y491335D01*
X213900D01*
X214510Y491945D01*
Y493882D01*
X209292Y499100D01*
Y507920D01*
X208449Y508763D01*
Y518557D01*
X209992Y520100D01*
Y521416D01*
X208449Y522959D01*
Y524801D01*
X209679Y526031D01*
Y527413D01*
X208502Y528590D01*
Y537710D01*
X209455Y538663D01*
Y540400D01*
X208392Y541463D01*
Y542737D01*
X209455Y543800D01*
Y545737D01*
X208502Y546690D01*
Y556610D01*
X208992Y557100D01*
Y559900D01*
X207992Y560900D01*
Y563400D01*
X208992Y564400D01*
Y565900D01*
X208502Y566390D01*
Y575610D01*
X208992Y576100D01*
Y578200D01*
X207992Y579200D01*
Y580700D01*
X208992Y581700D01*
Y583700D01*
X208502Y584190D01*
Y586443D01*
X206581Y588364D01*
Y588714D01*
G01X265699Y400093D02*
X260202Y405590D01*
Y416006D01*
X205292Y470916D01*
Y491800D01*
X201592Y495500D01*
Y499200D01*
X199292Y501500D01*
Y510807D01*
X198503Y511596D01*
Y516658D01*
X198968Y517123D01*
Y519434D01*
X198892Y519510D01*
Y527800D01*
X199094Y528002D01*
Y529598D01*
X198302Y530390D01*
Y535242D01*
X199118Y536058D01*
Y537784D01*
X198892Y538010D01*
Y546200D01*
X199203Y546511D01*
Y548656D01*
X198423Y549436D01*
Y554378D01*
X199051Y555006D01*
Y565959D01*
X199191Y566099D01*
Y567200D01*
X198407Y567984D01*
Y573197D01*
X198967Y573757D01*
Y584475D01*
X199152Y584660D01*
Y586457D01*
X196817Y588792D01*
Y593332D01*
X197242Y593757D01*
G01X267476Y401870D02*
X262087Y407259D01*
Y417657D01*
X207892Y471852D01*
Y493000D01*
X204192Y496700D01*
Y501400D01*
X202992Y502600D01*
Y508310D01*
X201802Y509500D01*
Y511397D01*
X202556Y512151D01*
Y516803D01*
X201634Y517725D01*
Y520108D01*
X202835Y521309D01*
Y526813D01*
X201902Y527746D01*
Y529992D01*
X202388Y530478D01*
Y535194D01*
X201438Y536144D01*
Y537988D01*
X202695Y539245D01*
Y545397D01*
X201662Y546430D01*
Y548317D01*
X202528Y549183D01*
Y554303D01*
X201634Y555197D01*
Y556732D01*
X202292Y557390D01*
Y565044D01*
X201662Y565674D01*
Y567757D01*
X202402Y568497D01*
Y573146D01*
X201550Y573998D01*
Y575558D01*
X202992Y577000D01*
Y578600D01*
X201692Y579900D01*
Y581200D01*
X202992Y582500D01*
Y583600D01*
X201802Y584790D01*
Y587790D01*
X200878Y588714D01*
X200288D01*
G01X169770D02*
Y588364D01*
X171691Y586443D01*
Y584701D01*
X172192Y584200D01*
Y576001D01*
X171691Y575500D01*
Y566101D01*
X172192Y565600D01*
Y556901D01*
X171691Y556400D01*
Y546101D01*
X172092Y545700D01*
Y538101D01*
X171691Y537700D01*
Y528401D01*
X172992Y527100D01*
Y526029D01*
X172382Y525419D01*
X171124D01*
X170514Y524809D01*
Y522829D01*
X171124Y522219D01*
X172382D01*
X172992Y521609D01*
Y519901D01*
X171691Y518600D01*
Y511699D01*
X171092Y511100D01*
Y509800D01*
X172892Y508000D01*
Y506381D01*
X172282Y505771D01*
X171050D01*
X170440Y505161D01*
Y503181D01*
X171050Y502571D01*
X172282D01*
X172892Y501961D01*
Y489662D01*
X172092Y488862D01*
X171173D01*
X170317Y488006D01*
Y486406D01*
X171061Y485662D01*
X172092D01*
X172892Y484862D01*
Y483262D01*
X172092Y482462D01*
X170992D01*
X170192Y481662D01*
Y480062D01*
X170992Y479262D01*
X172092D01*
X172892Y478462D01*
Y476862D01*
X172092Y476062D01*
X171145D01*
X170345Y475262D01*
Y473662D01*
X171145Y472862D01*
X172092D01*
X172892Y472062D01*
Y470462D01*
X172092Y469662D01*
X171061D01*
X170261Y468862D01*
Y467262D01*
X171061Y466462D01*
X172092D01*
X172892Y465662D01*
Y463564D01*
X239092Y397364D01*
Y385634D01*
X249526Y375200D01*
X253216D01*
X253248Y375168D01*
G01X254072Y379475D02*
X249417D01*
X242792Y386100D01*
Y398871D01*
X176671Y464992D01*
Y487319D01*
X177543Y488191D01*
X179325D01*
X180814Y489680D01*
Y492262D01*
X179325Y493751D01*
X177543D01*
X176671Y494623D01*
Y496319D01*
X177543Y497191D01*
X179361D01*
X180898Y498728D01*
Y501310D01*
X179457Y502751D01*
X177543D01*
X176671Y503623D01*
Y579416D01*
X177291Y580036D01*
Y581036D01*
X176671Y581656D01*
Y582656D01*
X177291Y583276D01*
Y584276D01*
X176671Y584896D01*
Y587849D01*
X173620Y590900D01*
X173591D01*
G01X273616Y409536D02*
X268952Y414200D01*
Y423072D01*
X217672Y474352D01*
Y495952D01*
X213482Y500142D01*
Y587849D01*
X210431Y590900D01*
X210402D01*
G01X178691Y588514D02*
X179792D01*
X180711Y587595D01*
Y583946D01*
X180175Y583410D01*
Y582410D01*
X180711Y581874D01*
Y580707D01*
X180174Y580170D01*
Y579170D01*
X180711Y578633D01*
Y507609D01*
X183212Y505108D01*
Y485110D01*
X182340Y484238D01*
X181701D01*
X180212Y482749D01*
Y480167D01*
X181701Y478678D01*
X182340D01*
X183212Y477806D01*
Y476110D01*
X182340Y475238D01*
X181701D01*
X180312Y473849D01*
Y471067D01*
X181701Y469678D01*
X182340D01*
X183212Y468806D01*
Y462879D01*
X184974Y461117D01*
X187614D01*
X189945Y463448D01*
X191174D01*
X192380Y462242D01*
Y461013D01*
X189519Y458151D01*
Y456041D01*
X191341Y454219D01*
X193453D01*
X196314Y457081D01*
X197538D01*
X198747Y455872D01*
Y454646D01*
X195886Y451784D01*
Y449675D01*
X195888D01*
X245732Y399831D01*
Y386360D01*
X249420Y382672D01*
X251966D01*
X252577Y382660D01*
G01X254072Y378415D02*
X248977D01*
X241732Y385660D01*
Y398431D01*
X175613Y464550D01*
X175611D01*
Y487759D01*
X177103Y489251D01*
X178882D01*
X179754Y490123D01*
Y491822D01*
X178885Y492691D01*
X177103D01*
X175611Y494183D01*
Y496759D01*
X177103Y498251D01*
X178921D01*
X179838Y499168D01*
Y500870D01*
X179017Y501691D01*
X177103D01*
X175611Y503183D01*
Y587409D01*
X174720Y588300D01*
X173591D01*
G01X272866Y408786D02*
X267892Y413760D01*
Y422632D01*
X216614Y473910D01*
X216612D01*
Y495509D01*
X212422Y499699D01*
Y587409D01*
X211531Y588300D01*
X210402D01*
G01X178691Y591114D02*
X178692D01*
X181771Y588035D01*
Y508052D01*
X184272Y505551D01*
Y484667D01*
X182783Y483178D01*
X182144D01*
X181272Y482306D01*
Y480610D01*
X182144Y479738D01*
X182783D01*
X184272Y478249D01*
Y475667D01*
X182783Y474178D01*
X182144D01*
X181372Y473406D01*
Y471510D01*
X182144Y470738D01*
X182783D01*
X184272Y469249D01*
Y463322D01*
X185417Y462177D01*
X187174D01*
X189505Y464508D01*
X191614D01*
X193440Y462682D01*
Y460574D01*
X190579Y457712D01*
Y456484D01*
X191784Y455279D01*
X193010D01*
X195871Y458141D01*
X197981D01*
X199807Y456315D01*
Y454207D01*
X196946Y451345D01*
Y450117D01*
X246792Y400271D01*
Y386800D01*
X249860Y383732D01*
X251977D01*
X252597Y383720D01*
G01X286903Y414896D02*
X283292Y418507D01*
Y434633D01*
X282038Y435887D01*
Y437017D01*
X283391Y438369D01*
Y439499D01*
X282258Y440632D01*
X281128D01*
X279775Y439280D01*
X278645D01*
X267144Y450781D01*
X266014D01*
X264179Y448945D01*
X263049D01*
X262130Y449864D01*
Y450996D01*
X264047Y452913D01*
Y454045D01*
X262916Y455176D01*
X261784D01*
X259867Y453259D01*
X258735D01*
X229203Y482791D01*
Y511256D01*
X228492Y511967D01*
Y516307D01*
X229192Y517007D01*
Y526500D01*
X229992Y527300D01*
Y529100D01*
X228392Y530700D01*
Y535400D01*
X229665Y536673D01*
Y537727D01*
X228492Y538900D01*
Y546100D01*
X229792Y547400D01*
Y549099D01*
X228802Y550089D01*
Y554309D01*
X229992Y555499D01*
Y557500D01*
X229092Y558400D01*
Y564200D01*
X229992Y565100D01*
Y566907D01*
X228502Y568397D01*
Y573210D01*
X229792Y574500D01*
Y575800D01*
X228692Y576900D01*
Y584200D01*
X229592Y585100D01*
Y587101D01*
X228593Y588100D01*
X227192D01*
X226002Y589290D01*
Y592399D01*
X227360Y593757D01*
G01X283098Y410791D02*
X278292Y415597D01*
Y426300D01*
X276498Y428094D01*
Y429226D01*
X278216Y430944D01*
Y432076D01*
X277085Y433207D01*
X275953D01*
X273935Y431189D01*
X272803D01*
X271664Y432328D01*
Y433460D01*
X272282Y434078D01*
Y435210D01*
X271151Y436341D01*
X270019D01*
X269701Y436023D01*
X268569D01*
X224092Y480500D01*
Y499300D01*
X221526Y501866D01*
Y508134D01*
X222947Y509555D01*
Y511212D01*
X221692Y512467D01*
Y516547D01*
X222502Y517357D01*
Y529842D01*
X222102Y530242D01*
Y535710D01*
X223092Y536700D01*
Y538000D01*
X222092Y539000D01*
Y546500D01*
X222902Y547310D01*
Y549057D01*
X221592Y550367D01*
Y554099D01*
X222892Y555399D01*
Y556710D01*
X222392Y557210D01*
Y564200D01*
X222992Y564800D01*
Y567107D01*
X221629Y568470D01*
Y572969D01*
X222860Y574200D01*
Y575332D01*
X221892Y576300D01*
Y584000D01*
X222902Y585010D01*
Y586357D01*
X220002Y589257D01*
Y593096D01*
X220667Y593761D01*
G01X285116Y412309D02*
X280792Y416633D01*
Y433500D01*
X276462Y437830D01*
X275330D01*
X274912Y437412D01*
X273780D01*
X272649Y438543D01*
Y439675D01*
X273067Y440093D01*
Y441225D01*
X271705Y442587D01*
X270573D01*
X268655Y440669D01*
X267523D01*
X266392Y441800D01*
Y442932D01*
X268310Y444850D01*
Y445982D01*
X267179Y447113D01*
X266047D01*
X264229Y445295D01*
X263097D01*
X226692Y481700D01*
Y502106D01*
X226082Y502716D01*
X224409D01*
X223799Y503326D01*
Y505306D01*
X224409Y505916D01*
X226082D01*
X226692Y506526D01*
Y507800D01*
X225192Y509300D01*
Y511047D01*
X226192Y512047D01*
Y516199D01*
X224892Y517499D01*
Y518428D01*
X226653Y520189D01*
Y521475D01*
X226043Y522085D01*
X225353D01*
X224743Y522695D01*
Y524675D01*
X225353Y525285D01*
X226043D01*
X226653Y525895D01*
Y527131D01*
X225092Y528692D01*
Y529432D01*
X226202Y530542D01*
Y535490D01*
X225092Y536600D01*
Y538600D01*
X225792Y539300D01*
Y540600D01*
X224796Y541596D01*
Y543204D01*
X225792Y544200D01*
Y546000D01*
X225192Y546600D01*
Y548847D01*
X226392Y550047D01*
Y553899D01*
X224892Y555399D01*
Y556890D01*
X225692Y557690D01*
Y559400D01*
X224492Y560600D01*
Y561800D01*
X225692Y563000D01*
Y565500D01*
X225109Y566083D01*
Y567216D01*
X226392Y568499D01*
Y573001D01*
X224959Y574434D01*
Y575867D01*
X225692Y576600D01*
Y578200D01*
X224492Y579400D01*
Y580900D01*
X225692Y582100D01*
Y584800D01*
X224992Y585500D01*
Y587735D01*
X224013Y588714D01*
G01X274753Y412486D02*
X271832Y415407D01*
Y425732D01*
X270040Y427524D01*
X269400D01*
X266677Y430247D01*
Y432544D01*
X265330Y433891D01*
X262270D01*
X260310Y435851D01*
Y438911D01*
X258963Y440258D01*
X255903D01*
X253943Y442218D01*
Y445278D01*
X252596Y446625D01*
X249536D01*
X247576Y448585D01*
Y451645D01*
X246229Y452992D01*
X243169D01*
X241209Y454952D01*
Y458012D01*
X239862Y459359D01*
X236802D01*
X234842Y461319D01*
Y464379D01*
X233495Y465726D01*
X230438D01*
X228475Y467689D01*
Y470114D01*
X226496Y472093D01*
X225068D01*
X222108Y475053D01*
Y477113D01*
X220412Y478809D01*
Y497209D01*
X217586Y500035D01*
Y522200D01*
X216966Y522820D01*
Y523820D01*
X217586Y524440D01*
Y525776D01*
X216966Y526396D01*
Y527396D01*
X217586Y528016D01*
Y538181D01*
X216966Y538801D01*
Y539801D01*
X217586Y540421D01*
Y541421D01*
X216966Y542041D01*
Y543041D01*
X217586Y543661D01*
Y544661D01*
X216966Y545281D01*
Y546281D01*
X217586Y546901D01*
Y556844D01*
X216966Y557464D01*
Y558464D01*
X217586Y559084D01*
Y560084D01*
X216966Y560704D01*
Y561704D01*
X217586Y562324D01*
Y563324D01*
X216966Y563944D01*
Y564944D01*
X217586Y565564D01*
Y575812D01*
X216966Y576432D01*
Y577432D01*
X217586Y578052D01*
Y579052D01*
X216966Y579672D01*
Y580672D01*
X217586Y581292D01*
Y582292D01*
X216966Y582912D01*
Y583912D01*
X217586Y584532D01*
Y587375D01*
X216447Y588514D01*
X215502D01*
G01X275503Y413237D02*
X272892Y415847D01*
Y426172D01*
X270480Y428584D01*
X269840D01*
X267737Y430687D01*
Y432987D01*
X265773Y434951D01*
X262713D01*
X261370Y436294D01*
Y439354D01*
X259406Y441318D01*
X256346D01*
X255003Y442661D01*
Y445721D01*
X253039Y447685D01*
X249979D01*
X248636Y449028D01*
Y452088D01*
X246672Y454052D01*
X243612D01*
X242269Y455395D01*
Y458455D01*
X240305Y460419D01*
X237245D01*
X235902Y461762D01*
Y464822D01*
X233938Y466786D01*
X230878D01*
X229535Y468129D01*
Y470554D01*
X226936Y473153D01*
X225508D01*
X223168Y475493D01*
Y477553D01*
X221472Y479249D01*
Y497652D01*
X218646Y500478D01*
Y587986D01*
X217058Y589574D01*
X217043D01*
X215503Y591114D01*
X215502D01*
G01X190549Y593757D02*
X188844Y595462D01*
Y605649D01*
X193895Y610700D01*
G01Y588714D02*
X193807D01*
X192121Y590400D01*
Y592092D01*
X192296Y592267D01*
Y594900D01*
X191184Y596012D01*
Y597088D01*
X192196Y598100D01*
Y599300D01*
X191184Y600312D01*
Y601388D01*
X192321Y602525D01*
Y603799D01*
X191621Y604499D01*
X190549D01*
G01X183856Y593757D02*
X182151Y595462D01*
Y605649D01*
X187202Y610700D01*
G01Y588714D02*
X187114D01*
X185428Y590400D01*
Y592092D01*
X185603Y592267D01*
Y594900D01*
X184491Y596012D01*
Y597088D01*
X185503Y598100D01*
Y599300D01*
X184491Y600312D01*
Y601388D01*
X185628Y602525D01*
Y603799D01*
X184928Y604499D01*
X183856D01*
G01X203935Y593757D02*
X202230Y595462D01*
Y607115D01*
X205415Y610300D01*
X206581D01*
G01Y588714D02*
X206493D01*
X204807Y590400D01*
Y592092D01*
X205714Y592999D01*
Y594592D01*
X204570Y595736D01*
Y597156D01*
X205414Y598000D01*
Y599700D01*
X204570Y600544D01*
Y601756D01*
X205514Y602700D01*
Y603900D01*
X204915Y604499D01*
X203935D01*
G01X227360Y593757D02*
X225655Y595462D01*
Y605649D01*
X230706Y610700D01*
G01X288671Y416664D02*
X285892Y419443D01*
Y441000D01*
X282443Y444449D01*
X281311D01*
X279893Y443031D01*
X278761D01*
X277630Y444162D01*
Y445294D01*
X279677Y447341D01*
Y448424D01*
X278546Y449555D01*
X277365D01*
X275367Y447557D01*
X274235D01*
X273104Y448688D01*
Y449820D01*
X275393Y452109D01*
Y453192D01*
X274262Y454323D01*
X273081D01*
X270841Y452083D01*
X269709D01*
X268439Y453353D01*
Y454485D01*
X270572Y456618D01*
Y457630D01*
X269441Y458761D01*
X268189D01*
X266176Y456748D01*
X265044D01*
X263892Y457900D01*
X257892D01*
X231492Y484300D01*
Y500100D01*
X232492Y501100D01*
Y508800D01*
X232102Y509190D01*
Y511657D01*
X232702Y512257D01*
Y516807D01*
X232152Y517357D01*
Y519200D01*
X232392Y519440D01*
Y527700D01*
X232152Y527940D01*
Y529816D01*
X232802Y530466D01*
Y535490D01*
X232102Y536190D01*
Y537500D01*
X232392Y537790D01*
Y540500D01*
X231592Y541300D01*
Y543600D01*
X232392Y544400D01*
Y546300D01*
X232102Y546590D01*
Y549457D01*
X232702Y550057D01*
Y554607D01*
X232152Y555157D01*
Y556900D01*
X232392Y557140D01*
Y565500D01*
X232152Y565740D01*
Y567647D01*
X233002Y568497D01*
Y573190D01*
X232002Y574190D01*
Y575400D01*
X232392Y575790D01*
Y584400D01*
X232002Y584790D01*
Y587470D01*
X230706Y588766D01*
Y588714D01*
G01D02*
X230618D01*
X228932Y590400D01*
Y592092D01*
X229107Y592267D01*
Y594900D01*
X227995Y596012D01*
Y597088D01*
X229007Y598100D01*
Y599300D01*
X227995Y600312D01*
Y601388D01*
X229132Y602525D01*
Y603799D01*
X228432Y604499D01*
X227360D01*
G01X197242Y593757D02*
X195537Y595462D01*
Y605435D01*
X196159Y606057D01*
Y607245D01*
X199214Y610300D01*
X200202D01*
G01X200288Y588714D02*
X200200D01*
X198514Y590400D01*
Y592600D01*
X199014Y593100D01*
Y594999D01*
X197877Y596136D01*
Y597464D01*
X198814Y598401D01*
Y599799D01*
X197877Y600736D01*
Y601964D01*
X198914Y603001D01*
Y603899D01*
X198314Y604499D01*
X197242D01*
G01X220667Y593761D02*
X218962Y595466D01*
Y605649D01*
X224013Y610700D01*
G01Y588714D02*
X223925D01*
X222239Y590400D01*
Y592092D01*
X222414Y592267D01*
Y594900D01*
X221302Y596012D01*
Y597088D01*
X222314Y598100D01*
Y599300D01*
X221302Y600312D01*
Y601388D01*
X222439Y602525D01*
Y603799D01*
X221739Y604499D01*
X220667D01*
G01X173591Y590900D02*
X175303Y592612D01*
Y594200D01*
X174203Y595300D01*
X173253D01*
X172663Y595890D01*
Y597260D01*
X173183Y597780D01*
X173793D01*
X174403Y598390D01*
Y599780D01*
X173793Y600390D01*
X173213D01*
X172663Y600940D01*
Y602360D01*
X173303Y603000D01*
X174583D01*
X175322Y603739D01*
Y605645D01*
X173617Y607350D01*
G01X210402Y590900D02*
X212114Y592612D01*
Y594200D01*
X211014Y595300D01*
X210064D01*
X209474Y595890D01*
Y597260D01*
X209994Y597780D01*
X210534D01*
X211144Y598390D01*
Y599780D01*
X210534Y600390D01*
X210024D01*
X209474Y600940D01*
Y602360D01*
X210114Y603000D01*
X211394D01*
X212133Y603739D01*
Y605645D01*
X210428Y607350D01*
G01X178691Y588514D02*
X178403D01*
X176986Y589931D01*
Y594900D01*
X176156Y595730D01*
Y602270D01*
X176986Y603100D01*
Y608044D01*
X178691Y609749D01*
G01X215502Y588514D02*
X215214D01*
X213797Y589931D01*
Y594900D01*
X212967Y595730D01*
Y602270D01*
X213797Y603100D01*
Y608044D01*
X215502Y609749D01*
G01X173591Y588300D02*
X173303D01*
X171603Y590000D01*
Y608011D01*
X173591Y609999D01*
G01X210402Y588300D02*
X210114D01*
X208414Y590000D01*
Y608011D01*
X210402Y609999D01*
G01X178691Y591114D02*
X180403Y592826D01*
Y594532D01*
X179435Y595500D01*
X177887D01*
X177216Y596171D01*
Y597448D01*
X177668Y597900D01*
X178003D01*
X178703Y598600D01*
Y599688D01*
X177993Y600398D01*
X177756D01*
X177216Y600938D01*
Y601829D01*
X177987Y602600D01*
X179503D01*
X180503Y603600D01*
Y605328D01*
X178691Y607140D01*
G01X215502Y591114D02*
X217214Y592826D01*
Y594500D01*
X216214Y595500D01*
X214698D01*
X214027Y596171D01*
Y597448D01*
X214479Y597900D01*
X214814D01*
X215514Y598600D01*
Y599688D01*
X214804Y600398D01*
X214567D01*
X214027Y600938D01*
Y601829D01*
X214798Y602600D01*
X216314D01*
X217314Y603600D01*
Y605328D01*
X215502Y607140D01*
G01X284024Y52100D02*
X287130Y48994D01*
Y32848D01*
X285802Y31520D01*
X284820D01*
X284050Y30750D01*
G01X284024Y49500D02*
X285123D01*
X286070Y48553D01*
Y46020D01*
X285100Y45050D01*
X284752D01*
X284136Y44434D01*
Y43102D01*
X284638Y42600D01*
X285350D01*
X286070Y41880D01*
Y40920D01*
X285250Y40100D01*
X284750D01*
X284150Y39500D01*
Y38500D01*
X286070Y36580D01*
Y33291D01*
X285359Y32580D01*
X284843D01*
X284024Y33399D01*
G01X289124Y52314D02*
X292316Y49122D01*
Y33732D01*
X289124Y30540D01*
G01X277557Y27899D02*
Y30021D01*
X279436Y31900D01*
X280836D01*
X282292Y33356D01*
Y34700D01*
X281676Y35316D01*
Y48441D01*
X280203Y49914D01*
G01X270864Y27899D02*
X271992Y29027D01*
Y30581D01*
X273111Y31700D01*
X274335D01*
X275911Y33276D01*
Y34900D01*
X275136Y35675D01*
Y48688D01*
X273910Y49914D01*
G01X240746Y17157D02*
Y25054D01*
X242613Y26921D01*
Y28444D01*
X241592Y29465D01*
Y34400D01*
X242592Y35400D01*
Y37200D01*
X242192Y37600D01*
Y45900D01*
X242592Y46300D01*
Y47785D01*
X241463Y48914D01*
Y53172D01*
X242692Y54401D01*
Y66188D01*
X241492Y67388D01*
Y72012D01*
X242813Y73333D01*
Y74579D01*
X242292Y75100D01*
Y83579D01*
X242813Y84100D01*
Y85364D01*
X241463Y86714D01*
Y90972D01*
X242813Y92322D01*
Y104827D01*
X241466Y106174D01*
Y110374D01*
X242566Y111474D01*
Y115585D01*
X244652Y117671D01*
Y118802D01*
X242727Y120727D01*
Y121435D01*
X244282Y122990D01*
X244990D01*
X246916Y121064D01*
X248045D01*
X249281Y122300D01*
Y123433D01*
X246835Y125879D01*
Y126587D01*
X266486Y146238D01*
Y148830D01*
X307992Y190336D01*
Y197503D01*
X313889Y203400D01*
G01X243392Y-4100D02*
X242525Y-3233D01*
Y-932D01*
X240892Y701D01*
Y2000D01*
X242242Y3350D01*
Y4250D01*
X240992Y5500D01*
Y6699D01*
X242525Y8232D01*
Y10200D01*
X239625Y13100D01*
Y16036D01*
X240746Y17157D01*
G01X243392Y12114D02*
X244865Y10641D01*
Y-2484D01*
X245481Y-3100D01*
Y-4444D01*
X244025Y-5900D01*
X242625D01*
X240746Y-7779D01*
Y-9901D01*
G01X316124Y201765D02*
X310892Y196533D01*
Y189700D01*
X268894Y147702D01*
Y145356D01*
X251192Y127654D01*
Y120675D01*
X245313Y114796D01*
Y83980D01*
X245892Y83401D01*
Y75400D01*
X245313Y74821D01*
Y46100D01*
X245892Y45521D01*
Y37800D01*
X245313Y37221D01*
Y25921D01*
X242813Y23421D01*
Y16722D01*
X241319Y15228D01*
Y14187D01*
X243392Y12114D01*
G01X264171Y17157D02*
Y17773D01*
X266413Y20015D01*
Y28199D01*
X265613Y28999D01*
Y34821D01*
X266113Y35321D01*
Y37179D01*
X265546Y37746D01*
Y45633D01*
X266113Y46200D01*
Y48014D01*
X265513Y48614D01*
Y53314D01*
X266463Y54264D01*
Y65949D01*
X265613Y66799D01*
Y72621D01*
X266113Y73121D01*
Y74679D01*
X265392Y75400D01*
Y83279D01*
X266113Y84000D01*
Y85814D01*
X265513Y86414D01*
Y91114D01*
X266066Y91667D01*
Y104974D01*
X265466Y105574D01*
Y110574D01*
X266066Y111174D01*
Y114110D01*
X293592Y141636D01*
Y150994D01*
X295452Y152854D01*
X296244D01*
X299349Y149749D01*
X300141D01*
X301160Y150768D01*
Y151560D01*
X298055Y154665D01*
Y155457D01*
X333218Y190620D01*
Y194591D01*
G01X267517Y-3700D02*
X265950Y-2133D01*
Y-932D01*
X264592Y426D01*
Y1799D01*
X265792Y2999D01*
Y4125D01*
X264592Y5325D01*
Y6900D01*
X266392Y8700D01*
Y9758D01*
X263050Y13100D01*
Y16036D01*
X264171Y17157D01*
G01X267517Y12114D02*
X268906Y10725D01*
Y-2288D01*
X269518Y-2900D01*
Y-4300D01*
X267718Y-6100D01*
X266718D01*
X265418Y-7400D01*
Y-8654D01*
X264171Y-9901D01*
G01X335718Y194591D02*
Y189583D01*
X304092Y157957D01*
Y148600D01*
X268866Y113374D01*
Y111274D01*
X269534Y110606D01*
Y105941D01*
X269013Y105420D01*
Y91874D01*
X269613Y91274D01*
Y86614D01*
X268913Y85914D01*
Y83900D01*
X269592Y83221D01*
Y75300D01*
X268913Y74621D01*
Y73179D01*
X269513Y72579D01*
Y67049D01*
X268963Y66499D01*
Y53864D01*
X269292Y53535D01*
Y48493D01*
X268913Y48114D01*
Y46179D01*
X269592Y45500D01*
Y37579D01*
X268913Y36900D01*
Y35379D01*
X269513Y34779D01*
Y29249D01*
X268963Y28699D01*
Y18964D01*
X265613Y15614D01*
Y14018D01*
X267517Y12114D01*
G01X234053Y17157D02*
X233125Y16229D01*
Y13101D01*
X235925Y10301D01*
Y8432D01*
X234542Y7049D01*
Y5650D01*
X235992Y4200D01*
Y3000D01*
X234492Y1500D01*
Y301D01*
X235925Y-1132D01*
Y-3012D01*
X237013Y-4100D01*
G01X304512Y204600D02*
X301892Y201980D01*
Y199700D01*
X299092Y196900D01*
Y193100D01*
X300092Y192100D01*
Y189508D01*
X276229Y165645D01*
X275097D01*
X274363Y166379D01*
X273571D01*
X272100Y164908D01*
Y164116D01*
X272834Y163382D01*
Y162250D01*
X235853Y125269D01*
Y111361D01*
X235166Y110674D01*
Y105874D01*
X236013Y105027D01*
Y92114D01*
X235113Y91214D01*
Y86414D01*
X236113Y85414D01*
Y84020D01*
X235592Y83499D01*
Y75200D01*
X236113Y74679D01*
Y73099D01*
X235113Y72099D01*
Y67079D01*
X236013Y66179D01*
Y54314D01*
X235113Y53414D01*
Y48614D01*
X236113Y47614D01*
Y46200D01*
X235592Y45679D01*
Y37300D01*
X236113Y36779D01*
Y35299D01*
X235113Y34299D01*
Y29379D01*
X236013Y28479D01*
Y19117D01*
X234053Y17157D01*
G01X237099Y12114D02*
X238325Y10888D01*
Y-2125D01*
X239100Y-2900D01*
Y-4524D01*
X237524Y-6100D01*
X236300D01*
X234053Y-8347D01*
Y-9901D01*
G01X306392Y202936D02*
X305092Y201636D01*
Y190972D01*
X238366Y124246D01*
Y111774D01*
X238966Y111174D01*
Y105874D01*
X238713Y105621D01*
Y103579D01*
X238942Y103350D01*
Y86443D01*
X238792Y86293D01*
Y83900D01*
X239392Y83300D01*
Y75399D01*
X238892Y74899D01*
Y64700D01*
X238713Y64521D01*
Y53864D01*
X238963Y53614D01*
Y48664D01*
X238613Y48314D01*
Y46200D01*
X240092Y44721D01*
Y37942D01*
X238946Y36796D01*
Y28832D01*
X238392Y28278D01*
Y18793D01*
X235113Y15514D01*
Y14100D01*
X237099Y12114D01*
G01X257478Y17157D02*
Y19379D01*
X259513Y21414D01*
Y28499D01*
X258913Y29099D01*
Y34721D01*
X259713Y35521D01*
Y36979D01*
X258992Y37700D01*
Y45679D01*
X259713Y46400D01*
Y47914D01*
X258913Y48714D01*
Y53414D01*
X259313Y53814D01*
Y66499D01*
X258913Y66899D01*
Y72521D01*
X259713Y73321D01*
Y74979D01*
X259092Y75600D01*
Y83499D01*
X259713Y84120D01*
Y85714D01*
X258913Y86514D01*
Y91214D01*
X259313Y91614D01*
Y105627D01*
X258566Y106374D01*
Y110474D01*
X259566Y111474D01*
Y114682D01*
X284530Y139646D01*
Y140508D01*
X281304Y143734D01*
Y144596D01*
X282168Y145460D01*
X283030D01*
X286295Y142195D01*
X287087D01*
X288021Y143129D01*
Y143921D01*
X284692Y147250D01*
Y149165D01*
X328392Y192865D01*
Y195407D01*
X328368Y195431D01*
G01X260824Y-3700D02*
X259350Y-2226D01*
Y-1132D01*
X257917Y301D01*
Y1524D01*
X259417Y3024D01*
Y4376D01*
X257917Y5876D01*
Y6999D01*
X259592Y8674D01*
Y10059D01*
X256550Y13101D01*
Y16229D01*
X257478Y17157D01*
G01X260824Y12114D02*
X262213Y10725D01*
Y-2288D01*
X262825Y-2900D01*
Y-4300D01*
X261025Y-6100D01*
X260025D01*
X258725Y-7400D01*
Y-8654D01*
X257478Y-9901D01*
G01X330718Y195421D02*
Y191655D01*
X291092Y152029D01*
Y142672D01*
X262166Y113746D01*
Y111474D01*
X262966Y110674D01*
Y105774D01*
X262313Y105121D01*
Y91714D01*
X263013Y91014D01*
Y86514D01*
X262213Y85714D01*
Y83800D01*
X262792Y83221D01*
Y75700D01*
X262213Y75121D01*
Y73179D01*
X263113Y72279D01*
Y67299D01*
X262313Y66499D01*
Y53914D01*
X263013Y53214D01*
Y48714D01*
X262213Y47914D01*
Y46200D01*
X262792Y45621D01*
Y37700D01*
X262213Y37121D01*
Y35279D01*
X263113Y34379D01*
Y29499D01*
X262013Y28399D01*
Y25655D01*
X262313Y25355D01*
Y20678D01*
X260463Y18828D01*
Y17464D01*
X259013Y16014D01*
Y13925D01*
X260824Y12114D01*
G01X247213Y14300D02*
X248939Y16026D01*
Y17752D01*
X247791Y18900D01*
X247139D01*
X246419Y19620D01*
Y21088D01*
X250293Y24962D01*
Y36780D01*
X250913Y37400D01*
Y38400D01*
X250293Y39020D01*
Y39780D01*
X250913Y40400D01*
Y41400D01*
X250293Y42020D01*
Y42780D01*
X250913Y43400D01*
Y44400D01*
X250293Y45020D01*
Y55880D01*
X250913Y56500D01*
Y57500D01*
X250293Y58120D01*
Y114569D01*
X257534Y121810D01*
Y123922D01*
X255117Y126339D01*
Y127379D01*
X257017Y129279D01*
X258177D01*
X260534Y126922D01*
X262646D01*
X273863Y138139D01*
Y147464D01*
X297559Y171160D01*
X298195D01*
X298903Y171868D01*
Y172504D01*
X299610Y173211D01*
X300246D01*
X300954Y173919D01*
Y174555D01*
X301735Y175336D01*
X302372D01*
X303080Y176044D01*
Y176681D01*
X304051Y177652D01*
X304687D01*
X305395Y178360D01*
Y178996D01*
X306102Y179703D01*
X306739D01*
X307447Y180411D01*
Y181048D01*
X308258Y181859D01*
X308894D01*
X309602Y182567D01*
Y183203D01*
X310309Y183910D01*
X310945D01*
X311653Y184618D01*
Y185254D01*
X312572Y186173D01*
X313209D01*
X313917Y186881D01*
Y187518D01*
X314652Y188253D01*
Y190343D01*
X315102Y190793D01*
Y191793D01*
X314652Y192243D01*
Y193448D01*
X319692Y198488D01*
G01X247239Y-7050D02*
X248009Y-6280D01*
X248991D01*
X250319Y-4952D01*
Y11194D01*
X247213Y14300D01*
G01X284050Y-7050D02*
X284820Y-6280D01*
X285802D01*
X287130Y-4952D01*
Y11194D01*
X284024Y14300D01*
G01X252313Y14514D02*
X254139Y16340D01*
Y17900D01*
X252119Y19920D01*
Y20788D01*
X253093Y21762D01*
X253969D01*
X254677Y22470D01*
Y23346D01*
X255393Y24062D01*
Y32500D01*
X255992Y33099D01*
Y33901D01*
X255393Y34500D01*
Y36980D01*
X256013Y37600D01*
Y38600D01*
X255393Y39220D01*
Y39980D01*
X256013Y40600D01*
Y41600D01*
X255393Y42220D01*
Y114269D01*
X278435Y137311D01*
Y146618D01*
X323382Y191565D01*
Y193803D01*
X325860Y196281D01*
G01X252313Y-7260D02*
X255505Y-4068D01*
Y11322D01*
X252313Y14514D01*
G01X289124Y-7260D02*
X292316Y-4068D01*
Y11322D01*
X289124Y14514D01*
G01X247213Y11700D02*
X245359Y13554D01*
Y21531D01*
X249233Y25405D01*
Y115009D01*
X256474Y122250D01*
Y123482D01*
X254057Y125899D01*
Y127819D01*
X256577Y130339D01*
X258617D01*
X260974Y127982D01*
X262206D01*
X272803Y138579D01*
Y147904D01*
X313592Y188693D01*
Y193888D01*
X318942Y199238D01*
G01X247213Y-4401D02*
X248032Y-5220D01*
X248548D01*
X249259Y-4509D01*
Y-1220D01*
X247339Y700D01*
Y1700D01*
X247939Y2300D01*
X248439D01*
X249259Y3120D01*
Y4080D01*
X248539Y4800D01*
X247827D01*
X247325Y5302D01*
Y6634D01*
X247941Y7250D01*
X248289D01*
X249259Y8220D01*
Y10753D01*
X248312Y11700D01*
X247213D01*
G01X284024Y-4401D02*
X284843Y-5220D01*
X285359D01*
X286070Y-4509D01*
Y-1220D01*
X284150Y700D01*
Y1700D01*
X284750Y2300D01*
X285250D01*
X286070Y3120D01*
Y4080D01*
X285350Y4800D01*
X284638D01*
X284136Y5302D01*
Y6634D01*
X284752Y7250D01*
X285100D01*
X286070Y8220D01*
Y10753D01*
X285123Y11700D01*
X284024D01*
G01X252313Y11914D02*
X250589Y13638D01*
Y18097D01*
X251059Y18567D01*
Y21231D01*
X254333Y24505D01*
Y114709D01*
X277375Y137751D01*
Y147058D01*
X317685Y187368D01*
Y188005D01*
X318393Y188713D01*
X319030D01*
X320132Y189815D01*
Y190451D01*
X320840Y191159D01*
X321476D01*
X322322Y192005D01*
Y194243D01*
X323029Y194950D01*
Y195586D01*
X323737Y196294D01*
X324373D01*
X325110Y197031D01*
G01X252313Y-4651D02*
X253422D01*
X254445Y-3628D01*
Y-1007D01*
X253738Y-300D01*
X252940D01*
X252339Y301D01*
Y1499D01*
X252940Y2100D01*
X253638D01*
X254445Y2907D01*
Y4280D01*
X253725Y5000D01*
X253225D01*
X252525Y5700D01*
Y6700D01*
X253225Y7400D01*
X253739D01*
X254445Y8106D01*
Y10881D01*
X253411Y11915D01*
X252313D01*
Y11914D01*
G01X289124Y-4651D02*
X290233D01*
X291256Y-3628D01*
Y-1007D01*
X290549Y-300D01*
X289751D01*
X289150Y301D01*
Y1499D01*
X289751Y2100D01*
X290449D01*
X291256Y2907D01*
Y4280D01*
X290536Y5000D01*
X290036D01*
X289336Y5700D01*
Y6700D01*
X290036Y7400D01*
X290550D01*
X291256Y8106D01*
Y10881D01*
X290222Y11915D01*
X289124D01*
Y11914D01*
G01X277557Y17157D02*
X276436Y16036D01*
Y13100D01*
X279336Y10200D01*
Y-3233D01*
X280203Y-4100D01*
G01Y12114D02*
X281676Y10641D01*
Y-2484D01*
X282292Y-3100D01*
Y-4444D01*
X280836Y-5900D01*
X279436D01*
X277557Y-7779D01*
Y-9901D01*
G01X270864Y17157D02*
X269936Y16229D01*
Y13101D01*
X272736Y10301D01*
Y-3012D01*
X273824Y-4100D01*
G01X273910Y12114D02*
X275136Y10888D01*
Y-2125D01*
X275911Y-2900D01*
Y-4524D01*
X274335Y-6100D01*
X273111D01*
X270864Y-8347D01*
Y-9901D01*
G01X294289Y17157D02*
X293036Y15904D01*
Y14150D01*
X296036Y11150D01*
Y-2101D01*
X297635Y-3700D01*
G01X284024Y110514D02*
X287041Y107497D01*
Y61747D01*
X285041Y59747D01*
Y56451D01*
X285750Y55742D01*
Y53826D01*
X284024Y52100D01*
G01X289124Y107655D02*
X291081Y105698D01*
Y60092D01*
X289181Y58192D01*
Y57520D01*
X287400Y55739D01*
Y51438D01*
X289124Y49714D01*
G01D02*
Y49715D01*
X290222D01*
X291256Y48681D01*
Y45906D01*
X290550Y45200D01*
X290036D01*
X289336Y44500D01*
Y43500D01*
X290036Y42800D01*
X290536D01*
X291256Y42080D01*
Y40707D01*
X290449Y39900D01*
X289914D01*
X289313Y39299D01*
Y38101D01*
X289914Y37500D01*
X290549D01*
X291256Y36793D01*
Y34172D01*
X290233Y33149D01*
X289124D01*
G01X284050Y107865D02*
X285981Y105934D01*
Y62190D01*
X283981Y60190D01*
Y57320D01*
X282050Y55389D01*
Y51474D01*
X284024Y49500D01*
G01X289150Y110264D02*
Y110238D01*
X292141Y107247D01*
Y59649D01*
X290241Y57749D01*
Y56620D01*
X290950Y55911D01*
Y54140D01*
X289124Y52314D01*
G01X277557Y112327D02*
X278266Y111618D01*
Y105974D01*
X279366Y104874D01*
Y92074D01*
X277966Y90674D01*
Y86874D01*
X279366Y85474D01*
Y84000D01*
X278892Y83526D01*
Y75600D01*
X279366Y75126D01*
Y73275D01*
X278366Y72275D01*
Y67327D01*
X278498Y67195D01*
Y67193D01*
X279466Y66225D01*
Y64759D01*
X277557Y62850D01*
Y54957D01*
G01D02*
X276592Y53992D01*
Y50744D01*
X279336Y48000D01*
Y34567D01*
X280203Y33700D01*
G01Y49914D02*
X278492Y51625D01*
Y53350D01*
X279616Y54474D01*
Y61809D01*
X282066Y64259D01*
Y74874D01*
X282792Y75600D01*
Y83274D01*
X282066Y84000D01*
Y105071D01*
X280203Y106934D01*
G01X273824Y33700D02*
X272736Y34788D01*
Y48101D01*
X272092Y48745D01*
Y53729D01*
X270864Y54957D01*
G01D02*
X272766Y56859D01*
Y66227D01*
X271966Y67027D01*
Y72159D01*
X272766Y72959D01*
Y74726D01*
X272192Y75300D01*
Y83426D01*
X272766Y84000D01*
Y85574D01*
X271966Y86374D01*
Y90974D01*
X272766Y91774D01*
Y105074D01*
X271966Y105874D01*
Y111225D01*
X270864Y112327D01*
G01X273910Y49914D02*
X274592Y50596D01*
Y54700D01*
X275392Y55500D01*
Y66985D01*
X275766Y67359D01*
Y72659D01*
X275466Y72959D01*
Y75174D01*
X276192Y75900D01*
Y83374D01*
X275466Y84100D01*
Y86074D01*
X275866Y86474D01*
Y91174D01*
X275566Y91474D01*
Y105628D01*
X273910Y107284D01*
G01X297635Y34100D02*
X296036Y35699D01*
Y48950D01*
X293036Y51950D01*
Y53704D01*
X294289Y54957D01*
G01X309675Y404426D02*
Y411417D01*
X294992Y426100D01*
Y445100D01*
X274131Y465961D01*
X263432D01*
X242813Y486580D01*
Y488680D01*
X241292Y490201D01*
Y507900D01*
X242505Y509113D01*
Y511087D01*
X241463Y512129D01*
Y516371D01*
X242631Y517539D01*
Y529449D01*
X241463Y530617D01*
Y535270D01*
X242588Y536395D01*
Y548732D01*
X241463Y549857D01*
Y554107D01*
X242613Y555257D01*
Y567267D01*
X241513Y568367D01*
Y573121D01*
X242561Y574169D01*
Y575802D01*
X242392Y575971D01*
Y586728D01*
X239711Y589409D01*
Y592722D01*
X240746Y593757D01*
G01X312175Y404426D02*
Y412517D01*
X297592Y427100D01*
Y448700D01*
X293820Y452472D01*
X292688D01*
X292570Y452354D01*
X291438D01*
X290307Y453485D01*
Y454617D01*
X290425Y454735D01*
Y455867D01*
X289294Y456998D01*
X288162D01*
X288044Y456880D01*
X286912D01*
X285781Y458011D01*
Y459143D01*
X285899Y459261D01*
Y460393D01*
X284768Y461524D01*
X283636D01*
X283518Y461406D01*
X282386D01*
X281255Y462537D01*
Y463669D01*
X281373Y463787D01*
Y464919D01*
X280242Y466050D01*
X279110D01*
X278992Y465932D01*
X277860D01*
X276729Y467063D01*
Y468195D01*
X276847Y468313D01*
Y469445D01*
X275792Y470500D01*
X274170D01*
X273560Y469890D01*
Y468693D01*
X272950Y468083D01*
X270970D01*
X270360Y468693D01*
Y470518D01*
X269750Y471128D01*
X267770D01*
X267160Y470518D01*
Y468693D01*
X266550Y468083D01*
X264570D01*
X263960Y468693D01*
Y469890D01*
X263350Y470500D01*
X262492D01*
X245313Y487679D01*
Y518500D01*
X245792Y518979D01*
Y528400D01*
X245313Y528879D01*
Y537700D01*
X245792Y538179D01*
Y546300D01*
X245313Y546779D01*
Y556500D01*
X245792Y556979D01*
Y565600D01*
X245313Y566079D01*
Y575620D01*
X245792Y576099D01*
Y584100D01*
X245313Y584579D01*
Y586443D01*
X243392Y588364D01*
Y588714D01*
G01X304375Y403882D02*
Y409517D01*
X289992Y423900D01*
Y442900D01*
X271057Y461835D01*
X259681D01*
X236166Y485350D01*
Y488426D01*
X235166Y489426D01*
Y502174D01*
X235392Y502400D01*
Y508600D01*
X236192Y509400D01*
Y510718D01*
X235113Y511797D01*
Y516457D01*
X236013Y517357D01*
Y519300D01*
X235692Y519621D01*
Y527900D01*
X236275Y528483D01*
Y529216D01*
X235113Y530378D01*
Y535242D01*
X236113Y536242D01*
Y537800D01*
X235692Y538221D01*
Y546600D01*
X236113Y547021D01*
Y548557D01*
X235113Y549557D01*
Y554221D01*
X236468Y555576D01*
Y557125D01*
X235692Y557901D01*
Y565400D01*
X236013Y565721D01*
Y567179D01*
X234965Y568227D01*
Y572944D01*
X235963Y573942D01*
Y575728D01*
X235692Y575999D01*
Y583900D01*
X235963Y584171D01*
Y586457D01*
X232813Y589607D01*
Y592517D01*
X234053Y593757D01*
G01X306875Y403882D02*
Y410617D01*
X292492Y425000D01*
Y444000D01*
X272613Y463879D01*
X262705D01*
X260124Y466460D01*
X259262D01*
X258926Y466124D01*
X258064D01*
X256663Y467525D01*
Y468387D01*
X256999Y468723D01*
Y469585D01*
X255598Y470986D01*
X254736D01*
X254400Y470650D01*
X253538D01*
X252137Y472051D01*
Y472913D01*
X252473Y473249D01*
Y474111D01*
X251072Y475512D01*
X250210D01*
X249874Y475176D01*
X249012D01*
X247611Y476577D01*
Y477439D01*
X247947Y477775D01*
Y478637D01*
X246546Y480038D01*
X245684D01*
X245348Y479702D01*
X244486D01*
X243085Y481103D01*
Y481965D01*
X243421Y482301D01*
Y483163D01*
X242020Y484564D01*
X241158D01*
X240822Y484228D01*
X239960D01*
X238592Y485596D01*
Y494200D01*
X237492Y495300D01*
Y502299D01*
X239492Y504299D01*
Y508500D01*
X238392Y509600D01*
Y511176D01*
X238963Y511747D01*
Y516629D01*
X238358Y517234D01*
Y519265D01*
X239092Y519999D01*
Y527800D01*
X238713Y528179D01*
Y529992D01*
X238963Y530242D01*
Y535192D01*
X238392Y535763D01*
Y537179D01*
X239092Y537879D01*
Y546100D01*
X238092Y547100D01*
Y549000D01*
X238963Y549871D01*
Y555007D01*
X238292Y555678D01*
Y557199D01*
X239092Y557999D01*
Y564200D01*
X237992Y565300D01*
Y567200D01*
X239213Y568421D01*
Y573080D01*
X238292Y574001D01*
Y575399D01*
X239092Y576199D01*
Y583900D01*
X238613Y584379D01*
Y587200D01*
X237099Y588714D01*
G01X316205Y406287D02*
Y413859D01*
X301472Y428592D01*
Y450052D01*
X276944Y474580D01*
X263941D01*
X252154Y486367D01*
X250293Y490860D01*
Y587849D01*
X247242Y590900D01*
X247213D01*
G01X319375Y408160D02*
Y414589D01*
X304214Y429750D01*
X304212D01*
Y451248D01*
X296624Y458836D01*
Y460950D01*
X297184Y461510D01*
Y462736D01*
X295977Y463943D01*
X294751D01*
X294191Y463383D01*
X292077D01*
X290257Y465203D01*
Y467317D01*
X290817Y467877D01*
Y469106D01*
X289613Y470310D01*
X287171D01*
X283890Y473591D01*
Y475474D01*
X282044Y477320D01*
X265301D01*
X254333Y488288D01*
Y507212D01*
X253922Y507623D01*
Y508623D01*
X254333Y509034D01*
Y519493D01*
X253839Y519987D01*
Y520987D01*
X254333Y521481D01*
Y522509D01*
X253713Y523129D01*
Y524129D01*
X254333Y524749D01*
Y525749D01*
X253713Y526369D01*
Y527369D01*
X254333Y527989D01*
Y538042D01*
X253713Y538662D01*
Y539662D01*
X254333Y540282D01*
Y541282D01*
X253713Y541902D01*
Y542902D01*
X254333Y543522D01*
Y544522D01*
X253713Y545142D01*
Y546142D01*
X254333Y546762D01*
Y556983D01*
X253713Y557603D01*
Y558603D01*
X254333Y559223D01*
Y560223D01*
X253713Y560843D01*
Y561843D01*
X254333Y562463D01*
Y563463D01*
X253713Y564083D01*
Y565083D01*
X254333Y565703D01*
Y576036D01*
X253713Y576656D01*
Y577656D01*
X254333Y578276D01*
Y579276D01*
X253713Y579896D01*
Y580896D01*
X254333Y581516D01*
Y582516D01*
X253713Y583136D01*
Y584136D01*
X254333Y584756D01*
Y587595D01*
X253414Y588514D01*
X252313D01*
G01X315145Y406287D02*
Y413419D01*
X300414Y428150D01*
X300412D01*
Y449609D01*
X276501Y473520D01*
X263501D01*
X251255Y485766D01*
X249233Y490649D01*
Y577044D01*
X248753Y577524D01*
Y578524D01*
X249233Y579004D01*
Y580004D01*
X248753Y580484D01*
Y581484D01*
X249233Y581964D01*
Y582964D01*
X248753Y583444D01*
Y584444D01*
X249233Y584924D01*
Y587409D01*
X248342Y588300D01*
X247213D01*
G01X320435Y408160D02*
Y415029D01*
X305272Y430192D01*
Y451691D01*
X297684Y459279D01*
Y460507D01*
X298244Y461067D01*
Y463179D01*
X296420Y465003D01*
X294308D01*
X293748Y464443D01*
X292520D01*
X291317Y465646D01*
Y466874D01*
X291877Y467434D01*
Y469546D01*
X290053Y471370D01*
X287611D01*
X284950Y474031D01*
Y475914D01*
X282484Y478380D01*
X265741D01*
X255393Y488728D01*
Y588035D01*
X252314Y591114D01*
X252313D01*
G01X284039Y495944D02*
Y496075D01*
X285804Y497840D01*
Y504058D01*
X287104Y505358D01*
Y550049D01*
X284053Y553100D01*
X284024D01*
G01X289124Y493344D02*
X287364Y495104D01*
Y499672D01*
X289832Y502140D01*
Y502989D01*
X291144Y504301D01*
Y520400D01*
X289132Y522412D01*
Y525440D01*
X291144Y527452D01*
Y540148D01*
X290192Y541100D01*
Y545400D01*
X291144Y546352D01*
Y548695D01*
X289125Y550714D01*
X289124D01*
G01X284039Y493344D02*
Y493375D01*
X282312Y495102D01*
Y502066D01*
X286044Y505798D01*
Y548509D01*
X284053Y550500D01*
X284024D01*
G01X289124Y495944D02*
X290892Y497712D01*
Y502549D01*
X292204Y503861D01*
Y520840D01*
X290192Y522852D01*
Y525000D01*
X292204Y527012D01*
Y540588D01*
X291252Y541540D01*
Y544960D01*
X292204Y545912D01*
Y550235D01*
X289125Y553314D01*
X289124D01*
G01X277557Y498644D02*
Y505042D01*
X279624Y507109D01*
Y510707D01*
X278274Y512057D01*
Y516307D01*
X279424Y517457D01*
Y519600D01*
X279192Y519832D01*
Y527900D01*
X279424Y528132D01*
Y529467D01*
X278324Y530567D01*
Y535233D01*
X279474Y536383D01*
Y537700D01*
X279192Y537982D01*
Y546500D01*
X279474Y546782D01*
Y548657D01*
X276124Y552007D01*
Y554524D01*
X277557Y555957D01*
G01X280203Y493244D02*
Y503890D01*
X282124Y505811D01*
Y518432D01*
X282592Y518900D01*
Y527800D01*
X282124Y528268D01*
Y537700D01*
X282592Y538168D01*
Y546300D01*
X282124Y546768D01*
Y548643D01*
X280203Y550564D01*
Y550914D01*
G01X271092Y498644D02*
Y506778D01*
X272924Y508610D01*
Y510757D01*
X271924Y511757D01*
Y516457D01*
X272824Y517357D01*
Y519300D01*
X272592Y519532D01*
Y527700D01*
X272824Y527932D01*
Y529469D01*
X271776Y530517D01*
Y535144D01*
X272774Y536142D01*
Y538000D01*
X272592Y538182D01*
Y546600D01*
X272774Y546782D01*
Y548657D01*
G01X273992Y493744D02*
X275792Y495544D01*
Y503200D01*
X275592Y503400D01*
Y510825D01*
X275774Y511007D01*
Y517207D01*
X275524Y517457D01*
Y519400D01*
X275892Y519768D01*
Y527900D01*
X275524Y528268D01*
Y530197D01*
X276024Y530697D01*
Y534856D01*
X275424Y535456D01*
Y537500D01*
X275892Y537968D01*
Y545900D01*
X275424Y546368D01*
Y549400D01*
X273910Y550914D01*
G01X328748Y405699D02*
Y417644D01*
X313192Y433200D01*
Y461214D01*
X288406Y486000D01*
X269693D01*
X265892Y489801D01*
Y495100D01*
X266113Y495321D01*
Y511157D01*
X265613Y511657D01*
Y517057D01*
X266463Y517907D01*
Y519100D01*
X265892Y519671D01*
Y527800D01*
X266419Y528327D01*
Y529460D01*
X265513Y530366D01*
Y535822D01*
X266113Y536422D01*
Y537800D01*
X265792Y538121D01*
Y546300D01*
X266113Y546621D01*
Y548957D01*
X265613Y549457D01*
Y554857D01*
X266413Y555657D01*
Y556900D01*
X265892Y557421D01*
Y565700D01*
X266413Y566221D01*
Y567297D01*
X265313Y568397D01*
Y573142D01*
X266213Y574042D01*
Y575500D01*
X265792Y575921D01*
Y584400D01*
X266213Y584821D01*
Y586507D01*
X262813Y589907D01*
Y592399D01*
X264171Y593757D01*
G01X331248Y405851D02*
Y418744D01*
X315692Y434300D01*
Y461387D01*
X310308Y466771D01*
Y467609D01*
X311095Y468396D01*
Y469283D01*
X309694Y470684D01*
X308832D01*
X308045Y469896D01*
X307183D01*
X305782Y471297D01*
Y472159D01*
X307017Y473396D01*
Y474257D01*
X305616Y475658D01*
X304753D01*
X303519Y474422D01*
X302657D01*
X301256Y475823D01*
Y476685D01*
X302481Y477912D01*
X302673Y478104D01*
Y478965D01*
X301272Y480366D01*
X300409D01*
X298993Y478948D01*
X298131D01*
X296730Y480349D01*
Y481211D01*
X298175Y482658D01*
Y483519D01*
X296774Y484920D01*
X295911D01*
X294467Y483474D01*
X293605D01*
X288479Y488600D01*
X274092D01*
X272192Y490500D01*
Y492000D01*
X269392Y494800D01*
Y496926D01*
X268913Y497405D01*
Y511657D01*
X269513Y512257D01*
Y516807D01*
X268963Y517357D01*
Y519100D01*
X269192Y519329D01*
Y527900D01*
X268963Y528129D01*
Y529816D01*
X269613Y530466D01*
Y535578D01*
X268913Y536278D01*
Y537600D01*
X269192Y537879D01*
Y546200D01*
X268913Y546479D01*
Y549200D01*
G01X268963Y555500D02*
Y567647D01*
X269813Y568497D01*
Y573178D01*
X268813Y574178D01*
Y575300D01*
X269192Y575679D01*
Y583700D01*
X268813Y584079D01*
Y587470D01*
X267517Y588766D01*
Y588714D01*
G01X323375Y406172D02*
Y415817D01*
X308092Y431100D01*
Y452900D01*
X301592Y459400D01*
Y463600D01*
X284192Y481000D01*
X266992D01*
X259092Y488900D01*
Y494600D01*
X259713Y495221D01*
Y511257D01*
X258913Y512057D01*
Y516957D01*
X259313Y517357D01*
Y519300D01*
X259192Y519421D01*
Y527600D01*
X259313Y527721D01*
Y529842D01*
X258913Y530242D01*
Y535722D01*
X259713Y536522D01*
Y538180D01*
X259146Y538747D01*
Y545954D01*
X259713Y546521D01*
Y549057D01*
X258913Y549857D01*
Y554757D01*
X259513Y555357D01*
Y557400D01*
X259192Y557721D01*
Y565800D01*
X259513Y566121D01*
Y567397D01*
X258440Y568470D01*
Y572969D01*
X259713Y574242D01*
Y575500D01*
X259192Y576021D01*
Y584400D01*
X259713Y584921D01*
Y586379D01*
X256792Y589300D01*
Y593071D01*
X257478Y593757D01*
G01X325875Y406172D02*
Y416917D01*
X310692Y432100D01*
Y454100D01*
X308853Y455939D01*
Y457071D01*
X309971Y458189D01*
Y459321D01*
X308840Y460452D01*
X307708D01*
X306590Y459334D01*
X305458D01*
X304292Y460500D01*
Y464500D01*
X303527Y465265D01*
Y466127D01*
X304058Y466658D01*
Y467520D01*
X302657Y468921D01*
X301795D01*
X301264Y468390D01*
X300402D01*
X299001Y469791D01*
Y470653D01*
X299532Y471184D01*
Y472046D01*
X298131Y473447D01*
X297269D01*
X296738Y472916D01*
X295876D01*
X294475Y474317D01*
Y475179D01*
X295006Y475710D01*
Y476572D01*
X293605Y477973D01*
X292743D01*
X292212Y477442D01*
X291350D01*
X289949Y478843D01*
Y479705D01*
X290480Y480236D01*
Y481098D01*
X289079Y482499D01*
X288217D01*
X287686Y481968D01*
X286824D01*
X285292Y483500D01*
X268393D01*
X262779Y489114D01*
Y494313D01*
X262213Y494879D01*
Y511257D01*
X263113Y512157D01*
Y516557D01*
X262313Y517357D01*
Y519300D01*
X262492Y519479D01*
Y527700D01*
X262313Y527879D01*
Y529842D01*
X263013Y530542D01*
Y535478D01*
X262213Y536278D01*
Y537700D01*
X262492Y537979D01*
Y546400D01*
X262213Y546679D01*
Y549057D01*
X263113Y549957D01*
Y554357D01*
X262013Y555457D01*
Y557400D01*
X262492Y557879D01*
Y565800D01*
X262313Y565979D01*
Y567597D01*
X262879Y568163D01*
Y573413D01*
X262213Y574079D01*
Y575600D01*
X262492Y575879D01*
Y584500D01*
X262213Y584779D01*
Y587368D01*
X262170D01*
X260824Y588714D01*
G01X240746Y593757D02*
X239041Y595462D01*
Y605949D01*
X243392Y610300D01*
G01Y588714D02*
X243304D01*
X241618Y590400D01*
Y592092D01*
X242525Y592999D01*
Y594592D01*
X241381Y595736D01*
Y597156D01*
X242225Y598000D01*
Y599700D01*
X241381Y600544D01*
Y601756D01*
X242325Y602700D01*
Y603900D01*
X241726Y604499D01*
X240746D01*
G01X264171Y593757D02*
X262466Y595462D01*
Y605649D01*
X267517Y610700D01*
G01Y588714D02*
X267429D01*
X265743Y590400D01*
Y592092D01*
X265918Y592267D01*
Y594900D01*
X264806Y596012D01*
Y597088D01*
X265818Y598100D01*
Y599300D01*
X264806Y600312D01*
Y601388D01*
X265943Y602525D01*
Y603799D01*
X265243Y604499D01*
X264171D01*
G01X234053Y593757D02*
X232348Y595462D01*
Y605635D01*
X237013Y610300D01*
G01X237099Y588714D02*
X237011D01*
X235325Y590400D01*
Y592600D01*
X235825Y593100D01*
Y594999D01*
X234688Y596136D01*
Y597464D01*
X235625Y598401D01*
Y599799D01*
X234688Y600736D01*
Y601964D01*
X235725Y603001D01*
Y603899D01*
X235125Y604499D01*
X234053D01*
G01X257478Y593757D02*
X255773Y595462D01*
Y605649D01*
X260824Y610700D01*
G01Y588714D02*
X260736D01*
X259050Y590400D01*
Y592092D01*
X259225Y592267D01*
Y594900D01*
X258113Y596012D01*
Y597088D01*
X259125Y598100D01*
Y599300D01*
X258113Y600312D01*
Y601388D01*
X259250Y602525D01*
Y603799D01*
X258550Y604499D01*
X257478D01*
G01X247213Y590900D02*
X248925Y592612D01*
Y594200D01*
X247825Y595300D01*
X246875D01*
X246285Y595890D01*
Y597260D01*
X246805Y597780D01*
X247415D01*
X248025Y598390D01*
Y599780D01*
X247415Y600390D01*
X246835D01*
X246285Y600940D01*
Y602360D01*
X246925Y603000D01*
X248205D01*
X248944Y603739D01*
Y605645D01*
X247239Y607350D01*
G01X284050D02*
X285797Y605603D01*
Y603487D01*
X284997Y602687D01*
X283717D01*
X283096Y602066D01*
Y600940D01*
X283646Y600390D01*
X284134D01*
X284757Y599767D01*
Y598377D01*
X284160Y597780D01*
X283616D01*
X283096Y597260D01*
Y595890D01*
X283686Y595300D01*
X284636D01*
X285736Y594200D01*
Y592612D01*
X284024Y590900D01*
G01X252313Y588514D02*
X252025D01*
X250608Y589931D01*
Y594900D01*
X249778Y595730D01*
Y602270D01*
X250608Y603100D01*
Y608044D01*
X252313Y609749D01*
G01X289124D02*
X287419Y608044D01*
Y602824D01*
X286589Y601994D01*
Y595730D01*
X287419Y594900D01*
Y589931D01*
X288836Y588514D01*
X289124D01*
G01X247213Y588300D02*
X246925D01*
X245225Y590000D01*
Y608011D01*
X247213Y609999D01*
G01X284024D02*
X282036Y608011D01*
Y590288D01*
X284024Y588300D01*
G01X252313Y591114D02*
X254025Y592826D01*
Y594500D01*
X253025Y595500D01*
X251509D01*
X250838Y596171D01*
Y597448D01*
X251290Y597900D01*
X251625D01*
X252325Y598600D01*
Y599688D01*
X251615Y600398D01*
X251378D01*
X250838Y600938D01*
Y601829D01*
X251609Y602600D01*
X253125D01*
X254125Y603600D01*
Y605328D01*
X252313Y607140D01*
G01X289124D02*
X290936Y605328D01*
Y603854D01*
X289682Y602600D01*
X288712D01*
X287718Y601606D01*
Y600898D01*
X288218Y600398D01*
X288426D01*
X289167Y599657D01*
Y598631D01*
X288436Y597900D01*
X288101D01*
X287649Y597448D01*
Y596171D01*
X288320Y595500D01*
X289836D01*
X290836Y594500D01*
Y592826D01*
X289124Y591114D01*
G01X280203Y610300D02*
X275852Y605949D01*
Y595462D01*
X277557Y593757D01*
G01Y604499D02*
X278537D01*
X279136Y603900D01*
Y602700D01*
X278192Y601756D01*
Y600544D01*
X279036Y599700D01*
Y598000D01*
X278192Y597156D01*
Y595736D01*
X279336Y594592D01*
Y592999D01*
X278429Y592092D01*
Y590488D01*
X280203Y588714D01*
G01X273824Y610300D02*
X269159Y605635D01*
Y595462D01*
X270864Y593757D01*
G01Y604499D02*
X271936D01*
X272536Y603899D01*
Y603001D01*
X271499Y601964D01*
Y600736D01*
X272436Y599799D01*
Y598401D01*
X271499Y597464D01*
Y596136D01*
X272636Y594999D01*
Y593100D01*
X272136Y592600D01*
Y590400D01*
X273822Y588714D01*
X273910D01*
G01X297635Y610700D02*
X292584Y605649D01*
Y595462D01*
X294289Y593757D01*
G01X304328Y49914D02*
X305717Y48525D01*
Y35512D01*
X306329Y34900D01*
Y33500D01*
X304529Y31700D01*
X303529D01*
X302229Y30400D01*
Y29146D01*
X300982Y27899D01*
G01X297635Y49914D02*
X299024Y48525D01*
Y35512D01*
X299636Y34900D01*
Y33500D01*
X297836Y31700D01*
X296836D01*
X295536Y30400D01*
Y29146D01*
X294289Y27899D01*
G01X331100Y28014D02*
X328384Y30730D01*
Y34140D01*
X329362Y35118D01*
Y52470D01*
X331100Y54208D01*
Y54857D01*
G01X334447D02*
X336092Y53212D01*
Y29660D01*
X334446Y28014D01*
G01X324407Y9114D02*
X326049Y10756D01*
Y19719D01*
X328992Y22662D01*
Y25400D01*
X329792Y26200D01*
X338492D01*
X339527Y27235D01*
Y30735D01*
X342879Y34087D01*
Y39623D01*
X341042Y41460D01*
Y43180D01*
X342862Y45000D01*
Y47870D01*
X347092Y52100D01*
X348812D01*
X349572Y52860D01*
Y56670D01*
X352892Y59990D01*
Y69804D01*
X356692Y73604D01*
Y79963D01*
X353144Y83511D01*
Y85739D01*
X352634Y86249D01*
Y88082D01*
X352935Y88383D01*
Y90658D01*
X352425Y91168D01*
Y100434D01*
X353418Y101427D01*
Y110024D01*
X354049Y110655D01*
X355857D01*
X356618Y109894D01*
Y104434D01*
X357418Y103634D01*
X359018D01*
X359818Y104434D01*
Y199064D01*
G01X324407Y-4536D02*
Y9114D01*
G01X300982Y17157D02*
X299736Y15911D01*
Y13699D01*
X302729Y10706D01*
Y-2101D01*
X304328Y-3700D01*
G01Y12114D02*
X305717Y10725D01*
Y-2288D01*
X306329Y-2900D01*
Y-4300D01*
X304529Y-6100D01*
X303529D01*
X302229Y-7400D01*
Y-8654D01*
X300982Y-9901D01*
G01X297635Y12114D02*
X299024Y10725D01*
Y-2288D01*
X299636Y-2900D01*
Y-4300D01*
X297836Y-6100D01*
X296836D01*
X295536Y-7400D01*
Y-8654D01*
X294289Y-9901D01*
G01X334446Y9114D02*
X337832Y12500D01*
X345792D01*
X346911Y13619D01*
X350543D01*
X352892Y15968D01*
Y29900D01*
X356638Y33646D01*
Y36447D01*
X363991Y43800D01*
X370548D01*
X373592Y46844D01*
Y50600D01*
X371792Y52400D01*
Y75096D01*
X370892Y75996D01*
Y79175D01*
X371792Y80075D01*
Y88500D01*
X372423Y89131D01*
Y96025D01*
X366079Y102369D01*
Y198554D01*
G01X334447Y-1743D02*
X334446Y-1742D01*
Y1854D01*
X335056Y2464D01*
X337290D01*
X337900Y3074D01*
Y4974D01*
X337290Y5584D01*
X335056D01*
X334446Y6194D01*
Y9114D01*
G01X331100Y17057D02*
X335988Y21945D01*
X340029D01*
X342792Y24708D01*
Y29120D01*
X346572Y32900D01*
X347492D01*
X349452Y34860D01*
Y48460D01*
X350692Y49700D01*
X351692D01*
X356332Y54340D01*
Y61540D01*
X361858Y67066D01*
Y73188D01*
X359026Y76020D01*
Y83034D01*
X359918Y83926D01*
Y96586D01*
X361818Y98486D01*
Y198627D01*
G01X331100Y-9786D02*
Y-7439D01*
X329250Y-5589D01*
Y-2942D01*
X329892Y-2300D01*
Y7600D01*
X329366Y8126D01*
Y10274D01*
X329992Y10900D01*
Y15949D01*
X331100Y17057D01*
G01X334447D02*
X336873Y19483D01*
X342000D01*
X349567Y27050D01*
Y31275D01*
X352892Y34600D01*
Y37890D01*
X359592Y44590D01*
Y47844D01*
X364848Y53100D01*
X368688D01*
X369792Y54204D01*
Y74251D01*
X368892Y75151D01*
Y80748D01*
X369792Y81648D01*
Y88941D01*
X370567Y89716D01*
Y93186D01*
X363868Y99893D01*
Y198651D01*
G01X334447Y-7108D02*
Y-5355D01*
X332592Y-3500D01*
Y7800D01*
X332811Y8019D01*
Y11287D01*
X332330Y11768D01*
Y13650D01*
X334447Y15767D01*
Y17057D01*
G01X324407Y84599D02*
Y87115D01*
X326292Y89000D01*
Y91200D01*
X325277Y92215D01*
Y96685D01*
X329342Y100750D01*
Y105800D01*
X325392Y109750D01*
Y117361D01*
X340988Y132957D01*
Y200519D01*
G01X324407Y73757D02*
X325727Y75077D01*
Y82193D01*
X324407Y83513D01*
Y84599D01*
G01X327092Y103021D02*
X324771Y100700D01*
X324276D01*
X317192Y93616D01*
Y92300D01*
X315692Y90800D01*
Y89200D01*
X316492Y88400D01*
Y86700D01*
X315826Y86034D01*
Y83766D01*
X316091Y83501D01*
Y72499D01*
X314368Y70776D01*
Y65814D01*
G01X344988Y199498D02*
Y131299D01*
X332092Y118403D01*
Y108899D01*
X334092Y106899D01*
Y97436D01*
X332392Y95736D01*
Y91800D01*
X333192Y91000D01*
Y88647D01*
X334447Y87392D01*
G01D02*
X333273Y86218D01*
Y74931D01*
X334447Y73757D01*
G01X331100Y89964D02*
X329992Y91072D01*
Y97300D01*
X331442Y98750D01*
Y106600D01*
X329792Y108250D01*
Y118932D01*
X342988Y132128D01*
Y199608D01*
G01X331100Y65814D02*
Y68018D01*
X330321Y68797D01*
X327224D01*
X326614Y69407D01*
Y70797D01*
X327224Y71407D01*
X328778D01*
X329388Y72017D01*
Y80951D01*
X328822Y81517D01*
Y85348D01*
X331100Y87626D01*
Y89964D01*
G01X334447Y92757D02*
Y94369D01*
X336092Y96014D01*
Y104200D01*
X336792Y104900D01*
Y106880D01*
X334192Y109480D01*
Y110987D01*
X334992Y111787D01*
X339066D01*
X339868Y112589D01*
Y114771D01*
X339070Y115569D01*
X334992D01*
X334192Y116369D01*
Y117674D01*
X346988Y130470D01*
Y199062D01*
G01X334446Y65814D02*
X336174Y67542D01*
Y83618D01*
X335992Y83800D01*
Y86100D01*
X336358Y86466D01*
Y88434D01*
X335792Y89000D01*
Y91412D01*
X334447Y92757D01*
G01X324407Y46914D02*
Y35957D01*
G01X350188Y199305D02*
Y128596D01*
X342492Y120900D01*
Y111101D01*
X341692Y110301D01*
X341192D01*
X340392Y109501D01*
Y107901D01*
X341192Y107101D01*
X341692D01*
X342492Y106301D01*
Y104900D01*
X339492Y101900D01*
Y93600D01*
X338992Y93100D01*
Y91800D01*
X339892Y90900D01*
Y88900D01*
X339292Y88300D01*
Y86400D01*
X339892Y85800D01*
Y75700D01*
X339407Y75215D01*
Y72485D01*
X339892Y72000D01*
Y67316D01*
X339513Y66937D01*
Y64605D01*
X338409Y63501D01*
X329240D01*
X326543Y60804D01*
Y56751D01*
X326042Y56250D01*
Y50850D01*
X324407Y49215D01*
Y46914D01*
G01X300982Y109700D02*
Y105410D01*
X302966Y103426D01*
Y91874D01*
X302466Y91374D01*
Y86374D01*
X303066Y85774D01*
Y84000D01*
X302392Y83326D01*
Y75300D01*
X303066Y74626D01*
Y73275D01*
X302266Y72475D01*
Y67259D01*
X303466Y66059D01*
Y57441D01*
X300982Y54957D01*
G01D02*
X299736Y53711D01*
Y51499D01*
X302729Y48506D01*
Y35699D01*
X304328Y34100D01*
G01X304178Y107684D02*
X306266Y105596D01*
Y103774D01*
X305566Y103074D01*
Y91674D01*
X306266Y90974D01*
Y75859D01*
X305566Y75159D01*
Y73227D01*
X306166Y72627D01*
Y65374D01*
X305875Y65083D01*
Y56783D01*
X302492Y53400D01*
Y51750D01*
X304328Y49914D01*
G01X294289Y54957D02*
X296266Y56934D01*
Y66309D01*
X295466Y67109D01*
Y72175D01*
X296166Y72875D01*
Y74800D01*
X295592Y75374D01*
Y83400D01*
X296166Y83974D01*
Y86074D01*
X295466Y86774D01*
Y91074D01*
X296566Y92174D01*
Y103127D01*
X295666Y104027D01*
Y110150D01*
X294889Y110927D01*
G01X297635Y105084D02*
X299066Y103653D01*
Y91712D01*
X299766Y91012D01*
Y86674D01*
X299166Y86074D01*
Y83926D01*
X299492Y83600D01*
Y75600D01*
X299166Y75274D01*
Y72659D01*
X299666Y72159D01*
Y67059D01*
X298466Y65859D01*
Y55857D01*
X295930Y53321D01*
Y51619D01*
X297635Y49914D01*
G01X334446Y46914D02*
X333274Y45742D01*
Y39718D01*
X334447Y38545D01*
Y35957D01*
G01X354188Y200166D02*
Y126936D01*
X346531Y119279D01*
Y94000D01*
X345992Y93461D01*
Y91400D01*
X346292Y91100D01*
Y88900D01*
X346033Y88641D01*
Y85759D01*
X346292Y85500D01*
Y84000D01*
X346192Y83900D01*
Y72400D01*
X346492Y72100D01*
Y70100D01*
X346106Y69714D01*
Y64114D01*
X341292Y59300D01*
X334592D01*
X332742Y57450D01*
Y52300D01*
X331745Y51303D01*
Y49615D01*
X334446Y46914D01*
G01X331100Y54857D02*
Y58908D01*
X333436Y61244D01*
X339577D01*
X342853Y64520D01*
Y69639D01*
X342686Y69806D01*
Y72594D01*
X342853Y72761D01*
Y74739D01*
X342192Y75400D01*
Y85600D01*
X342940Y86348D01*
Y88652D01*
X342680Y88912D01*
Y91088D01*
X342940Y91348D01*
Y101848D01*
X344531Y103439D01*
Y120109D01*
X352188Y127766D01*
Y199802D01*
G01X356188Y200081D02*
Y124806D01*
X353658Y122276D01*
Y121144D01*
X356618Y118184D01*
Y117052D01*
X355487Y115921D01*
X354355D01*
X351250Y119026D01*
X350118D01*
X348686Y117594D01*
Y116506D01*
X351142Y114050D01*
Y112950D01*
X350218Y112026D01*
Y102626D01*
X348975Y101383D01*
Y94317D01*
X349692Y93600D01*
Y91500D01*
X349292Y91100D01*
Y89000D01*
X349692Y88600D01*
Y85800D01*
X349292Y85400D01*
Y83800D01*
X349446Y83646D01*
Y72654D01*
X349192Y72400D01*
Y69900D01*
X349553Y69539D01*
Y63881D01*
X348692Y63020D01*
Y59334D01*
X346428Y57070D01*
X336560D01*
X334447Y54957D01*
Y54857D01*
G01X341892Y396301D02*
X344354Y398763D01*
Y475598D01*
X330892Y489060D01*
Y503800D01*
X327087Y507605D01*
X327092Y507617D01*
Y512130D01*
X327754Y512792D01*
G01X342353Y401161D02*
Y402186D01*
X342354Y402187D01*
Y475304D01*
X328892Y488766D01*
Y503383D01*
X327787Y504488D01*
X326872D01*
X325959Y503575D01*
X325114D01*
X324413Y504276D01*
Y505155D01*
X325362Y506104D01*
Y506966D01*
X324407Y507921D01*
Y509999D01*
G01X348354Y396007D02*
Y397762D01*
X349892Y399300D01*
Y400600D01*
X348354Y402138D01*
Y476840D01*
X334892Y490302D01*
Y508000D01*
X333592Y509300D01*
Y511937D01*
X334447Y512792D01*
G01X346354Y395968D02*
Y476122D01*
X332892Y489584D01*
Y505800D01*
X329192Y509500D01*
Y511200D01*
X331100Y513108D01*
Y515364D01*
G01X351192Y402800D02*
X351092Y402900D01*
Y478450D01*
X350059Y479483D01*
Y481362D01*
X351092Y482395D01*
Y483951D01*
X350060Y484983D01*
X348811D01*
X346313Y482485D01*
X345063D01*
X343932Y483616D01*
Y484630D01*
X347123Y487821D01*
Y488806D01*
X345992Y489937D01*
X344713D01*
X341878Y487102D01*
X340713D01*
X339582Y488233D01*
Y489332D01*
X342463Y492213D01*
Y493487D01*
X341332Y494618D01*
X340232D01*
X339101Y493487D01*
X338309D01*
X337141Y494655D01*
Y495943D01*
X340032Y498834D01*
Y505160D01*
X335692Y509500D01*
Y511000D01*
X336292Y511600D01*
Y513900D01*
X335792Y514400D01*
Y516812D01*
X334447Y518157D01*
G01X353554Y407821D02*
Y485738D01*
X342392Y496900D01*
Y505300D01*
X339692Y508000D01*
Y511100D01*
X339292Y511500D01*
Y513900D01*
X339892Y514500D01*
Y516400D01*
X338992Y517300D01*
Y518700D01*
X339521Y519229D01*
Y529871D01*
X337141Y532251D01*
Y534393D01*
X336113Y535421D01*
Y537753D01*
X334566Y539300D01*
X333021D01*
X324407Y547914D01*
G01X357554Y407727D02*
Y488238D01*
X350364Y495428D01*
Y496560D01*
X351634Y497830D01*
Y499059D01*
X350503Y500190D01*
X349468D01*
X348266Y498988D01*
X347018D01*
X346192Y499814D01*
Y502973D01*
X346802Y503583D01*
X348299D01*
X348870Y504154D01*
Y505544D01*
X348221Y506193D01*
X346802D01*
X346192Y506803D01*
Y508800D01*
X346792Y509400D01*
Y510800D01*
X345929Y511663D01*
Y513837D01*
X346490Y514398D01*
Y516502D01*
X346104Y516888D01*
Y530388D01*
X345292Y531200D01*
Y532200D01*
X342851Y534641D01*
Y539509D01*
X334446Y547914D01*
G01X355554Y407821D02*
Y487138D01*
X344392Y498300D01*
Y507000D01*
X342592Y508800D01*
Y511200D01*
X343092Y511700D01*
Y513900D01*
X342592Y514400D01*
Y516600D01*
X342992Y517000D01*
Y519400D01*
X342792Y519600D01*
Y531808D01*
X340392Y534208D01*
Y534600D01*
X339418Y535574D01*
Y538666D01*
X334748Y543336D01*
X332888D01*
X329383Y546841D01*
Y554140D01*
X331100Y555857D01*
G01X359554Y407781D02*
Y489438D01*
X353668Y495324D01*
Y504558D01*
X349061Y509165D01*
Y511169D01*
X349792Y511900D01*
Y513900D01*
X349292Y514400D01*
Y516400D01*
X349692Y516800D01*
Y522284D01*
X350296Y522888D01*
X351600D01*
X352167Y523455D01*
Y524845D01*
X351514Y525498D01*
X350152D01*
X349542Y526108D01*
Y533050D01*
X349454Y533138D01*
Y541718D01*
X346191Y544981D01*
Y552968D01*
X345149Y554010D01*
X342549D01*
X341939Y553400D01*
Y552337D01*
X341308Y551706D01*
X339918D01*
X339329Y552295D01*
Y553400D01*
X338719Y554010D01*
X336294D01*
X334447Y555857D01*
G01X359392Y401500D02*
X362754Y404862D01*
Y490809D01*
X356692Y496871D01*
Y506839D01*
X352443Y511088D01*
Y513679D01*
X353277Y514513D01*
Y516681D01*
X352674Y517284D01*
Y520208D01*
X356692Y524226D01*
Y527100D01*
X356152Y527640D01*
Y530360D01*
X355594Y530918D01*
Y535606D01*
X356154Y536166D01*
Y541073D01*
X352891Y544336D01*
Y551069D01*
X349541Y554419D01*
Y557151D01*
X346104Y560588D01*
Y568188D01*
X344992Y569300D01*
X343892D01*
X339433Y573759D01*
Y576086D01*
X338519Y577000D01*
X333192D01*
X332192Y578000D01*
Y581276D01*
X327754Y585714D01*
G01X360967Y400225D02*
X364754Y404012D01*
Y501144D01*
X356478Y509420D01*
Y520754D01*
X358692Y522968D01*
Y526800D01*
X359892Y528000D01*
Y530313D01*
X360692Y531113D01*
X362492D01*
X363508Y532129D01*
Y533709D01*
X362696Y534521D01*
X361396D01*
X359615Y536302D01*
Y559162D01*
X356202Y562575D01*
X355340D01*
X354253Y561488D01*
X353391D01*
X352407Y562472D01*
Y563334D01*
X353494Y564421D01*
Y565283D01*
X352818Y565959D01*
Y568283D01*
X349301Y571800D01*
X347920D01*
X346133Y573587D01*
Y576232D01*
X342626Y579739D01*
X338266D01*
X337255Y580750D01*
Y582114D01*
X338080Y582939D01*
X341654D01*
X342871Y584156D01*
Y586487D01*
X341622Y587736D01*
X332792D01*
X331100Y589428D01*
Y593657D01*
G01X327754Y512792D02*
Y515038D01*
X325692Y517100D01*
Y519100D01*
X326048Y519456D01*
Y532678D01*
X327754Y534384D01*
Y536957D01*
G01X324407Y509999D02*
Y512485D01*
X322592Y514300D01*
Y516600D01*
X322892Y516900D01*
Y519300D01*
X322692Y519500D01*
Y530300D01*
X323392Y531000D01*
Y533249D01*
X324407Y534264D01*
Y536957D01*
G01X326922Y497170D02*
X323822D01*
X320598Y500394D01*
Y509866D01*
X319216Y511248D01*
Y513599D01*
X319540Y513923D01*
Y516890D01*
X316292Y520138D01*
Y524300D01*
X312752Y527840D01*
Y535226D01*
X311021Y536957D01*
G01X334447Y512792D02*
X333492Y513747D01*
Y515900D01*
X332441Y516951D01*
Y519049D01*
X332792Y519400D01*
Y530402D01*
X331930Y531264D01*
X329725D01*
X329115Y531874D01*
Y532864D01*
X329725Y533474D01*
X331742D01*
X332540Y534272D01*
Y535050D01*
X334447Y536957D01*
G01X331100Y515364D02*
X330737Y515727D01*
Y528651D01*
X331100Y529014D01*
G01X334447Y518157D02*
Y529013D01*
X334446Y529014D01*
G01X301092Y493300D02*
X302692Y494900D01*
Y501901D01*
X302924Y502133D01*
Y511157D01*
X302424Y511657D01*
Y517057D01*
X303224Y517857D01*
Y529497D01*
X302124Y530597D01*
Y535342D01*
X303024Y536242D01*
Y537900D01*
X302592Y538332D01*
Y546100D01*
X303024Y546532D01*
Y548707D01*
X299624Y552107D01*
Y554599D01*
X300982Y555957D01*
G01X304392Y494700D02*
X306566Y496874D01*
Y509626D01*
X305724Y510468D01*
Y511657D01*
X306324Y512257D01*
Y516807D01*
X305774Y517357D01*
Y529847D01*
X306266Y530339D01*
Y535926D01*
X305624Y536568D01*
Y549670D01*
X304328Y550966D01*
Y550914D01*
G01X294392Y493100D02*
X296092Y494800D01*
Y502100D01*
X296524Y502532D01*
Y511257D01*
X295724Y512057D01*
Y516957D01*
X296324Y517557D01*
Y519400D01*
X295992Y519732D01*
Y527900D01*
X296324Y528232D01*
Y529597D01*
X295251Y530670D01*
Y535169D01*
X296524Y536442D01*
Y537700D01*
X295992Y538232D01*
Y546200D01*
X296524Y546732D01*
Y548557D01*
X293624Y551457D01*
Y555292D01*
X294289Y555957D01*
G01X297835Y494944D02*
X299892Y497001D01*
Y498700D01*
X298682Y499910D01*
Y502190D01*
X299024Y502532D01*
Y511257D01*
X299924Y512157D01*
Y516557D01*
X298824Y517657D01*
Y519100D01*
X299292Y519568D01*
Y527900D01*
X299124Y528068D01*
Y529797D01*
X299690Y530363D01*
Y535501D01*
X299024Y536167D01*
Y537700D01*
X299292Y537968D01*
Y546300D01*
X299024Y546568D01*
Y549568D01*
X298981D01*
X297635Y550914D01*
G01X324407Y547914D02*
Y552524D01*
X326034Y554151D01*
Y557622D01*
X326845Y558433D01*
Y563532D01*
X326034Y564343D01*
Y568058D01*
X324407Y569685D01*
Y574757D01*
G01X334446Y547914D02*
X332117Y550243D01*
Y554238D01*
X332792Y554913D01*
Y567700D01*
X332557Y567935D01*
Y572867D01*
X334447Y574757D01*
G01X331100Y555857D02*
Y566814D01*
G01X334447Y555857D02*
Y566813D01*
X334446Y566814D01*
G01X327754Y585714D02*
X326034Y587434D01*
Y595346D01*
X322492Y598888D01*
Y605130D01*
X323661Y606299D01*
X324015D01*
X327754Y610038D01*
Y612457D01*
G01X354525Y585722D02*
Y588194D01*
X352803Y589916D01*
Y602711D01*
X356329Y606237D01*
Y608263D01*
X354525Y610067D01*
Y612358D01*
G01X365667Y396325D02*
X370754Y401412D01*
Y499104D01*
X372893Y501243D01*
Y525102D01*
X373792Y526001D01*
Y548900D01*
X375592Y550700D01*
Y574300D01*
X367270Y582622D01*
X357625D01*
X354525Y585722D01*
G01X347833D02*
Y590841D01*
X346104Y592570D01*
Y595936D01*
X348592Y598424D01*
Y605000D01*
X349809Y606217D01*
Y608283D01*
X347833Y610259D01*
Y612357D01*
G01X364146Y397654D02*
X368754Y402262D01*
Y499933D01*
X370893Y502072D01*
Y526001D01*
X371792Y526900D01*
Y549300D01*
X373692Y551200D01*
Y557200D01*
X371792Y559100D01*
Y575822D01*
X366602Y581012D01*
X351937D01*
X347833Y585116D01*
Y585722D01*
G01X362292Y398700D02*
X366754Y403162D01*
Y506598D01*
X368861Y508705D01*
Y527168D01*
X369792Y528099D01*
Y549700D01*
X371992Y551900D01*
Y556500D01*
X369792Y558700D01*
Y575267D01*
X368283Y576776D01*
X351302D01*
X346149Y581929D01*
Y587043D01*
X344592Y588600D01*
X343592D01*
X340371Y591821D01*
X336283D01*
X334447Y593657D01*
G01X304328Y610700D02*
X299277Y605649D01*
Y595462D01*
X300982Y593757D01*
G01Y604499D02*
X302054D01*
X302754Y603799D01*
Y602525D01*
X301617Y601388D01*
Y600312D01*
X302629Y599300D01*
Y598100D01*
X301617Y597088D01*
Y596012D01*
X302729Y594900D01*
Y592267D01*
X302554Y592092D01*
Y590400D01*
X304240Y588714D01*
X304328D01*
G01X294289Y604499D02*
X295361D01*
X296061Y603799D01*
Y602525D01*
X294924Y601388D01*
Y600312D01*
X295936Y599300D01*
Y598100D01*
X294924Y597088D01*
Y596012D01*
X296036Y594900D01*
Y592267D01*
X295861Y592092D01*
Y590400D01*
X297547Y588714D01*
X297635D01*
G01X331100Y593657D02*
Y597693D01*
X330552Y598241D01*
X328322D01*
X327662Y598901D01*
Y600961D01*
X328447Y601746D01*
X330274D01*
X331100Y602572D01*
Y604614D01*
G01X334447Y593657D02*
Y607292D01*
G01X401375Y-1743D02*
X401377Y-1741D01*
Y773D01*
X400767Y1383D01*
X398599D01*
X397962Y2020D01*
Y3920D01*
X398545Y4503D01*
X400767D01*
X401377Y5113D01*
Y9122D01*
G01X368118Y198724D02*
Y103159D01*
X374533Y96744D01*
Y88583D01*
X373632Y87682D01*
Y82678D01*
X376092Y80218D01*
Y44700D01*
X382367Y38425D01*
Y29124D01*
X386324Y25167D01*
X394495D01*
X399637Y20025D01*
Y15155D01*
X400667Y14125D01*
Y12500D01*
X401377Y11790D01*
Y9122D01*
G01D02*
X401376Y9121D01*
G01X404722Y-4536D02*
X404723Y-4535D01*
Y9122D01*
G01X370118Y198554D02*
Y105302D01*
X377392Y98028D01*
Y85200D01*
X378092Y84500D01*
Y72700D01*
X378892Y71900D01*
Y55050D01*
X383692Y50250D01*
Y45400D01*
X387819Y41273D01*
X388681D01*
X390522Y43114D01*
X391284D01*
X392756Y41642D01*
Y40934D01*
X390888Y39066D01*
Y38204D01*
X392542Y36550D01*
Y30134D01*
X403088Y19588D01*
Y15996D01*
X402692Y15600D01*
Y13400D01*
X404723Y11369D01*
Y9122D01*
G01D02*
X404722Y9121D01*
G01X386518Y195037D02*
Y127751D01*
X402505Y111764D01*
X407541D01*
X412192Y107113D01*
Y92300D01*
X413292Y91200D01*
Y89100D01*
X410592Y86400D01*
X410554D01*
X409492Y85338D01*
Y75300D01*
X409782Y75010D01*
Y71684D01*
X410251Y71215D01*
Y68113D01*
X409805Y67667D01*
Y64487D01*
X413163Y61129D01*
Y56478D01*
X413125Y56440D01*
Y46033D01*
X412492Y45400D01*
Y38418D01*
X413147Y37763D01*
Y34645D01*
X416392Y31400D01*
Y27058D01*
X423128Y20322D01*
Y15502D01*
X428147Y10483D01*
Y9120D01*
G01X384518Y194697D02*
Y127598D01*
X386292Y125824D01*
Y124962D01*
X385296Y123966D01*
Y123104D01*
X386641Y121759D01*
X387503D01*
X388499Y122755D01*
X389361D01*
X390706Y121410D01*
Y120548D01*
X389710Y119552D01*
Y118690D01*
X391055Y117345D01*
X391917D01*
X392913Y118341D01*
X393775D01*
X402352Y109764D01*
X406712D01*
X410192Y106284D01*
Y92334D01*
X406192Y88334D01*
Y86500D01*
X407292Y85400D01*
Y75700D01*
X406357Y74765D01*
Y69765D01*
X406349Y69757D01*
Y59495D01*
X409689Y56155D01*
Y52830D01*
X410071Y52448D01*
Y49634D01*
X409808Y49371D01*
Y34416D01*
X413068Y31156D01*
Y29624D01*
X413062Y29618D01*
Y26991D01*
X421456Y18597D01*
Y17057D01*
G01X401375Y87392D02*
Y73759D01*
X401377Y73757D01*
G01X379318Y191223D02*
Y122274D01*
X395662Y105930D01*
Y104656D01*
X394801Y103795D01*
X393086D01*
X392256Y102965D01*
Y101365D01*
X393026Y100595D01*
X394892D01*
X395692Y99795D01*
Y95700D01*
X400292Y91100D01*
Y88475D01*
X401375Y87392D01*
G01X404722Y84599D02*
X404723Y84598D01*
Y83731D01*
X404147Y83155D01*
Y79699D01*
X404391Y79455D01*
Y74089D01*
X404723Y73757D01*
G01X381318Y190630D02*
Y123574D01*
X399292Y105600D01*
Y101556D01*
X402392Y98456D01*
Y94300D01*
X403192Y93500D01*
Y91600D01*
X402892Y91300D01*
Y89100D01*
X403192Y88800D01*
Y86129D01*
X404722Y84599D01*
G01X401377Y46922D02*
X398676Y44221D01*
Y38658D01*
X401377Y35957D01*
G01X374118Y197381D02*
Y120118D01*
X376319Y117917D01*
Y116785D01*
X375179Y115645D01*
Y114513D01*
X376310Y113382D01*
X377442D01*
X378582Y114522D01*
X379714D01*
X380592Y113644D01*
Y78600D01*
X383592Y75600D01*
Y74300D01*
X382292Y73000D01*
Y64886D01*
X386378Y60800D01*
X389692D01*
X392692Y57800D01*
Y54000D01*
X396392Y50300D01*
X400667D01*
X401375Y49592D01*
Y46924D01*
X401377Y46922D01*
G01X404723D02*
Y45385D01*
X406992Y43116D01*
Y38226D01*
X404723Y35957D01*
G01X376118Y196930D02*
Y120948D01*
X382692Y114374D01*
Y80872D01*
X384464Y79100D01*
X388300D01*
X389344Y78056D01*
X390206D01*
X390762Y78612D01*
X391624D01*
X392608Y77628D01*
Y76766D01*
X392052Y76210D01*
Y75348D01*
X392792Y74608D01*
Y65471D01*
X399661Y58602D01*
Y53931D01*
X401392Y52200D01*
X401892D01*
X404722Y49370D01*
Y46923D01*
X404723Y46922D01*
G01X392448Y191624D02*
Y132154D01*
X407638Y116964D01*
X409396D01*
X419292Y107068D01*
Y91500D01*
X419992Y90800D01*
Y89200D01*
X419592Y88800D01*
Y85800D01*
X419992Y85400D01*
Y82455D01*
X417142Y79605D01*
Y76716D01*
X416374Y75948D01*
Y70018D01*
X419820Y66572D01*
Y64196D01*
X426433Y57583D01*
Y53159D01*
X428147Y51445D01*
Y46924D01*
X428149Y46922D01*
G01X390448Y191575D02*
Y131325D01*
X393786Y127987D01*
Y126855D01*
X393125Y126194D01*
Y125143D01*
X394256Y124012D01*
X395469D01*
X396049Y124592D01*
X397181D01*
X398312Y123461D01*
Y122329D01*
X397572Y121589D01*
Y120477D01*
X398703Y119346D01*
X399855D01*
X400575Y120066D01*
X401707D01*
X402838Y118935D01*
Y117803D01*
X402167Y117132D01*
Y115954D01*
X403157Y114964D01*
X408567D01*
X416792Y106739D01*
Y92200D01*
X416292Y91700D01*
Y88800D01*
X416692Y88400D01*
Y86200D01*
X413056Y82564D01*
Y72436D01*
X413492Y72000D01*
Y70031D01*
X416374Y67149D01*
Y64243D01*
X421456Y59161D01*
Y54857D01*
G01X408198Y191151D02*
Y140928D01*
X440015Y109111D01*
Y107902D01*
X439355Y107242D01*
X437647D01*
X437031Y106626D01*
Y104674D01*
X437724Y103981D01*
X439323D01*
X439992Y103312D01*
Y95754D01*
X438921Y94683D01*
Y91871D01*
X440450Y90342D01*
Y89458D01*
X439692Y88700D01*
Y87599D01*
X438792Y86699D01*
Y85319D01*
X438187Y84714D01*
G01X397648Y190969D02*
Y136768D01*
X425754Y108662D01*
Y102438D01*
X426492Y101700D01*
Y93700D01*
X426069Y93277D01*
Y91823D01*
X427792Y90100D01*
Y88400D01*
X428147Y88045D01*
Y87392D01*
G01X395648Y191381D02*
Y134198D01*
X396448Y133398D01*
X398189D01*
X398844Y132743D01*
Y130285D01*
X399913Y129216D01*
X402371D01*
X403370Y128217D01*
Y125759D01*
X404439Y124690D01*
X406897D01*
X407962Y123625D01*
Y121167D01*
X408965Y120164D01*
X411423D01*
X423754Y107833D01*
Y102061D01*
X421654Y99961D01*
Y98245D01*
X422264Y97635D01*
X423006D01*
X423634Y97007D01*
Y96017D01*
X423042Y95425D01*
X422064D01*
X421454Y94815D01*
Y92757D01*
G01X406198Y190981D02*
Y140099D01*
X434892Y111405D01*
Y103500D01*
X436492Y101900D01*
Y93900D01*
X436692Y93700D01*
Y91300D01*
X436292Y90900D01*
Y89500D01*
X434840Y88048D01*
Y87392D01*
G01X402898Y191500D02*
Y138873D01*
X431692Y110079D01*
Y102800D01*
X433292Y101200D01*
Y94100D01*
X432792Y93600D01*
Y91700D01*
X433392Y91100D01*
Y89300D01*
X432592Y88500D01*
Y86200D01*
X433392Y85400D01*
Y83700D01*
X432792Y83100D01*
Y76650D01*
X433216Y76226D01*
Y72425D01*
X431761Y70970D01*
Y68229D01*
X433216Y66774D01*
Y64495D01*
X436557Y61154D01*
Y53865D01*
X436128Y53436D01*
Y51564D01*
X438187Y49505D01*
Y46924D01*
X438189Y46922D01*
G01X434842D02*
X431646Y50118D01*
Y52015D01*
X433106Y53475D01*
Y60527D01*
X429769Y63864D01*
Y75475D01*
X430092Y75798D01*
Y83300D01*
X429692Y83700D01*
Y85800D01*
X430192Y86300D01*
Y88700D01*
X429675Y89217D01*
Y91283D01*
X430042Y91650D01*
Y93500D01*
X429692Y93850D01*
Y109188D01*
X400898Y137982D01*
Y191694D01*
G01X407706Y236409D02*
X405148Y233851D01*
Y208945D01*
X409292Y204801D01*
Y199400D01*
X413454Y195238D01*
Y141638D01*
X445875Y109217D01*
G01Y106583D02*
X445192Y105900D01*
Y103700D01*
X446680Y102212D01*
Y85612D01*
X446692Y85600D01*
Y37300D01*
X446500Y37108D01*
Y32208D01*
X443268Y28976D01*
Y27243D01*
X442295Y26270D01*
Y23345D01*
X444096Y21544D01*
Y19644D01*
X443499Y19047D01*
X440974D01*
X439792Y17865D01*
Y12770D01*
X438187Y11165D01*
Y9124D01*
G01X434840Y9120D02*
X434842Y9122D01*
X434840Y9124D01*
Y10942D01*
X436556Y12658D01*
Y29116D01*
X438893Y31453D01*
X439575D01*
X443252Y35130D01*
Y37140D01*
X442592Y37800D01*
Y43138D01*
X443243Y43789D01*
Y55949D01*
X442692Y56500D01*
Y61156D01*
X443272Y61736D01*
Y74620D01*
X442992Y74900D01*
Y86200D01*
X443392Y86600D01*
Y88600D01*
X442992Y89000D01*
Y91000D01*
X443392Y91400D01*
Y93400D01*
X443192Y93600D01*
Y109536D01*
X411404Y141324D01*
Y194243D01*
X407168Y198479D01*
Y203921D01*
X402671Y208418D01*
Y235365D01*
X399676Y238360D01*
G01X383154Y411204D02*
Y483891D01*
X401375Y502112D01*
Y512792D01*
G01X411392Y401633D02*
Y469928D01*
X439992Y498528D01*
Y508309D01*
X438187Y510114D01*
G01X385154Y411284D02*
Y483062D01*
X404722Y502630D01*
Y509999D01*
G01X393592Y393500D02*
Y396200D01*
X396192Y398800D01*
Y403101D01*
X400842Y407751D01*
Y476584D01*
X425939Y501681D01*
Y503363D01*
X425250Y504052D01*
X423536D01*
X422852Y504736D01*
Y506568D01*
X423536Y507252D01*
X425254D01*
X428147Y510145D01*
Y512792D01*
G01X392592Y393800D02*
Y397642D01*
X394292Y399342D01*
Y404100D01*
X398842Y408650D01*
Y477413D01*
X420666Y499237D01*
Y509374D01*
X423204Y511912D01*
Y513988D01*
X421454Y515738D01*
Y518157D01*
G01X409392Y401553D02*
Y470757D01*
X411927Y473292D01*
Y475133D01*
X413270Y476476D01*
X413980Y476475D01*
X415110D01*
X416453Y477818D01*
Y479659D01*
X417796Y481002D01*
X418506Y481001D01*
X419636D01*
X420979Y482344D01*
Y483763D01*
X422743Y485527D01*
X424162D01*
X425505Y486870D01*
Y488711D01*
X426848Y490054D01*
X427558Y490053D01*
X428688D01*
X430031Y491396D01*
Y493425D01*
X432206Y495600D01*
X434235D01*
X437088Y498453D01*
Y505156D01*
X436292Y505952D01*
Y511340D01*
X434840Y512792D01*
G01X377954Y410841D02*
Y495262D01*
X381692Y499000D01*
Y535200D01*
X388239Y541747D01*
X390234D01*
X391419Y542932D01*
Y544597D01*
X392539Y545717D01*
X399171D01*
X401376Y547922D01*
G01X398092Y391600D02*
Y393900D01*
X402692Y398500D01*
X403592D01*
X404692Y399600D01*
Y403400D01*
X406092Y404800D01*
Y474369D01*
X429406Y497683D01*
Y497684D01*
X433392Y501670D01*
Y510900D01*
X432964Y511328D01*
Y513872D01*
X433391Y514299D01*
Y516101D01*
X433032Y516460D01*
Y519040D01*
X433214Y519222D01*
Y530278D01*
X431788Y531704D01*
Y534224D01*
X433228Y535664D01*
Y541211D01*
X438189Y546172D01*
Y547922D01*
G01X379954Y410706D02*
Y494062D01*
X390546Y504654D01*
Y505754D01*
X396792Y512000D01*
Y513600D01*
X396307Y514085D01*
Y532454D01*
X399737Y535884D01*
Y542936D01*
X404723Y547922D01*
G01X382777Y380709D02*
X383892Y381824D01*
Y383100D01*
X384592Y383800D01*
Y385400D01*
X384292Y385700D01*
Y387400D01*
X384792Y387900D01*
Y389200D01*
X388192Y392600D01*
Y394600D01*
X389792Y396200D01*
Y403500D01*
X395554Y409262D01*
Y478651D01*
X416692Y499789D01*
Y508500D01*
X416092Y509100D01*
Y511200D01*
X416692Y511800D01*
Y513900D01*
X416192Y514400D01*
Y516600D01*
X417449Y517857D01*
Y520543D01*
X416376Y521616D01*
Y529884D01*
X418873Y532381D01*
Y534567D01*
X419843Y535537D01*
Y538626D01*
X420835Y539618D01*
X422928D01*
X423497Y540187D01*
Y541577D01*
X422846Y542228D01*
X420453D01*
X419843Y542838D01*
Y544029D01*
X421592Y545778D01*
X426005D01*
X428149Y547922D01*
G01X379397Y378760D02*
Y380004D01*
X381292Y381899D01*
Y383400D01*
X380892Y383800D01*
Y385500D01*
X381426Y386034D01*
Y387166D01*
X380892Y387700D01*
Y389300D01*
X382192Y390600D01*
Y391300D01*
X387992Y397100D01*
Y404300D01*
X393554Y409862D01*
Y479481D01*
X412692Y498619D01*
Y508700D01*
X413392Y509400D01*
Y511200D01*
X412892Y511700D01*
Y513900D01*
X413292Y514300D01*
Y516600D01*
X412892Y517000D01*
Y527100D01*
X413100Y527308D01*
Y532208D01*
X416390Y535498D01*
Y543558D01*
X419829Y546997D01*
Y549263D01*
X419392Y549700D01*
Y553793D01*
X421456Y555857D01*
G01X396092Y392507D02*
Y394700D01*
X401092Y399700D01*
Y402600D01*
X404092Y405600D01*
Y475199D01*
X430492Y501599D01*
Y508300D01*
X429777Y509015D01*
Y510885D01*
X430398Y511506D01*
Y513894D01*
X429692Y514600D01*
Y516700D01*
X429992Y517000D01*
Y522629D01*
X430695Y523332D01*
Y526822D01*
X429761Y527756D01*
Y542841D01*
X434842Y547922D01*
G01X367042Y394850D02*
X372754Y400562D01*
Y498275D01*
X377292Y502813D01*
Y535600D01*
X380092Y538400D01*
Y574612D01*
X385763Y580283D01*
X395938D01*
X401377Y585722D01*
G01X416593Y401566D02*
Y467701D01*
X446892Y498000D01*
Y510800D01*
X445892Y511800D01*
Y513800D01*
X446892Y514800D01*
Y517600D01*
X446485Y518007D01*
Y531205D01*
X446592Y531312D01*
Y538300D01*
X446892Y538600D01*
Y548500D01*
X446366Y549026D01*
Y551774D01*
X446671Y552079D01*
Y556979D01*
X446992Y557300D01*
Y567300D01*
X446509Y567783D01*
Y577402D01*
X438189Y585722D01*
G01X369693Y394600D02*
X374754Y399661D01*
Y496862D01*
X379592Y501700D01*
Y535400D01*
X381792Y537600D01*
Y573600D01*
X385992Y577800D01*
X397761D01*
X404723Y584762D01*
Y585722D01*
G01X382476Y394284D02*
X386192Y398000D01*
Y405000D01*
X390354Y409162D01*
Y480807D01*
X409492Y499945D01*
Y511500D01*
X410092Y512100D01*
Y513900D01*
X409492Y514500D01*
Y516300D01*
X409780Y516588D01*
Y530488D01*
X409992Y530700D01*
Y535474D01*
X409779Y535687D01*
Y543387D01*
X413100Y546708D01*
Y551608D01*
X416375Y554883D01*
Y569620D01*
X419505Y572750D01*
X421870D01*
X423090Y573970D01*
Y576047D01*
X421213Y577924D01*
Y579164D01*
X422819Y580770D01*
X424176D01*
X426110Y578836D01*
X427281D01*
X428752Y580307D01*
Y581481D01*
X426958Y583275D01*
Y584531D01*
X428149Y585722D01*
G01X379530Y394761D02*
X384642Y399873D01*
Y406150D01*
X388354Y409862D01*
Y481636D01*
X406892Y500174D01*
Y511000D01*
X406092Y511800D01*
Y513900D01*
X406692Y514500D01*
Y516300D01*
X406092Y516900D01*
Y518900D01*
X406341Y519149D01*
Y538749D01*
X407092Y539500D01*
Y543440D01*
X409809Y546157D01*
Y549017D01*
X409992Y549200D01*
Y551600D01*
X413158Y554766D01*
Y568034D01*
X412792Y568400D01*
Y570100D01*
X416391Y573699D01*
Y588592D01*
X421456Y593657D01*
G01X414593Y402640D02*
Y468602D01*
X443211Y497220D01*
Y508879D01*
X442892Y509198D01*
Y511400D01*
X443692Y512200D01*
Y513600D01*
X442992Y514300D01*
Y516400D01*
X443692Y517100D01*
Y518900D01*
X443263Y519329D01*
Y530371D01*
X443692Y530800D01*
Y532500D01*
X442992Y533200D01*
Y535600D01*
X443247Y535855D01*
Y570345D01*
X439810Y573782D01*
Y580754D01*
X434842Y585722D01*
G01X401375Y512792D02*
Y514817D01*
X398184Y518008D01*
Y521589D01*
X398797Y522202D01*
X400616D01*
X401212Y522798D01*
Y523788D01*
X400588Y524412D01*
X399257D01*
X398647Y525022D01*
Y526905D01*
X399759Y528017D01*
Y530433D01*
X399492Y530700D01*
Y532700D01*
X401376Y534584D01*
Y536956D01*
X401377Y536957D01*
G01X404722Y509999D02*
X403492Y511229D01*
Y513600D01*
X402998Y514094D01*
Y516706D01*
X403257Y516965D01*
Y519235D01*
X403020Y519472D01*
Y530428D01*
X403492Y530900D01*
Y533034D01*
X404722Y534264D01*
Y536956D01*
X404723Y536957D01*
G01X401376Y547922D02*
Y550634D01*
X399656Y552354D01*
Y561246D01*
X399745Y561335D01*
Y568628D01*
X401377Y570260D01*
Y574757D01*
G01X404723Y547922D02*
Y550834D01*
X403109Y552448D01*
Y567940D01*
X404723Y569554D01*
Y574757D01*
G01X401377Y585722D02*
Y590982D01*
X399643Y592716D01*
Y595051D01*
X399973Y595381D01*
Y605547D01*
X399497Y606023D01*
Y608337D01*
X401376Y610216D01*
Y612658D01*
G01X404723Y585722D02*
X406392Y587391D01*
Y600240D01*
X406777Y600625D01*
Y605547D01*
X404722Y607602D01*
Y609864D01*
G01X421456Y593657D02*
X421454Y593659D01*
Y596531D01*
X420420Y597565D01*
X415677D01*
X414834Y598408D01*
Y599892D01*
X415707Y600765D01*
X421728D01*
X422786Y601823D01*
Y605960D01*
X421454Y607292D01*
G01X421456Y54857D02*
X419368Y52769D01*
Y49651D01*
X419826Y49193D01*
Y33966D01*
X419405Y33545D01*
Y30073D01*
X421456Y28022D01*
G01X438187Y-4536D02*
X438189Y-4534D01*
Y9122D01*
X438187Y9124D01*
G01D02*
Y9120D01*
G01X458266Y17157D02*
X457145Y16036D01*
Y13100D01*
X460045Y10200D01*
Y8232D01*
X458512Y6699D01*
Y5500D01*
X459762Y4250D01*
Y3350D01*
X458412Y2000D01*
Y701D01*
X460045Y-932D01*
Y-3233D01*
X460912Y-4100D01*
G01X424957Y188577D02*
X424519Y188139D01*
Y152992D01*
X443320Y134185D01*
Y133054D01*
X442345Y132079D01*
Y130949D01*
X443478Y129816D01*
X444607D01*
X445583Y130792D01*
X446713D01*
X447846Y129659D01*
Y128528D01*
X445644Y126326D01*
Y125196D01*
X446777Y124063D01*
X447906D01*
X450109Y126266D01*
X451239D01*
X452372Y125133D01*
Y124002D01*
X451127Y122757D01*
Y121965D01*
X452598Y120494D01*
X453390D01*
X454636Y121740D01*
X455765D01*
X456892Y120613D01*
Y105500D01*
X460166Y102226D01*
Y92024D01*
X459066Y90924D01*
Y86574D01*
X459992Y85648D01*
Y83700D01*
X459767Y83475D01*
Y75566D01*
X460066Y75267D01*
Y73174D01*
X458983Y72091D01*
Y67409D01*
X460333Y66059D01*
Y54542D01*
X458983Y53192D01*
Y48914D01*
X459992Y47905D01*
Y46059D01*
X459592Y45659D01*
Y37800D01*
X460092Y37300D01*
Y35300D01*
X458983Y34191D01*
Y29609D01*
X460133Y28459D01*
Y26041D01*
X458266Y24174D01*
Y17157D01*
G01X460912Y12114D02*
X462385Y10641D01*
Y-2484D01*
X463001Y-3100D01*
Y-4444D01*
X461545Y-5900D01*
X460145D01*
X458266Y-7779D01*
Y-9901D01*
G01X427457Y188577D02*
Y153584D01*
X459392Y121649D01*
Y120718D01*
X460192Y119918D01*
X460992D01*
X461792Y119118D01*
Y117518D01*
X460992Y116718D01*
X460192D01*
X459392Y115918D01*
Y106900D01*
X460442Y105850D01*
X462033D01*
X462833Y105050D01*
Y83959D01*
X463492Y83300D01*
Y75659D01*
X462833Y75000D01*
Y46254D01*
X463400Y45687D01*
Y37708D01*
X462833Y37141D01*
Y24941D01*
X460333Y22441D01*
Y16742D01*
X458839Y15248D01*
Y14187D01*
X460912Y12114D01*
G01X454533Y-4100D02*
X453445Y-3012D01*
Y-1132D01*
X452012Y301D01*
Y1500D01*
X453512Y3000D01*
Y4200D01*
X452062Y5650D01*
Y7049D01*
X453445Y8432D01*
Y10301D01*
X450645Y13101D01*
Y16229D01*
X451573Y17157D01*
G01D02*
Y24781D01*
X453592Y26800D01*
Y28400D01*
X452633Y29359D01*
Y34441D01*
X453692Y35500D01*
Y36900D01*
X452992Y37600D01*
Y45500D01*
X453692Y46200D01*
Y47399D01*
X452769Y48322D01*
Y53178D01*
X454292Y54701D01*
Y65500D01*
X452633Y67159D01*
Y72275D01*
X453417Y73059D01*
Y74775D01*
X452792Y75400D01*
Y83375D01*
X453417Y84000D01*
Y85823D01*
X452766Y86474D01*
Y91074D01*
X453461Y91769D01*
Y101066D01*
X451792Y102735D01*
Y110601D01*
X428838Y133555D01*
Y135168D01*
X431415Y137745D01*
Y138877D01*
X430109Y140183D01*
X428977D01*
X426354Y137560D01*
X425222D01*
X423755Y139027D01*
Y140159D01*
X426378Y142782D01*
Y143914D01*
X419784Y150508D01*
Y189404D01*
X419957Y189577D01*
G01X454619Y12114D02*
X452633Y14100D01*
Y15514D01*
X454192Y17073D01*
Y23800D01*
X456233Y25841D01*
Y28599D01*
X456483Y28849D01*
Y35049D01*
X456133Y35399D01*
Y36941D01*
X456792Y37600D01*
Y45541D01*
X456133Y46200D01*
Y47342D01*
X456483Y47692D01*
Y53614D01*
X456392Y53705D01*
Y66558D01*
X456483Y66649D01*
Y71942D01*
X455917Y72508D01*
Y74025D01*
X456692Y74800D01*
Y83600D01*
X455917Y84375D01*
Y85925D01*
X456566Y86574D01*
Y91474D01*
X456184Y91856D01*
Y102408D01*
X454392Y104200D01*
Y111249D01*
X439860Y125781D01*
Y134109D01*
X438703Y135266D01*
X437841D01*
X435629Y133054D01*
X434837D01*
X433429Y134462D01*
Y135254D01*
X435641Y137466D01*
Y138328D01*
X422284Y151685D01*
Y189404D01*
X422457Y189577D01*
G01X451573Y-9901D02*
Y-8347D01*
X453820Y-6100D01*
X455044D01*
X456620Y-4524D01*
Y-2900D01*
X455845Y-2125D01*
Y10888D01*
X454619Y12114D01*
G01X474998Y17157D02*
X474070Y16229D01*
Y13101D01*
X477112Y10059D01*
Y8674D01*
X475437Y6999D01*
Y5876D01*
X476937Y4376D01*
Y3024D01*
X475652Y1740D01*
X475437Y1524D01*
Y301D01*
X476870Y-1132D01*
Y-2226D01*
X478344Y-3700D01*
G01X437771Y185879D02*
Y170630D01*
X438381Y170020D01*
X439832D01*
X440392Y169460D01*
Y167470D01*
X439832Y166910D01*
X438381D01*
X437771Y166300D01*
Y158259D01*
X477292Y118738D01*
Y117200D01*
X475592Y115500D01*
Y114652D01*
X476392Y113852D01*
X478515D01*
X479315Y113052D01*
Y111452D01*
X478515Y110652D01*
X476392D01*
X475592Y109852D01*
Y108252D01*
X476392Y107452D01*
X477492D01*
X478292Y106652D01*
Y105052D01*
X477492Y104252D01*
X476392D01*
X475592Y103452D01*
Y102700D01*
X476892Y101400D01*
Y91673D01*
X476092Y90873D01*
Y86855D01*
X477233Y85714D01*
Y84341D01*
X476192Y83300D01*
Y75500D01*
X477233Y74459D01*
Y73341D01*
X476192Y72300D01*
Y67140D01*
X476833Y66499D01*
Y53814D01*
X476433Y53414D01*
Y48714D01*
X477233Y47914D01*
Y46541D01*
X476392Y45700D01*
Y37901D01*
X477233Y37060D01*
Y35541D01*
X476092Y34400D01*
Y29440D01*
X477492Y28040D01*
Y19651D01*
X474998Y17157D01*
G01X478344Y12114D02*
X479733Y10725D01*
Y-2288D01*
X480345Y-2900D01*
Y-4300D01*
X478545Y-6100D01*
X477545D01*
X476245Y-7400D01*
Y-8654D01*
X474998Y-9901D01*
G01X440271Y186121D02*
Y174314D01*
X445320Y169265D01*
Y154246D01*
X481392Y118174D01*
Y96464D01*
X479792Y94864D01*
Y91755D01*
X480533Y91014D01*
Y86514D01*
X479733Y85714D01*
Y83800D01*
X480092Y83441D01*
Y75100D01*
X479733Y74741D01*
Y73159D01*
X480633Y72259D01*
Y67299D01*
X479833Y66499D01*
Y53914D01*
X480266Y53481D01*
Y48447D01*
X479733Y47914D01*
Y46259D01*
X480392Y45600D01*
Y37399D01*
X479733Y36740D01*
Y35259D01*
X480633Y34359D01*
Y29499D01*
X479792Y28658D01*
Y18809D01*
X476533Y15550D01*
Y13925D01*
X478344Y12114D01*
G01X464732Y14300D02*
X467838Y11194D01*
Y-4952D01*
X466510Y-6280D01*
X465528D01*
X464758Y-7050D01*
G01X431297Y186013D02*
Y183019D01*
X431747Y182569D01*
Y181569D01*
X431297Y181119D01*
Y180119D01*
X431747Y179669D01*
Y178669D01*
X431297Y178219D01*
Y176779D01*
X431747Y176329D01*
Y175329D01*
X431297Y174879D01*
Y173822D01*
X431747Y173372D01*
Y172372D01*
X431297Y171922D01*
Y170922D01*
X431747Y170472D01*
Y169472D01*
X431297Y169022D01*
Y168022D01*
X431747Y167572D01*
Y166572D01*
X431297Y166122D01*
Y164950D01*
X431747Y164500D01*
Y163500D01*
X431297Y163050D01*
Y162050D01*
X431747Y161600D01*
Y160600D01*
X431297Y160150D01*
Y159150D01*
X431747Y158700D01*
Y157700D01*
X431297Y157250D01*
Y155015D01*
X432004Y154308D01*
X432640D01*
X433348Y153600D01*
Y152964D01*
X434086Y152226D01*
X434722D01*
X435430Y151518D01*
Y150882D01*
X469072Y117240D01*
Y114924D01*
X467583Y113435D01*
X464344D01*
X463472Y112563D01*
Y110167D01*
X464444Y109195D01*
X467951D01*
X469072Y108074D01*
Y100048D01*
X467813Y98789D01*
Y60820D01*
X468433Y60200D01*
Y59200D01*
X467813Y58580D01*
Y57820D01*
X468433Y57200D01*
Y56200D01*
X467813Y55580D01*
Y24563D01*
X463938Y20688D01*
Y19620D01*
X464658Y18900D01*
X465658D01*
X466458Y18100D01*
Y16026D01*
X464732Y14300D01*
G01X469832Y14514D02*
X473024Y11322D01*
Y-4068D01*
X469832Y-7260D01*
G01X434997Y186413D02*
Y184626D01*
X435668Y183955D01*
Y156203D01*
X472964Y118907D01*
Y42520D01*
X473584Y41900D01*
Y40900D01*
X472964Y40280D01*
Y39520D01*
X473584Y38900D01*
Y37900D01*
X472964Y37280D01*
Y27186D01*
X473584Y26566D01*
Y25566D01*
X472964Y24946D01*
Y24114D01*
X472196Y23346D01*
Y22470D01*
X471488Y21762D01*
X470612D01*
X469638Y20788D01*
Y19920D01*
X471658Y17900D01*
Y16340D01*
X469832Y14514D01*
G01X464732Y11700D02*
X465831D01*
X466778Y10753D01*
Y8220D01*
X465808Y7250D01*
X465460D01*
X464844Y6634D01*
Y5302D01*
X465346Y4800D01*
X466058D01*
X466778Y4080D01*
Y3120D01*
X465958Y2300D01*
X465458D01*
X464858Y1700D01*
Y700D01*
X466778Y-1220D01*
Y-4509D01*
X466067Y-5220D01*
X465551D01*
X464732Y-4401D01*
G01X430237Y186013D02*
Y154575D01*
X468012Y116800D01*
Y115367D01*
X467140Y114495D01*
X463901D01*
X462412Y113006D01*
Y109727D01*
X464004Y108135D01*
X467511D01*
X468012Y107634D01*
Y100488D01*
X466753Y99229D01*
Y25006D01*
X462878Y21131D01*
Y13554D01*
X464732Y11700D01*
G01X469832Y11914D02*
Y11915D01*
X470930D01*
X471964Y10881D01*
Y8106D01*
X471258Y7400D01*
X470744D01*
X470044Y6700D01*
Y5700D01*
X470744Y5000D01*
X471244D01*
X471964Y4280D01*
Y2907D01*
X471157Y2100D01*
X470459D01*
X469858Y1499D01*
Y301D01*
X470459Y-300D01*
X471257D01*
X471964Y-1007D01*
Y-3628D01*
X470941Y-4651D01*
X469832D01*
G01X433937Y186413D02*
Y184186D01*
X434608Y183515D01*
Y181947D01*
X434158Y181497D01*
Y180497D01*
X434608Y180047D01*
Y177657D01*
X434158Y177207D01*
Y176207D01*
X434608Y175757D01*
Y173660D01*
X434158Y173210D01*
Y172210D01*
X434608Y171760D01*
Y169825D01*
X434158Y169375D01*
Y168375D01*
X434608Y167925D01*
Y155763D01*
X471904Y118467D01*
Y24557D01*
X468578Y21231D01*
Y18687D01*
X468108Y18217D01*
Y13638D01*
X469832Y11914D01*
G01X428147Y9120D02*
Y1941D01*
X427579Y1373D01*
X426589D01*
X425939Y2023D01*
Y6384D01*
X425329Y6994D01*
X424339D01*
X423729Y6384D01*
Y-569D01*
X424903Y-1743D01*
X428147D01*
G01X421456Y17057D02*
Y15925D01*
X419592Y14061D01*
Y10800D01*
X419836Y10556D01*
Y7844D01*
X419592Y7600D01*
Y-2676D01*
X421454Y-4538D01*
Y-7108D01*
G01X434840Y-1743D02*
Y1889D01*
X434230Y2499D01*
X431963D01*
X431353Y3109D01*
Y5009D01*
X431963Y5619D01*
X434230D01*
X434840Y6229D01*
Y9120D01*
G01X438187Y84714D02*
X439485Y83416D01*
Y81884D01*
X438493Y80892D01*
Y79033D01*
X440092Y77434D01*
Y75660D01*
X438189Y73757D01*
G01X428147Y87392D02*
X427844Y87089D01*
Y82836D01*
X427234Y82226D01*
X424384D01*
X423774Y81616D01*
Y80626D01*
X424384Y80016D01*
X427809D01*
X428384Y79441D01*
Y78451D01*
X427739Y77806D01*
X422244D01*
X421581Y77143D01*
Y76153D01*
X422138Y75596D01*
X427554D01*
X428149Y75001D01*
Y73757D01*
G01X421454Y92757D02*
X421965Y92246D01*
Y79902D01*
X419841Y77778D01*
Y72222D01*
X419443Y71824D01*
Y69349D01*
X421456Y67336D01*
Y65822D01*
G01X434840Y87392D02*
X435892D01*
X436692Y86592D01*
Y85870D01*
X436158Y85336D01*
Y75073D01*
X434842Y73757D01*
G01X438189Y46922D02*
X436492Y45225D01*
Y37654D01*
X438189Y35957D01*
G01X428149Y46922D02*
Y45617D01*
X427539Y45007D01*
X423575D01*
X422965Y44397D01*
Y43366D01*
X423575Y42756D01*
X427539D01*
X428149Y42146D01*
Y40947D01*
X427539Y40337D01*
X423575D01*
X422965Y39727D01*
Y38351D01*
X423626Y37690D01*
X427649D01*
X428149Y37190D01*
Y35957D01*
G01X434842D02*
X433411Y37388D01*
Y45491D01*
X434842Y46922D01*
G01X442771Y188577D02*
Y175844D01*
X450780Y167835D01*
Y164845D01*
X450170Y164235D01*
X448465D01*
X447855Y163625D01*
Y161735D01*
X448465Y161125D01*
X450170D01*
X450780Y160515D01*
Y158625D01*
X450170Y158015D01*
X448465D01*
X447855Y157405D01*
Y155515D01*
X448465Y154905D01*
X450170D01*
X450780Y154295D01*
Y152322D01*
X483892Y119210D01*
Y92001D01*
X483092Y91201D01*
Y86355D01*
X483954Y85493D01*
Y84361D01*
X483192Y83599D01*
Y75200D01*
X484097Y74295D01*
Y73505D01*
X483133Y72541D01*
Y66799D01*
X484392Y65540D01*
Y64600D01*
X483566Y63774D01*
Y62826D01*
X484392Y62000D01*
Y60926D01*
X483566Y60100D01*
Y58726D01*
X484292Y58000D01*
Y56926D01*
X483566Y56200D01*
Y53847D01*
X482792Y53073D01*
Y48855D01*
X483633Y48014D01*
Y46242D01*
X482692Y45301D01*
Y41974D01*
X483292Y41374D01*
Y40099D01*
X482592Y39399D01*
Y37900D01*
X483633Y36859D01*
Y35141D01*
X483133Y34641D01*
Y28999D01*
X484192Y27940D01*
Y26400D01*
X483392Y25600D01*
Y22901D01*
X484092Y22201D01*
Y19558D01*
X481691Y17157D01*
G01X445271Y188577D02*
Y176788D01*
X457345Y164714D01*
Y156697D01*
X456785Y156137D01*
X454852D01*
X454292Y155577D01*
Y154137D01*
X454852Y153577D01*
X456785D01*
X457345Y153017D01*
Y149293D01*
X486392Y120246D01*
Y92015D01*
X487133Y91274D01*
Y86614D01*
X486433Y85914D01*
Y84000D01*
X486992Y83441D01*
Y75200D01*
X486433Y74641D01*
Y73159D01*
X487033Y72559D01*
Y67049D01*
X486292Y66308D01*
Y54055D01*
X486866Y53481D01*
Y48547D01*
X485892Y47573D01*
Y35900D01*
X487033Y34759D01*
Y29249D01*
X486483Y28699D01*
Y18964D01*
X483133Y15614D01*
Y14018D01*
X485037Y12114D01*
G01X454284Y185697D02*
Y178826D01*
X466251Y166859D01*
Y153116D01*
X490267Y129100D01*
X509292D01*
X511036Y127356D01*
Y124560D01*
X511596Y124000D01*
X513676D01*
X514236Y124560D01*
Y125200D01*
X515036Y126000D01*
X516636D01*
X517436Y125200D01*
Y123782D01*
X518236Y122982D01*
X519836D01*
X520636Y123782D01*
Y125200D01*
X521436Y126000D01*
X522518D01*
X533784Y114734D01*
Y111556D01*
X532666Y110438D01*
Y106074D01*
X533766Y104974D01*
Y92074D01*
X532666Y90974D01*
Y86474D01*
X533966Y85174D01*
Y84200D01*
X533292Y83526D01*
Y75500D01*
X533966Y74826D01*
Y73475D01*
X532666Y72175D01*
Y67333D01*
X533593Y66406D01*
Y66400D01*
X533766Y66227D01*
Y54258D01*
X532666Y53158D01*
Y48644D01*
X533955Y47355D01*
Y35563D01*
X532605Y34213D01*
Y29594D01*
X533755Y28444D01*
Y26663D01*
X531888Y24796D01*
Y17157D01*
G01X456492Y185400D02*
Y180192D01*
X468656Y168028D01*
Y154248D01*
X489818Y133086D01*
X493584D01*
X495570Y131100D01*
X520955D01*
X536455Y115600D01*
Y83900D01*
X537092Y83263D01*
Y75500D01*
X536455Y74863D01*
Y25863D01*
X533955Y23363D01*
Y16662D01*
X532461Y15168D01*
Y14187D01*
X534534Y12114D01*
G01X449392Y185848D02*
Y177023D01*
X461766Y164649D01*
Y150529D01*
X494295Y118000D01*
X499573D01*
X500373Y118800D01*
Y122800D01*
X501173Y123600D01*
X502773D01*
X503573Y122800D01*
Y116260D01*
X504133Y115700D01*
X525746D01*
X527092Y114354D01*
Y111564D01*
X526366Y110838D01*
Y106174D01*
X527166Y105374D01*
Y91874D01*
X526266Y90974D01*
Y86674D01*
X527066Y85874D01*
Y83900D01*
X526692Y83526D01*
Y75200D01*
X527066Y74826D01*
Y72859D01*
X526166Y71959D01*
Y67326D01*
X527266Y66226D01*
Y54138D01*
X526366Y53238D01*
Y48774D01*
X527255Y47885D01*
Y35299D01*
X526255Y34299D01*
Y29437D01*
X527155Y28537D01*
Y27063D01*
X525195Y25103D01*
Y17157D01*
G01X451592Y185669D02*
Y178463D01*
X463781Y166274D01*
Y152050D01*
X489631Y126200D01*
X506146D01*
X512146Y120200D01*
Y119000D01*
X512946Y118200D01*
X514546D01*
X515646Y119300D01*
X525682D01*
X529884Y115098D01*
Y111256D01*
X530184Y110956D01*
Y105756D01*
X529866Y105438D01*
Y91974D01*
X530566Y91274D01*
Y86538D01*
X529800Y85772D01*
Y84100D01*
X530492Y83408D01*
Y75400D01*
X529800Y74708D01*
Y72741D01*
X530366Y72175D01*
Y67559D01*
X529766Y66959D01*
Y53974D01*
X530466Y53274D01*
Y48738D01*
X529755Y48027D01*
Y35399D01*
X530105Y35049D01*
Y28849D01*
X529855Y28599D01*
Y26263D01*
X528392Y24800D01*
Y17651D01*
X526255Y15514D01*
Y14104D01*
X527391Y12968D01*
Y12964D01*
X528241Y12114D01*
G01X461018Y183900D02*
Y181003D01*
X461725Y180296D01*
X462361D01*
X463069Y179588D01*
Y178952D01*
X463776Y178245D01*
X464412D01*
X465120Y177537D01*
Y176901D01*
X465827Y176194D01*
X466463D01*
X467171Y175486D01*
Y174850D01*
X467878Y174143D01*
X468514D01*
X469222Y173435D01*
Y172799D01*
X469929Y172092D01*
X470565D01*
X471273Y171384D01*
Y170748D01*
X472425Y169596D01*
Y168466D01*
X472875Y168016D01*
Y167016D01*
X472425Y166566D01*
Y165566D01*
X472875Y165116D01*
Y164116D01*
X472425Y163666D01*
Y162666D01*
X472875Y162216D01*
Y161216D01*
X472425Y160766D01*
Y159766D01*
X472875Y159316D01*
Y158316D01*
X472425Y157866D01*
Y155686D01*
X489429Y138680D01*
X497048D01*
X498304Y137424D01*
Y135906D01*
X499430Y134780D01*
X502431D01*
X503300Y135649D01*
Y137191D01*
X504789Y138680D01*
X508171D01*
X509660Y137191D01*
Y135652D01*
X510532Y134780D01*
X513400D01*
X513900Y135280D01*
Y137559D01*
X515021Y138680D01*
X518583D01*
X541435Y115828D01*
Y44820D01*
X542055Y44200D01*
Y43200D01*
X541435Y42580D01*
Y41820D01*
X542055Y41200D01*
Y40200D01*
X541435Y39580D01*
Y38820D01*
X542055Y38200D01*
Y37200D01*
X541435Y36580D01*
Y25310D01*
X537561Y21436D01*
Y19620D01*
X538281Y18900D01*
X539281D01*
X540081Y18100D01*
Y16026D01*
X538355Y14300D01*
G01X464819Y185913D02*
Y183770D01*
X478119Y170470D01*
Y155390D01*
X491029Y142480D01*
X520583D01*
X546672Y116391D01*
Y31620D01*
X547192Y31100D01*
Y29900D01*
X546672Y29380D01*
Y24509D01*
X546069Y23906D01*
Y23030D01*
X545362Y22323D01*
X544486D01*
X542761Y20598D01*
Y19501D01*
X543262Y19000D01*
X544693D01*
X545281Y18412D01*
Y16340D01*
X543455Y14514D01*
G01X459958Y183900D02*
Y180563D01*
X471365Y169156D01*
Y155246D01*
X488989Y137620D01*
X496608D01*
X497244Y136984D01*
Y135466D01*
X498990Y133720D01*
X502871D01*
X504360Y135209D01*
Y136748D01*
X505232Y137620D01*
X507728D01*
X508600Y136748D01*
Y135209D01*
X510089Y133720D01*
X513840D01*
X514960Y134840D01*
Y137119D01*
X515461Y137620D01*
X518143D01*
X540375Y115388D01*
Y25753D01*
X536501Y21879D01*
Y13554D01*
X538355Y11700D01*
G01X463759Y185913D02*
Y183330D01*
X466121Y180968D01*
Y180331D01*
X466829Y179623D01*
X467466D01*
X468567Y178522D01*
Y177885D01*
X469275Y177177D01*
X469912D01*
X470900Y176189D01*
Y175553D01*
X471608Y174845D01*
X472244D01*
X473003Y174086D01*
Y173450D01*
X473711Y172742D01*
X474347D01*
X477059Y170030D01*
Y154950D01*
X490589Y141420D01*
X520140D01*
X545612Y115948D01*
Y24949D01*
X541701Y21038D01*
Y13668D01*
X543455Y11914D01*
G01X472448Y187055D02*
Y185478D01*
X486392Y171534D01*
Y159876D01*
X494468Y151800D01*
X497160D01*
X497720Y151240D01*
Y149960D01*
X498280Y149400D01*
X499720D01*
X500280Y149960D01*
Y151240D01*
X500840Y151800D01*
X502280D01*
X502840Y151240D01*
Y149960D01*
X503400Y149400D01*
X504840D01*
X505740Y150300D01*
X523711D01*
X558192Y115819D01*
Y112364D01*
X556466Y110638D01*
Y106374D01*
X558000Y104840D01*
Y103708D01*
X557292Y103000D01*
Y91664D01*
X556566Y90938D01*
Y86374D01*
X557266Y85674D01*
Y83974D01*
X556592Y83300D01*
Y75474D01*
X557266Y74800D01*
Y73075D01*
X556566Y72375D01*
Y67059D01*
X557392Y66233D01*
Y54263D01*
X556655Y53526D01*
Y48614D01*
X557255Y48014D01*
Y46063D01*
X556592Y45400D01*
Y37463D01*
X557255Y36800D01*
Y35363D01*
X556792Y34900D01*
Y29000D01*
X557555Y28237D01*
Y19399D01*
X555313Y17157D01*
G01X474948Y187055D02*
Y185980D01*
X488380Y172548D01*
Y161012D01*
X495392Y154000D01*
X523547D01*
X560692Y116855D01*
Y103100D01*
X560192Y102600D01*
Y91548D01*
X560459Y91281D01*
Y85967D01*
X559984Y85492D01*
Y84100D01*
X560592Y83492D01*
Y75200D01*
X559984Y74592D01*
Y73209D01*
X560566Y72627D01*
Y67059D01*
X560105Y66598D01*
Y53914D01*
X560566Y53453D01*
Y48575D01*
X560055Y48064D01*
Y46037D01*
X560792Y45300D01*
Y37737D01*
X560055Y37000D01*
Y35237D01*
X560655Y34637D01*
Y29249D01*
X560105Y28699D01*
Y18964D01*
X556755Y15614D01*
Y14018D01*
X558659Y12114D01*
G01X467448Y187055D02*
Y184671D01*
X480680Y171439D01*
Y155912D01*
X482783Y153809D01*
X483575D01*
X484433Y154667D01*
X485225D01*
X486244Y153648D01*
Y152856D01*
X485386Y151998D01*
Y151206D01*
X486405Y150187D01*
X487197D01*
X488055Y151045D01*
X488847D01*
X489866Y150026D01*
Y149234D01*
X489008Y148376D01*
Y147584D01*
X491492Y145100D01*
X521667D01*
X550420Y116347D01*
Y111228D01*
X549966Y110774D01*
Y106274D01*
X550666Y105574D01*
Y91738D01*
X549866Y90938D01*
Y86174D01*
X550666Y85374D01*
Y84214D01*
X549392Y82940D01*
Y75624D01*
X550666Y74350D01*
Y73175D01*
X550066Y72575D01*
Y66959D01*
X550766Y66259D01*
Y64759D01*
X550455Y64448D01*
Y53926D01*
X550055Y53526D01*
Y48714D01*
X550855Y47914D01*
Y46400D01*
X550092Y45637D01*
Y37800D01*
X550855Y37037D01*
Y35563D01*
X550055Y34763D01*
Y29099D01*
X550655Y28499D01*
Y19192D01*
X548620Y17157D01*
G01X469948Y187055D02*
Y185280D01*
X483392Y171836D01*
Y159100D01*
X495492Y147000D01*
X523475D01*
X553284Y117191D01*
Y111456D01*
X553932Y110808D01*
Y106004D01*
X553366Y105438D01*
Y91674D01*
X554066Y90974D01*
Y86138D01*
X553292Y85364D01*
Y73101D01*
X554022Y72371D01*
Y67215D01*
X553455Y66648D01*
Y53986D01*
X554155Y53286D01*
Y48714D01*
X553355Y47914D01*
Y46200D01*
X553892Y45663D01*
Y37500D01*
X553355Y36963D01*
Y35437D01*
X553892Y34900D01*
Y29136D01*
X553513Y28757D01*
Y18920D01*
X550155Y15562D01*
Y13925D01*
X551966Y12114D01*
G01X481592Y193300D02*
X495992Y178900D01*
X508892D01*
X535180Y152612D01*
X535972D01*
X536480Y153120D01*
X537272D01*
X538291Y152101D01*
Y151309D01*
X537783Y150801D01*
Y150009D01*
X538802Y148990D01*
X539594D01*
X540502Y149898D01*
X541294D01*
X542313Y148879D01*
Y148087D01*
X541405Y147179D01*
Y146387D01*
X542424Y145368D01*
X543216D01*
X544124Y146276D01*
X544916D01*
X545935Y145257D01*
Y144465D01*
X545027Y143557D01*
Y142765D01*
X546046Y141746D01*
X546838D01*
X547746Y142654D01*
X548538D01*
X549557Y141635D01*
Y140843D01*
X548649Y139935D01*
Y139143D01*
X549668Y138124D01*
X550460D01*
X551368Y139032D01*
X552160D01*
X553179Y138013D01*
X553180D01*
X569784Y121409D01*
Y102207D01*
X570499Y101492D01*
Y92107D01*
X569492Y91100D01*
Y86348D01*
X570592Y85248D01*
Y84099D01*
X569792Y83299D01*
Y75500D01*
X570592Y74700D01*
Y73299D01*
X569416Y72123D01*
Y67394D01*
X570592Y66218D01*
Y54273D01*
X569640Y53321D01*
Y53012D01*
X569416Y52788D01*
Y48914D01*
X570592Y47738D01*
Y45834D01*
X569492Y44734D01*
Y42434D01*
X570192Y41734D01*
Y39900D01*
X569292Y39000D01*
Y38200D01*
X570592Y36900D01*
Y35359D01*
X569416Y34183D01*
Y29594D01*
X570592Y28418D01*
Y26799D01*
X568699Y24906D01*
Y17157D01*
G01X483492Y194200D02*
X494792Y182900D01*
X507491D01*
X532791Y157600D01*
X536625D01*
X572284Y121941D01*
Y103108D01*
X573266Y102126D01*
Y84027D01*
X574192Y83101D01*
Y75626D01*
X573266Y74700D01*
Y46026D01*
X573992Y45300D01*
Y37926D01*
X573266Y37200D01*
Y25673D01*
X570766Y23173D01*
Y16674D01*
X569272Y15180D01*
Y14187D01*
X571345Y12114D01*
G01X479792Y189500D02*
Y189000D01*
X494692Y174100D01*
X504193D01*
X511092Y167201D01*
Y160060D01*
X511652Y159500D01*
X513481D01*
X514041Y160060D01*
Y163740D01*
X514601Y164300D01*
X516041D01*
X516601Y163740D01*
Y157860D01*
X517161Y157300D01*
X524693D01*
X564784Y117209D01*
Y103892D01*
X564192Y103300D01*
Y91864D01*
X563466Y91138D01*
Y86374D01*
X564192Y85648D01*
Y84300D01*
X563392Y83500D01*
Y75200D01*
X564192Y74400D01*
Y73365D01*
X563066Y72239D01*
Y67227D01*
X564292Y66001D01*
Y54640D01*
X563202Y53550D01*
Y48990D01*
X564192Y48000D01*
Y46200D01*
X563492Y45500D01*
Y38000D01*
X564192Y37300D01*
Y35425D01*
X563066Y34299D01*
Y29327D01*
X563992Y28401D01*
Y27000D01*
X563258Y26266D01*
Y25134D01*
X563976Y24416D01*
Y23284D01*
X563192Y22500D01*
Y21414D01*
X564092Y20514D01*
Y19243D01*
X561868Y17019D01*
G01X481142Y190750D02*
X495792Y176100D01*
X508493D01*
X555754Y128839D01*
X557253D01*
X558355Y127737D01*
X558357Y126236D01*
X559376Y125217D01*
X560168D01*
X561325Y126374D01*
X562115Y126375D01*
X563135Y125355D01*
Y124563D01*
X561978Y123406D01*
X561979Y122614D01*
X562998Y121595D01*
X563790D01*
X564947Y122752D01*
X565737Y122753D01*
X566757Y121733D01*
Y120941D01*
X565600Y119784D01*
X565601Y118992D01*
X567284Y117309D01*
Y102592D01*
X566784Y102092D01*
Y90956D01*
X567092Y90648D01*
Y86400D01*
X566692Y86000D01*
Y83900D01*
X567292Y83300D01*
Y75600D01*
X566692Y75000D01*
Y72749D01*
X567084Y72357D01*
Y67557D01*
X566892Y67365D01*
Y53638D01*
X567084Y53446D01*
Y48832D01*
X566749Y48497D01*
Y46044D01*
X567316Y45477D01*
Y37924D01*
X566749Y37357D01*
Y35216D01*
X566916Y35049D01*
Y28849D01*
X566592Y28525D01*
Y19040D01*
X563184Y15632D01*
Y13982D01*
X565052Y12114D01*
G01X485792Y195200D02*
X495992Y185000D01*
X508792D01*
X513757Y180035D01*
Y180033D01*
X532752Y161040D01*
X536952D01*
X574912Y123080D01*
Y116762D01*
X576401Y115273D01*
X578020D01*
X578892Y114401D01*
Y111905D01*
X578020Y111033D01*
X576301D01*
X574812Y109544D01*
Y106162D01*
X576301Y104673D01*
X577440D01*
X578412Y103701D01*
Y102725D01*
X576301Y100614D01*
Y97987D01*
X578302Y95986D01*
Y95281D01*
X577186Y94165D01*
Y25005D01*
X573312Y21131D01*
Y13554D01*
X575166Y11700D01*
G01X426372Y413233D02*
X426139Y413466D01*
Y459519D01*
X440940Y474320D01*
Y478849D01*
X457554Y495463D01*
Y506662D01*
X460333Y509441D01*
Y510707D01*
X458983Y512057D01*
Y516307D01*
X460333Y517657D01*
Y519100D01*
X459992Y519441D01*
Y527900D01*
X460333Y528241D01*
Y529258D01*
X458983Y530608D01*
Y535290D01*
X460333Y536640D01*
Y538260D01*
X459992Y538601D01*
Y546800D01*
X460333Y547141D01*
Y548507D01*
X458983Y549857D01*
Y554107D01*
X460133Y555257D01*
Y557300D01*
X459892Y557541D01*
Y565800D01*
X460133Y566041D01*
Y567259D01*
X459033Y568359D01*
Y573141D01*
X460183Y574291D01*
Y575600D01*
X459892Y575891D01*
Y584600D01*
X460183Y584891D01*
Y586457D01*
X456833Y589807D01*
Y592324D01*
X458266Y593757D01*
G01X428872Y413233D02*
X428714Y413391D01*
Y458519D01*
X445606Y475411D01*
Y476273D01*
X443900Y477980D01*
Y478842D01*
X444884Y479826D01*
X445746D01*
X447452Y478119D01*
X448314D01*
X450494Y480299D01*
Y485737D01*
X460645Y495888D01*
Y496596D01*
X460290Y496951D01*
Y498931D01*
X460900Y499541D01*
X463382D01*
X463992Y500151D01*
Y502131D01*
X463382Y502741D01*
X460900D01*
X460290Y503351D01*
Y505331D01*
X460900Y505941D01*
X463382D01*
X463992Y506551D01*
Y508200D01*
X462833Y509359D01*
Y518600D01*
X463292Y519059D01*
Y528100D01*
X462833Y528559D01*
Y537700D01*
X463292Y538159D01*
Y546000D01*
X462833Y546459D01*
Y556540D01*
X463292Y556999D01*
Y565300D01*
X462833Y565759D01*
Y575500D01*
X463292Y575959D01*
Y584300D01*
X462833Y584759D01*
Y586443D01*
X460912Y588364D01*
Y588714D01*
G01X444881Y406992D02*
X444792Y407081D01*
Y415600D01*
X443492Y416900D01*
Y452426D01*
X481420Y490354D01*
Y507127D01*
X483537Y509244D01*
Y511253D01*
X483160Y511630D01*
Y516668D01*
X483496Y517004D01*
Y529903D01*
X482592Y530807D01*
Y535101D01*
X483572Y536081D01*
Y549120D01*
X482892Y549800D01*
Y554100D01*
X483740Y554948D01*
Y557193D01*
X483367Y557566D01*
Y565375D01*
X483614Y565622D01*
Y567616D01*
X482692Y568538D01*
Y573285D01*
X483796Y574389D01*
Y586444D01*
X481253Y588987D01*
Y593319D01*
X481691Y593757D01*
G01X449023Y406491D02*
X449392Y406860D01*
Y414000D01*
X446328Y417064D01*
Y451714D01*
X485890Y491276D01*
Y502086D01*
X485280Y502696D01*
X483986D01*
X483376Y503306D01*
Y504696D01*
X483986Y505306D01*
X485280D01*
X485890Y505916D01*
Y510498D01*
X487492Y512100D01*
Y516348D01*
X486483Y517357D01*
Y519500D01*
X486692Y519709D01*
Y527700D01*
X486483Y527909D01*
Y529816D01*
X487133Y530466D01*
Y535458D01*
X486092Y536499D01*
Y537899D01*
X486692Y538499D01*
Y546400D01*
X486433Y546659D01*
Y549641D01*
G01X486483Y554809D02*
Y567647D01*
X487333Y568497D01*
Y573058D01*
X486333Y574058D01*
Y575300D01*
X486692Y575659D01*
Y584300D01*
X486333Y584659D01*
Y587470D01*
X485037Y588766D01*
Y588714D01*
G01X421372Y411038D02*
X421139Y411271D01*
Y466138D01*
X451974Y496973D01*
Y507641D01*
X453533Y509200D01*
Y510897D01*
X452633Y511797D01*
Y516457D01*
X453533Y517357D01*
Y519500D01*
X453292Y519741D01*
Y527800D01*
X453533Y528041D01*
Y529358D01*
X452633Y530258D01*
Y535242D01*
X453633Y536242D01*
Y537900D01*
X453292Y538241D01*
Y546500D01*
X453633Y546841D01*
Y548557D01*
X452633Y549557D01*
Y554257D01*
X453533Y555157D01*
Y557300D01*
X453192Y557641D01*
Y565600D01*
X453533Y565941D01*
Y567159D01*
X452485Y568207D01*
Y572944D01*
X453483Y573942D01*
Y575500D01*
X453292Y575691D01*
Y584800D01*
X453483Y584991D01*
Y586457D01*
X450492Y589448D01*
Y592676D01*
X451573Y593757D01*
G01X423872Y410647D02*
X423639Y410880D01*
Y465354D01*
X429309Y471024D01*
X430171D01*
X431410Y469785D01*
X432272D01*
X433256Y470769D01*
Y471631D01*
X432017Y472870D01*
Y473732D01*
X433001Y474716D01*
X433863D01*
X435102Y473477D01*
X435964D01*
X436948Y474461D01*
Y475323D01*
X435709Y476562D01*
Y477424D01*
X454672Y496387D01*
Y507598D01*
X456233Y509159D01*
Y511497D01*
X457092Y512356D01*
Y516200D01*
X455792Y517500D01*
Y518999D01*
X456592Y519799D01*
Y527500D01*
X455933Y528159D01*
Y529640D01*
X456792Y530499D01*
Y535499D01*
X456028Y536263D01*
Y537635D01*
X456592Y538199D01*
Y546200D01*
X455892Y546900D01*
Y548900D01*
X456792Y549800D01*
Y553900D01*
X455878Y554814D01*
Y556985D01*
X456592Y557699D01*
Y565500D01*
X456233Y565859D01*
Y567997D01*
X456733Y568497D01*
Y572656D01*
X456133Y573256D01*
Y575400D01*
X456592Y575859D01*
Y584500D01*
X456133Y584959D01*
Y587200D01*
X454619Y588714D01*
G01X439921Y406641D02*
X439592Y406970D01*
Y414300D01*
X438492Y415400D01*
Y454224D01*
X474046Y489778D01*
Y506698D01*
X476783Y509435D01*
Y511707D01*
X476433Y512057D01*
Y516957D01*
X476833Y517357D01*
Y529842D01*
X476433Y530242D01*
Y535942D01*
X476895Y536404D01*
Y549395D01*
X476433Y549857D01*
Y554757D01*
X477033Y555357D01*
Y567397D01*
X475960Y568470D01*
Y572969D01*
X476840Y573849D01*
Y586750D01*
X474565Y589025D01*
Y593324D01*
X474998Y593757D01*
G01X442381Y406641D02*
X442092Y406930D01*
Y414800D01*
X440992Y415900D01*
Y453188D01*
X478414Y490610D01*
Y492317D01*
X477904Y492827D01*
X477086D01*
X476476Y493437D01*
Y494827D01*
X477086Y495437D01*
X478604D01*
X479214Y496047D01*
Y497437D01*
X478604Y498047D01*
X477086D01*
X476476Y498657D01*
Y500047D01*
X477086Y500657D01*
X478604D01*
X479214Y501267D01*
Y502657D01*
X478604Y503267D01*
X477086D01*
X476476Y503877D01*
Y505944D01*
X479733Y509201D01*
Y511257D01*
X480633Y512157D01*
Y516557D01*
X479833Y517357D01*
Y519300D01*
X479992Y519459D01*
Y527600D01*
X479833Y527759D01*
Y529842D01*
X480533Y530542D01*
Y535658D01*
X479733Y536458D01*
Y537700D01*
X479992Y537959D01*
Y546500D01*
X479733Y546759D01*
Y549057D01*
X480633Y549957D01*
Y554357D01*
X479533Y555457D01*
Y557200D01*
X479992Y557659D01*
Y565700D01*
X479833Y565859D01*
Y567597D01*
X480399Y568163D01*
Y573393D01*
X479733Y574059D01*
Y575500D01*
X479992Y575759D01*
Y584300D01*
X479733Y584559D01*
Y587368D01*
X479690D01*
X478344Y588714D01*
G01X456473Y420405D02*
Y448800D01*
X490877Y483204D01*
X527049D01*
X532721Y488876D01*
Y496597D01*
X533663Y497539D01*
Y510999D01*
X532740Y511922D01*
Y516442D01*
X533955Y517657D01*
Y529267D01*
X532741Y530481D01*
Y535350D01*
X533606Y536215D01*
Y548856D01*
X532605Y549857D01*
Y554107D01*
X533635Y555137D01*
Y567387D01*
X532655Y568367D01*
Y573163D01*
X533634Y574142D01*
Y586628D01*
X531148Y589114D01*
Y593017D01*
X531888Y593757D01*
G01X458973Y420405D02*
Y447764D01*
X491507Y480298D01*
X502906D01*
X503516Y479688D01*
Y478478D01*
X504126Y477868D01*
X505516D01*
X506126Y478478D01*
Y479688D01*
X506736Y480298D01*
X508126D01*
X508736Y479688D01*
Y478478D01*
X509346Y477868D01*
X510736D01*
X511346Y478478D01*
Y479688D01*
X511956Y480298D01*
X514137D01*
X514747Y479688D01*
Y478450D01*
X515357Y477840D01*
X516747D01*
X517357Y478450D01*
Y479688D01*
X517967Y480298D01*
X519357D01*
X519967Y479688D01*
Y478450D01*
X520577Y477840D01*
X524451D01*
X536455Y489844D01*
Y499564D01*
X538203Y501312D01*
Y502790D01*
X537593Y503400D01*
X536441D01*
X535831Y504010D01*
Y504890D01*
X536441Y505500D01*
X537593D01*
X538203Y506110D01*
Y507489D01*
X536455Y509237D01*
Y518664D01*
X536892Y519101D01*
Y527800D01*
X536455Y528237D01*
Y537700D01*
X536892Y538137D01*
Y546100D01*
X536455Y546537D01*
Y556664D01*
X536892Y557101D01*
Y565300D01*
X536455Y565737D01*
Y586443D01*
X534534Y588364D01*
Y588714D01*
G01X555313Y593757D02*
X553955Y592399D01*
Y589907D01*
X557355Y586507D01*
Y574042D01*
X556455Y573142D01*
Y568397D01*
X557555Y567297D01*
Y566063D01*
X556988Y565496D01*
Y557467D01*
X557555Y556900D01*
Y555657D01*
X556755Y554857D01*
Y549457D01*
X557255Y548957D01*
Y546963D01*
X556992Y546700D01*
Y538163D01*
X557492Y537663D01*
Y536499D01*
X556655Y535662D01*
Y530366D01*
X557540Y529481D01*
Y528348D01*
X556992Y527800D01*
Y519913D01*
X557892Y519013D01*
Y517700D01*
X556755Y516563D01*
Y511657D01*
X557255Y511157D01*
Y509400D01*
X556492Y508637D01*
Y501100D01*
X557255Y500337D01*
Y497841D01*
X556892Y497478D01*
Y491826D01*
X557266Y491452D01*
Y489932D01*
X551543Y484209D01*
X549112D01*
X526176Y461273D01*
X495065D01*
X474079Y440287D01*
Y419941D01*
G01X558659Y588714D02*
Y588766D01*
X559955Y587470D01*
Y574038D01*
X560955Y573038D01*
Y568497D01*
X560105Y567647D01*
Y565687D01*
X560392Y565400D01*
Y557287D01*
X560105Y557000D01*
Y555157D01*
X560655Y554607D01*
Y550057D01*
X560055Y549457D01*
Y546637D01*
X560292Y546400D01*
Y537837D01*
X560055Y537600D01*
Y536238D01*
X560755Y535538D01*
Y530466D01*
X560105Y529816D01*
Y527887D01*
X560392Y527600D01*
Y519587D01*
X560105Y519300D01*
Y517357D01*
X560655Y516807D01*
Y512257D01*
X560055Y511657D01*
Y509237D01*
X560292Y509000D01*
Y497600D01*
X560692Y497200D01*
Y489642D01*
X550452Y479402D01*
X549590D01*
X548734Y480258D01*
X547872D01*
X546888Y479274D01*
Y478412D01*
X547744Y477556D01*
Y476694D01*
X546760Y475710D01*
X545898D01*
X545042Y476566D01*
X544180D01*
X543196Y475582D01*
Y474720D01*
X544052Y473864D01*
Y473002D01*
X543068Y472018D01*
X542206D01*
X541350Y472874D01*
X540488D01*
X539504Y471890D01*
Y471028D01*
X540360Y470172D01*
Y469310D01*
X530144Y459094D01*
X496486D01*
X476579Y439187D01*
Y419941D01*
G01X451473D02*
X450328Y421086D01*
Y449727D01*
X488901Y488300D01*
X520593D01*
X522792Y490499D01*
Y499500D01*
X526343Y503051D01*
Y508588D01*
X527155Y509400D01*
Y510897D01*
X526255Y511797D01*
Y516457D01*
X527155Y517357D01*
Y529438D01*
X526255Y530338D01*
Y535242D01*
X527126Y536113D01*
Y549066D01*
X525792Y550400D01*
Y553794D01*
X527728Y555730D01*
Y556863D01*
X526892Y557699D01*
Y565600D01*
X527155Y565863D01*
Y567237D01*
X525792Y568600D01*
Y572629D01*
X527105Y573942D01*
Y586587D01*
X525992Y587700D01*
X524792D01*
X523955Y588537D01*
Y592517D01*
X525195Y593757D01*
G01X454192Y420160D02*
Y421900D01*
X452828Y423264D01*
Y448691D01*
X490357Y486220D01*
X521213D01*
X522610Y487617D01*
X523431D01*
X525536Y485512D01*
X526441D01*
X527842Y486913D01*
Y487732D01*
X529992Y489882D01*
Y494200D01*
X528656Y495536D01*
Y505540D01*
X529294Y506178D01*
X530390D01*
X531112Y506900D01*
Y508080D01*
X529855Y509337D01*
Y511497D01*
X530105Y511747D01*
Y517207D01*
X529855Y517457D01*
Y518712D01*
X531265Y520122D01*
Y521297D01*
X530655Y521907D01*
X529977D01*
X529367Y522517D01*
Y524497D01*
X529977Y525107D01*
X530655D01*
X531265Y525717D01*
Y526941D01*
X529855Y528351D01*
Y529992D01*
X530105Y530242D01*
Y535192D01*
X529755Y535542D01*
Y548457D01*
X530105Y548807D01*
Y555007D01*
X529855Y555257D01*
Y557100D01*
X530192Y557437D01*
Y565900D01*
X529855Y566237D01*
Y567997D01*
X530355Y568497D01*
Y572656D01*
X529755Y573256D01*
Y575300D01*
X530692Y576237D01*
Y583800D01*
X529755Y584737D01*
Y587200D01*
X528241Y588714D01*
G01X551966D02*
X553355Y587325D01*
Y574137D01*
X554021Y573471D01*
Y568163D01*
X553455Y567597D01*
Y565937D01*
X553692Y565700D01*
Y557637D01*
X553155Y557100D01*
Y555457D01*
X554255Y554357D01*
Y549957D01*
X553355Y549057D01*
Y546937D01*
X553692Y546600D01*
Y538037D01*
X553355Y537700D01*
Y536538D01*
X554155Y535738D01*
Y530542D01*
X553455Y529842D01*
Y527837D01*
X553692Y527600D01*
Y519637D01*
X553455Y519400D01*
Y517357D01*
X554255Y516557D01*
Y512157D01*
X553355Y511257D01*
Y509500D01*
X553921Y508934D01*
Y500729D01*
X553092Y499900D01*
Y489474D01*
X549950Y486332D01*
X548554D01*
X525982Y463760D01*
X510022D01*
X509412Y464370D01*
Y465804D01*
X508830Y466386D01*
X507440D01*
X506802Y465748D01*
Y464370D01*
X506192Y463760D01*
X504802D01*
X504192Y464370D01*
Y466139D01*
X503582Y466749D01*
X502192D01*
X501582Y466139D01*
Y464370D01*
X500972Y463760D01*
X499582D01*
X498972Y464370D01*
Y466139D01*
X498362Y466749D01*
X496972D01*
X496362Y466139D01*
Y464370D01*
X495752Y463760D01*
X493752D01*
X471579Y441587D01*
Y421025D01*
G01X486148Y412641D02*
Y415380D01*
X498668Y427900D01*
X505598D01*
X512515Y434817D01*
Y444930D01*
X517488Y449903D01*
X534083D01*
X570539Y486359D01*
Y510934D01*
X569416Y512057D01*
Y516307D01*
X570427Y517318D01*
Y529606D01*
X569533Y530500D01*
Y535341D01*
X570483Y536291D01*
Y548790D01*
X569416Y549857D01*
Y554107D01*
X570455Y555146D01*
Y567378D01*
X569589Y568244D01*
Y573196D01*
X570483Y574090D01*
Y586590D01*
X567266Y589807D01*
Y592324D01*
X568699Y593757D01*
G01X488648Y414333D02*
X500330Y426015D01*
X507307D01*
X514861Y433569D01*
Y443845D01*
X515471Y444455D01*
X516861D01*
X517471Y443845D01*
Y438919D01*
X518081Y438309D01*
X519471D01*
X520081Y438919D01*
Y446406D01*
X521510Y447835D01*
X535811D01*
X573266Y485290D01*
Y500474D01*
X573792Y501000D01*
Y508800D01*
X573266Y509326D01*
Y519100D01*
X573692Y519526D01*
Y528100D01*
X573266Y528526D01*
Y537700D01*
X573792Y538226D01*
Y546200D01*
X573266Y546726D01*
Y556574D01*
X573692Y557000D01*
Y565600D01*
X573266Y566026D01*
Y575500D01*
X573692Y575926D01*
Y584000D01*
X573266Y584426D01*
Y586443D01*
X571345Y588364D01*
Y588714D01*
G01X502951Y406743D02*
X503108Y406900D01*
X507332D01*
X531114Y430682D01*
X538214D01*
X590966Y483434D01*
Y491074D01*
X594066Y494174D01*
Y511157D01*
X593292Y511931D01*
Y516399D01*
X594455Y517562D01*
Y529377D01*
X593142Y530690D01*
Y535184D01*
X594287Y536329D01*
Y548736D01*
X593253Y549770D01*
Y554544D01*
X594201Y555492D01*
Y567462D01*
X593140Y568523D01*
Y573016D01*
X594034Y573910D01*
Y586639D01*
X591688Y588985D01*
Y593321D01*
X592124Y593757D01*
G01X504791Y404903D02*
X508477D01*
X515650Y412076D01*
X516512D01*
X517350Y411238D01*
X518212D01*
X519196Y412222D01*
Y413084D01*
X518358Y413922D01*
Y414784D01*
X519342Y415768D01*
X520204D01*
X521042Y414930D01*
X522004D01*
X522888Y415814D01*
Y416776D01*
X522050Y417614D01*
Y418476D01*
X532021Y428447D01*
X538886D01*
X596213Y485774D01*
Y487300D01*
X595813Y487700D01*
X593592D01*
X593092Y488200D01*
Y489800D01*
X593892Y490600D01*
X595712D01*
X596213Y491101D01*
Y508673D01*
X596866Y509326D01*
Y511373D01*
X597466Y511973D01*
Y516807D01*
X596916Y517357D01*
Y529816D01*
X597566Y530466D01*
Y535526D01*
X596866Y536226D01*
Y549457D01*
X597466Y550057D01*
Y554607D01*
X596916Y555157D01*
Y567647D01*
X597766Y568497D01*
Y573226D01*
X596766Y574226D01*
Y587470D01*
X595470Y588766D01*
Y588714D01*
G01X481148Y414587D02*
X481192Y414631D01*
Y439000D01*
X496792Y454600D01*
X531347D01*
X563806Y487059D01*
Y511057D01*
X563415Y511448D01*
Y516806D01*
X563806Y517197D01*
Y529586D01*
X563219Y530173D01*
Y535395D01*
X563722Y535898D01*
Y548901D01*
X563387Y549236D01*
Y554578D01*
X563966Y555157D01*
Y567325D01*
X562918Y568373D01*
Y572944D01*
X563916Y573942D01*
Y586457D01*
X560766Y589607D01*
Y592517D01*
X562006Y593757D01*
G01X483992Y414931D02*
Y429143D01*
X484602Y429753D01*
X486091D01*
X486701Y430363D01*
Y431753D01*
X486091Y432363D01*
X484602D01*
X483992Y432973D01*
Y438500D01*
X497692Y452200D01*
X532412D01*
X567205Y486993D01*
Y508513D01*
X566666Y509052D01*
Y511497D01*
X566992Y511823D01*
Y517131D01*
X566666Y517457D01*
Y519200D01*
X567092Y519626D01*
Y527500D01*
X566666Y527926D01*
Y529992D01*
X566916Y530242D01*
Y535192D01*
X566566Y535542D01*
Y537500D01*
X567092Y538026D01*
Y546100D01*
X566566Y546626D01*
Y548457D01*
X567092Y548983D01*
Y554831D01*
X566666Y555257D01*
Y557000D01*
X566992Y557326D01*
Y565600D01*
X566666Y565926D01*
Y567997D01*
X567166Y568497D01*
Y572656D01*
X566566Y573256D01*
Y575200D01*
X566992Y575626D01*
Y583700D01*
X566566Y584126D01*
Y587200D01*
X565052Y588714D01*
G01X499351Y410343D02*
X500208Y411200D01*
X505380D01*
X529276Y435096D01*
X536428D01*
X585933Y484601D01*
Y507941D01*
X587666Y509674D01*
Y511257D01*
X586866Y512057D01*
Y516957D01*
X587266Y517357D01*
Y519600D01*
X587092Y519774D01*
Y527700D01*
X587266Y527874D01*
Y529842D01*
X586866Y530242D01*
Y535674D01*
X587666Y536474D01*
Y538026D01*
X587092Y538600D01*
Y546300D01*
X587666Y546874D01*
Y549057D01*
X586592Y550131D01*
Y554099D01*
X587813Y555320D01*
Y556453D01*
X587092Y557174D01*
Y565600D01*
X587611Y566119D01*
Y567252D01*
X586393Y568470D01*
Y573201D01*
X587666Y574474D01*
Y575400D01*
X587092Y575974D01*
Y583900D01*
X588041Y584849D01*
Y585982D01*
X584766Y589257D01*
Y593092D01*
X585431Y593757D01*
G01X501126Y408568D02*
X501326Y408768D01*
X506074D01*
X530112Y432806D01*
X537322D01*
X588466Y483950D01*
Y492201D01*
X591158Y494893D01*
Y496184D01*
X590548Y496794D01*
X588525D01*
X587915Y497404D01*
Y499384D01*
X588525Y499994D01*
X591135D01*
X591745Y500604D01*
Y502584D01*
X591135Y503194D01*
X588552D01*
X587998Y503748D01*
Y505728D01*
X588664Y506394D01*
X590548D01*
X591158Y507004D01*
Y508208D01*
X590166Y509200D01*
Y511257D01*
X591066Y512157D01*
Y516557D01*
X590266Y517357D01*
Y519300D01*
X590492Y519526D01*
Y527700D01*
X590266Y527926D01*
Y529842D01*
X590966Y530542D01*
Y535323D01*
X589853Y536436D01*
Y538361D01*
X590492Y539000D01*
Y546300D01*
X589792Y547000D01*
Y548683D01*
X591066Y549957D01*
Y553925D01*
X589792Y555199D01*
Y557226D01*
X590492Y557926D01*
Y565400D01*
X590266Y565626D01*
Y567597D01*
X590832Y568163D01*
Y573461D01*
X590166Y574127D01*
Y575500D01*
X590492Y575826D01*
Y584000D01*
X590166Y584326D01*
Y587368D01*
X590123D01*
X588777Y588714D01*
G01X432577Y412574D02*
Y457017D01*
X454401Y478841D01*
Y483590D01*
X466050Y495239D01*
X467490Y498717D01*
X467813Y499497D01*
Y586915D01*
X466733Y587995D01*
Y589044D01*
X464877Y590900D01*
X464733D01*
G01X462690Y422000D02*
Y445398D01*
X492060Y474768D01*
X526783D01*
X541435Y489420D01*
Y587429D01*
X539992Y588872D01*
Y589263D01*
X538355Y590900D01*
G01X492348Y411515D02*
Y412556D01*
X502862Y423070D01*
X509196D01*
X523519Y437393D01*
Y443670D01*
X524669Y444820D01*
X537940D01*
X578246Y485126D01*
Y587820D01*
X575166Y590900D01*
G01X435267Y412574D02*
Y455875D01*
X458901Y479509D01*
Y480371D01*
X457895Y481377D01*
Y483117D01*
X459503Y484725D01*
X461243D01*
X462249Y483719D01*
X463111D01*
X464095Y484703D01*
Y485565D01*
X462978Y486682D01*
Y488381D01*
X464586Y489989D01*
X466367D01*
X467443Y488913D01*
X468305D01*
X470387Y490995D01*
Y508795D01*
X471853Y510261D01*
Y576231D01*
X471233Y576851D01*
Y577851D01*
X471853Y578471D01*
Y579471D01*
X471233Y580091D01*
Y581091D01*
X471853Y581711D01*
Y582711D01*
X471233Y583331D01*
Y584331D01*
X471853Y584951D01*
Y587594D01*
X470933Y588514D01*
X469832D01*
G01X465393Y422000D02*
Y445125D01*
X493050Y472782D01*
X510447D01*
X513324Y469905D01*
X515112D01*
X517459Y472252D01*
X520191D01*
X521421Y471022D01*
Y469508D01*
X522031Y468898D01*
X523421D01*
X524031Y469508D01*
Y471022D01*
X525261Y472252D01*
X527350D01*
X545475Y490377D01*
Y507226D01*
X545050Y507651D01*
Y508651D01*
X545475Y509076D01*
Y519324D01*
X544855Y519944D01*
Y520944D01*
X545475Y521564D01*
Y522564D01*
X544855Y523184D01*
Y524184D01*
X545475Y524804D01*
Y525804D01*
X544855Y526424D01*
Y527424D01*
X545475Y528044D01*
Y538014D01*
X544855Y538634D01*
Y539634D01*
X545475Y540254D01*
Y541254D01*
X544855Y541874D01*
Y542874D01*
X545475Y543494D01*
Y544494D01*
X544855Y545114D01*
Y546114D01*
X545475Y546734D01*
Y556955D01*
X544855Y557575D01*
Y558575D01*
X545475Y559195D01*
Y560195D01*
X544855Y560815D01*
Y561815D01*
X545475Y562435D01*
Y563435D01*
X544855Y564055D01*
Y565055D01*
X545475Y565675D01*
Y575841D01*
X544855Y576461D01*
Y577461D01*
X545475Y578081D01*
Y579081D01*
X544855Y579701D01*
Y580701D01*
X545475Y581321D01*
Y582321D01*
X544855Y582941D01*
Y583941D01*
X545475Y584561D01*
Y587386D01*
X544347Y588514D01*
X543455D01*
G01X494978Y410383D02*
Y411686D01*
X499412Y416120D01*
X501388D01*
X502191Y415317D01*
X503570D01*
X504552Y416299D01*
Y419801D01*
X505851Y421100D01*
X510644D01*
X526171Y436627D01*
Y441604D01*
X527373Y442806D01*
X529643D01*
X530901Y441548D01*
Y439424D01*
X531599Y438726D01*
X535597D01*
X582286Y485415D01*
Y506891D01*
X581666Y507511D01*
Y508511D01*
X582286Y509131D01*
Y518933D01*
X581666Y519553D01*
Y520553D01*
X582286Y521173D01*
Y522173D01*
X581666Y522793D01*
Y523793D01*
X582286Y524413D01*
Y525413D01*
X581666Y526033D01*
Y527033D01*
X582286Y527653D01*
Y538405D01*
X581666Y539025D01*
Y540025D01*
X582286Y540645D01*
Y541645D01*
X581666Y542265D01*
Y543265D01*
X582286Y543885D01*
Y544885D01*
X581666Y545505D01*
Y546505D01*
X582286Y547125D01*
Y557095D01*
X581666Y557715D01*
Y558715D01*
X582286Y559335D01*
Y560335D01*
X581666Y560955D01*
Y561955D01*
X582286Y562575D01*
Y563575D01*
X581666Y564195D01*
Y565195D01*
X582286Y565815D01*
Y576259D01*
X581666Y576879D01*
Y577879D01*
X582286Y578499D01*
Y579499D01*
X581666Y580119D01*
Y581119D01*
X582286Y581739D01*
Y582739D01*
X581666Y583359D01*
Y584359D01*
X582286Y584979D01*
Y587593D01*
X581365Y588514D01*
X580266D01*
G01X431517Y412574D02*
Y457457D01*
X453341Y479281D01*
Y484030D01*
X465150Y495840D01*
X465951Y497774D01*
X466342Y498717D01*
X466753Y499708D01*
Y563854D01*
X466301Y564306D01*
Y565306D01*
X466753Y565758D01*
Y576050D01*
X466259Y576544D01*
Y577544D01*
X466753Y578038D01*
Y579164D01*
X466133Y579784D01*
Y580784D01*
X466753Y581404D01*
Y582404D01*
X466133Y583024D01*
Y584024D01*
X466753Y584644D01*
Y586474D01*
X464927Y588300D01*
X464732D01*
G01X461630Y422000D02*
Y445838D01*
X491620Y475828D01*
X526343D01*
X540375Y489860D01*
Y576310D01*
X539923Y576762D01*
Y577762D01*
X540375Y578214D01*
Y579368D01*
X539755Y579988D01*
Y580988D01*
X540375Y581608D01*
Y582608D01*
X539755Y583228D01*
Y584228D01*
X540375Y584848D01*
Y586986D01*
X539061Y588300D01*
X538355D01*
G01X491288Y411515D02*
Y412996D01*
X502422Y424130D01*
X508756D01*
X522459Y437833D01*
Y444110D01*
X524229Y445880D01*
X537500D01*
X577186Y485566D01*
Y576325D01*
X576804Y576707D01*
Y577707D01*
X577186Y578089D01*
Y579285D01*
X576566Y579905D01*
Y580905D01*
X577186Y581525D01*
Y582637D01*
X576678Y583145D01*
Y584145D01*
X577186Y584653D01*
Y587380D01*
X576266Y588300D01*
X575166D01*
G01X436327Y412574D02*
Y455435D01*
X459961Y479069D01*
Y480811D01*
X458955Y481817D01*
Y482677D01*
X459943Y483665D01*
X460803D01*
X461809Y482659D01*
X463551D01*
X465155Y484263D01*
Y486005D01*
X464038Y487122D01*
Y487941D01*
X465026Y488929D01*
X465927D01*
X467003Y487853D01*
X468745D01*
X471447Y490555D01*
Y508355D01*
X472913Y509821D01*
Y588034D01*
X469833Y591114D01*
X469832D01*
G01X466453Y422000D02*
Y444685D01*
X493490Y471722D01*
X510007D01*
X512884Y468845D01*
X515552D01*
X517899Y471192D01*
X519751D01*
X520361Y470582D01*
Y469068D01*
X521591Y467838D01*
X523861D01*
X525091Y469068D01*
Y470582D01*
X525701Y471192D01*
X527790D01*
X546535Y489937D01*
Y587829D01*
X544992Y589372D01*
Y589577D01*
X543455Y591114D01*
G01X469079Y421025D02*
Y442487D01*
X495325Y468733D01*
X509719D01*
X512514Y465938D01*
X525225D01*
X547574Y488287D01*
X548492D01*
X548992Y488787D01*
Y493900D01*
X550192Y495100D01*
Y497378D01*
X550453Y497639D01*
Y511659D01*
X550055Y512057D01*
Y516957D01*
X550455Y517357D01*
Y529842D01*
X550055Y530242D01*
Y535762D01*
X550509Y536216D01*
Y548983D01*
X550090Y549402D01*
Y554398D01*
X550655Y554963D01*
Y567397D01*
X550006Y568046D01*
Y573393D01*
X550508Y573895D01*
Y586704D01*
X548301Y588911D01*
Y593438D01*
X548620Y593757D01*
G01X438187Y510114D02*
Y512495D01*
X439992Y514300D01*
Y516400D01*
X439692Y516700D01*
Y519100D01*
X439825Y519233D01*
Y530067D01*
X439592Y530300D01*
Y535554D01*
X438189Y536957D01*
G01X428147Y512792D02*
X426692Y514247D01*
Y516610D01*
X426192Y517110D01*
Y519000D01*
X426543Y519351D01*
Y535351D01*
X428149Y536957D01*
G01X421454Y518157D02*
X420593D01*
X419762Y518988D01*
Y520433D01*
X420754Y521425D01*
X423341D01*
X424711Y522795D01*
Y524891D01*
X423728Y525874D01*
X422521D01*
X421272Y524625D01*
X420122D01*
X419032Y525715D01*
Y526598D01*
X421456Y529022D01*
G01X434840Y512792D02*
Y513548D01*
X435679Y514387D01*
Y515797D01*
X437859Y517977D01*
Y519041D01*
X437251Y519649D01*
X436140D01*
X435524Y520265D01*
Y521544D01*
X436162Y522182D01*
X437157D01*
X437740Y522765D01*
Y523755D01*
X437103Y524392D01*
X436092D01*
X435482Y525002D01*
Y526835D01*
X436475Y527828D01*
Y535324D01*
X434842Y536957D01*
G01X438189Y547922D02*
X438187Y547924D01*
Y553187D01*
X436578Y554796D01*
Y560475D01*
X437421Y561318D01*
Y564830D01*
X436578Y565673D01*
Y567910D01*
X438187Y569519D01*
Y574755D01*
X438189Y574757D01*
G01X428149Y547922D02*
X429878Y549651D01*
Y557114D01*
X429761Y557231D01*
Y568069D01*
X428147Y569683D01*
Y574755D01*
X428149Y574757D01*
G01X421456Y555857D02*
Y557122D01*
X422066Y557732D01*
X425762D01*
X426393Y558363D01*
Y559353D01*
X425804Y559942D01*
X422066D01*
X421456Y560552D01*
Y561542D01*
X422066Y562152D01*
X425908D01*
X426518Y562762D01*
Y563752D01*
X425908Y564362D01*
X422066D01*
X421456Y564972D01*
Y566822D01*
G01X434842Y547922D02*
X435232Y548312D01*
Y552968D01*
X433119Y555081D01*
Y560321D01*
X433236Y560438D01*
Y567556D01*
X435271Y569591D01*
Y572321D01*
X434842Y572750D01*
Y574757D01*
G01X438187Y609864D02*
Y607405D01*
X440692Y604900D01*
Y595500D01*
X439810Y594618D01*
Y589518D01*
X438187Y587895D01*
Y585724D01*
X438189Y585722D01*
G01X428149D02*
Y590657D01*
X429864Y592372D01*
Y595028D01*
X428692Y596200D01*
Y604800D01*
X430011Y606119D01*
Y608381D01*
X428147Y610245D01*
Y612657D01*
G01X434842Y585722D02*
Y587910D01*
X435270Y588338D01*
Y590624D01*
X433126Y592768D01*
Y594934D01*
X433414Y595222D01*
Y605678D01*
X433038Y606054D01*
Y608446D01*
X434840Y610248D01*
Y612657D01*
G01X458266Y593757D02*
X456561Y595462D01*
Y607115D01*
X459746Y610300D01*
X460912D01*
G01Y588714D02*
X460824D01*
X459138Y590400D01*
Y592092D01*
X460045Y592999D01*
Y594592D01*
X458901Y595736D01*
Y597156D01*
X459745Y598000D01*
Y599700D01*
X458901Y600544D01*
Y601756D01*
X459845Y602700D01*
Y603900D01*
X459246Y604499D01*
X458266D01*
G01X451573Y593757D02*
X449868Y595462D01*
Y605435D01*
X450490Y606057D01*
Y607245D01*
X453545Y610300D01*
X454533D01*
G01X454619Y588714D02*
X454531D01*
X452845Y590400D01*
Y592600D01*
X453345Y593100D01*
Y594999D01*
X452208Y596136D01*
Y597464D01*
X453145Y598401D01*
Y599799D01*
X452208Y600736D01*
Y601964D01*
X453245Y603001D01*
Y603899D01*
X452645Y604499D01*
X451573D01*
G01X474998Y593757D02*
X473293Y595462D01*
Y605649D01*
X478344Y610700D01*
G01Y588714D02*
X478256D01*
X476570Y590400D01*
Y592092D01*
X476745Y592267D01*
Y594900D01*
X475633Y596012D01*
Y597088D01*
X476645Y598100D01*
Y599300D01*
X475818Y600126D01*
X475633Y600312D01*
Y601388D01*
X476770Y602525D01*
Y603799D01*
X476070Y604499D01*
X474998D01*
G01X464732Y590900D02*
X464733D01*
G01D02*
X466445Y592612D01*
Y594200D01*
X465345Y595300D01*
X464395D01*
X463805Y595890D01*
Y597260D01*
X464325Y597780D01*
X464935D01*
X465545Y598390D01*
Y599780D01*
X464935Y600390D01*
X464355D01*
X463805Y600940D01*
Y602360D01*
X464445Y603000D01*
X465725D01*
X466464Y603739D01*
Y605644D01*
X464758Y607350D01*
G01X469832Y588514D02*
X469678D01*
X468127Y590065D01*
Y594901D01*
X467298Y595730D01*
Y602270D01*
X468127Y603099D01*
Y608236D01*
X469640Y609749D01*
X469832D01*
G01X464732Y588300D02*
X464445D01*
X464218Y588526D01*
X462745Y590000D01*
Y608012D01*
X464732Y609999D01*
G01X469832Y591114D02*
X471545Y592827D01*
Y594500D01*
X470868Y595176D01*
X470545Y595500D01*
X469029D01*
X468358Y596171D01*
Y597448D01*
X468810Y597900D01*
X469145D01*
X469845Y598600D01*
Y599688D01*
X469135Y600398D01*
X468898D01*
X468358Y600938D01*
Y601829D01*
X469129Y602600D01*
X470645D01*
X471645Y603600D01*
Y605328D01*
X469833Y607140D01*
G01X495077Y27899D02*
Y30021D01*
X496956Y31900D01*
X498356D01*
X499812Y33356D01*
Y34700D01*
X499196Y35316D01*
Y48441D01*
X497723Y49914D01*
G01X521848D02*
X523237Y48525D01*
Y35512D01*
X523849Y34900D01*
Y33500D01*
X522049Y31700D01*
X521049D01*
X519749Y30400D01*
Y29146D01*
X518502Y27899D01*
G01X491430Y49914D02*
X492656Y48688D01*
Y35675D01*
X493431Y34900D01*
Y33276D01*
X491855Y31700D01*
X490631D01*
X489492Y30561D01*
Y29007D01*
X488384Y27899D01*
G01X511809D02*
X513056Y29146D01*
Y30400D01*
X514356Y31700D01*
X515356D01*
X517156Y33500D01*
Y34900D01*
X516544Y35512D01*
Y48525D01*
X515155Y49914D01*
G01X501543Y52100D02*
X504650Y48993D01*
Y32848D01*
X503322Y31520D01*
X502339D01*
X501569Y30750D01*
G01X501543Y33399D02*
X502362Y32580D01*
X502879D01*
X503590Y33291D01*
Y36580D01*
X501670Y38500D01*
Y39500D01*
X502270Y40100D01*
X502770D01*
X503590Y40920D01*
Y41880D01*
X502870Y42600D01*
X502158D01*
X501656Y43102D01*
Y44434D01*
X502272Y45050D01*
X502620D01*
X503590Y46020D01*
Y48552D01*
X502642Y49500D01*
X501544D01*
G01X506643Y30540D02*
X506644D01*
X509836Y33732D01*
Y49121D01*
X506643Y52314D01*
G01X481691Y17157D02*
X480570Y16036D01*
Y13100D01*
X483912Y9758D01*
Y8700D01*
X482112Y6900D01*
Y5325D01*
X483312Y4125D01*
Y2999D01*
X482112Y1799D01*
Y426D01*
X483470Y-932D01*
Y-2133D01*
X485037Y-3700D01*
G01Y12114D02*
X486426Y10725D01*
Y-2288D01*
X487038Y-2900D01*
Y-4300D01*
X485238Y-6100D01*
X484238D01*
X482938Y-7400D01*
Y-8654D01*
X481691Y-9901D01*
G01X495077Y17157D02*
X493956Y16036D01*
Y13100D01*
X496856Y10200D01*
Y8232D01*
X495323Y6699D01*
Y5500D01*
X496573Y4250D01*
Y3350D01*
X495223Y2000D01*
Y701D01*
X496856Y-932D01*
Y-3233D01*
X497723Y-4100D01*
G01Y12114D02*
X499196Y10641D01*
Y-2484D01*
X499812Y-3100D01*
Y-4444D01*
X498356Y-5900D01*
X496956D01*
X495077Y-7779D01*
Y-9901D01*
G01X518502Y17157D02*
X517381Y16036D01*
Y13100D01*
X520723Y9758D01*
Y8700D01*
X518923Y6900D01*
Y5325D01*
X520123Y4125D01*
Y2999D01*
X518923Y1799D01*
Y426D01*
X520281Y-932D01*
Y-2133D01*
X521848Y-3700D01*
G01X518502Y-9901D02*
X519749Y-8654D01*
Y-7400D01*
X521049Y-6100D01*
X522049D01*
X523849Y-4300D01*
Y-2900D01*
X523237Y-2288D01*
Y10725D01*
X521848Y12114D01*
G01X488384Y17157D02*
X487456Y16229D01*
Y13101D01*
X490256Y10301D01*
Y8432D01*
X488873Y7049D01*
Y5650D01*
X490323Y4200D01*
Y3000D01*
X488823Y1500D01*
Y301D01*
X490256Y-1132D01*
Y-3012D01*
X491344Y-4100D01*
G01X491430Y12114D02*
X492656Y10888D01*
Y-2125D01*
X493431Y-2900D01*
Y-4524D01*
X491855Y-6100D01*
X490631D01*
X488384Y-8347D01*
Y-9901D01*
G01X511809Y17157D02*
X510881Y16229D01*
Y13101D01*
X513923Y10059D01*
Y8674D01*
X512248Y6999D01*
Y5876D01*
X513748Y4376D01*
Y3024D01*
X512248Y1524D01*
Y301D01*
X513681Y-1132D01*
Y-2226D01*
X515155Y-3700D01*
G01Y12114D02*
X516544Y10725D01*
Y-2288D01*
X517156Y-2900D01*
Y-4300D01*
X515356Y-6100D01*
X514356D01*
X513056Y-7400D01*
Y-8654D01*
X511809Y-9901D01*
G01X531888Y17157D02*
X530767Y16036D01*
Y13100D01*
X533667Y10200D01*
Y8232D01*
X532134Y6699D01*
Y5500D01*
X533384Y4250D01*
Y3350D01*
X532034Y2000D01*
Y701D01*
X533667Y-932D01*
Y-3233D01*
X534534Y-4100D01*
G01Y12114D02*
X536007Y10641D01*
Y-2484D01*
X536623Y-3100D01*
Y-4444D01*
X535167Y-5900D01*
X533767D01*
X531888Y-7779D01*
Y-9901D01*
G01X525195Y17157D02*
X524267Y16229D01*
Y13101D01*
X527067Y10301D01*
Y8432D01*
X525684Y7049D01*
Y5650D01*
X527134Y4200D01*
Y3000D01*
X525634Y1500D01*
Y301D01*
X527067Y-1132D01*
Y-3012D01*
X528155Y-4100D01*
G01X528241Y12114D02*
X529467Y10888D01*
Y-2125D01*
X530242Y-2900D01*
Y-4524D01*
X528666Y-6100D01*
X527442D01*
X525195Y-8347D01*
Y-9901D01*
G01X501544Y14300D02*
X504650Y11194D01*
Y-4952D01*
X503322Y-6280D01*
X502340D01*
X501570Y-7050D01*
G01X538355Y14300D02*
X541461Y11194D01*
Y-4952D01*
X540133Y-6280D01*
X539151D01*
X538381Y-7050D01*
G01X506644Y14514D02*
X509836Y11322D01*
Y-4068D01*
X506644Y-7260D01*
G01X501544Y11700D02*
X502643D01*
X503590Y10753D01*
Y8220D01*
X502620Y7250D01*
X502272D01*
X501656Y6634D01*
Y5302D01*
X502158Y4800D01*
X502870D01*
X503590Y4080D01*
Y3120D01*
X502770Y2300D01*
X502270D01*
X501670Y1700D01*
Y700D01*
X503590Y-1220D01*
Y-4509D01*
X502879Y-5220D01*
X502363D01*
X501544Y-4401D01*
G01X538355Y11700D02*
X539454D01*
X540401Y10753D01*
Y8220D01*
X539431Y7250D01*
X539083D01*
X538467Y6634D01*
Y5302D01*
X538969Y4800D01*
X539681D01*
X540401Y4080D01*
Y3120D01*
X539581Y2300D01*
X539081D01*
X538481Y1700D01*
Y700D01*
X540401Y-1220D01*
Y-4509D01*
X539690Y-5220D01*
X539174D01*
X538355Y-4401D01*
G01X506644Y11914D02*
Y11915D01*
X507742D01*
X508776Y10881D01*
Y8106D01*
X508070Y7400D01*
X507556D01*
X506856Y6700D01*
Y5700D01*
X507556Y5000D01*
X508056D01*
X508776Y4280D01*
Y2907D01*
X507969Y2100D01*
X507271D01*
X506670Y1499D01*
Y301D01*
X507271Y-300D01*
X508069D01*
X508776Y-1007D01*
Y-3628D01*
X507753Y-4651D01*
X506644D01*
G01X494927Y112357D02*
X495077Y112207D01*
Y106915D01*
X496886Y105106D01*
Y92094D01*
X495486Y90694D01*
Y86874D01*
X496886Y85474D01*
Y84000D01*
X496592Y83706D01*
Y75200D01*
X496886Y74906D01*
Y73195D01*
X495886Y72195D01*
Y67307D01*
X496986Y66207D01*
Y64579D01*
X495077Y62670D01*
Y54957D01*
G01D02*
X493956Y53836D01*
Y50900D01*
X496856Y48000D01*
Y46032D01*
X495323Y44499D01*
Y43300D01*
X496573Y42050D01*
Y41150D01*
X495223Y39800D01*
Y38501D01*
X496856Y36868D01*
Y34567D01*
X497723Y33700D01*
G01Y49914D02*
X495992Y51645D01*
Y53300D01*
X497066Y54374D01*
Y61339D01*
X499586Y63859D01*
Y74594D01*
X500192Y75200D01*
Y83294D01*
X499586Y83900D01*
Y105101D01*
X497723Y106964D01*
G01X518502Y54957D02*
X520466Y56921D01*
Y66579D01*
X519786Y67259D01*
Y72595D01*
X520586Y73395D01*
Y74706D01*
X519792Y75500D01*
Y83306D01*
X520586Y84100D01*
Y85774D01*
X519986Y86374D01*
Y91374D01*
X520486Y91874D01*
Y104906D01*
X518317Y107075D01*
Y112357D01*
G01X521848Y34100D02*
X520281Y35667D01*
Y36868D01*
X518923Y38226D01*
Y39599D01*
X520123Y40799D01*
Y41925D01*
X518923Y43125D01*
Y44700D01*
X520723Y46500D01*
Y47558D01*
X517381Y50900D01*
Y53836D01*
X518502Y54957D01*
G01X521113Y106964D02*
X523086Y104991D01*
Y91854D01*
X523786Y91154D01*
Y86494D01*
X523086Y85794D01*
Y84200D01*
X523692Y83594D01*
Y75600D01*
X523086Y74994D01*
Y73307D01*
X523686Y72707D01*
Y66879D01*
X523120Y66313D01*
Y56798D01*
X519892Y53570D01*
Y51870D01*
X521848Y49914D01*
G01X488384Y54957D02*
Y61457D01*
X490286Y63359D01*
Y66307D01*
X489486Y67107D01*
Y72159D01*
X490286Y72959D01*
Y74706D01*
X489692Y75300D01*
Y83406D01*
X490286Y84000D01*
Y85574D01*
X489486Y86374D01*
Y90974D01*
X490492Y91980D01*
Y105300D01*
X488634Y107158D01*
Y112357D01*
G01X491344Y33700D02*
X490256Y34788D01*
Y36636D01*
X488392Y38500D01*
Y39301D01*
X490323Y41232D01*
Y41968D01*
X488392Y43899D01*
Y44500D01*
X490256Y46364D01*
Y48101D01*
X489092Y49265D01*
Y54249D01*
X488384Y54957D01*
G01X491430Y106964D02*
X493086Y105308D01*
Y91474D01*
X493386Y91174D01*
Y86474D01*
X492986Y86074D01*
Y84006D01*
X493492Y83500D01*
Y75200D01*
X492986Y74694D01*
Y72959D01*
X493286Y72659D01*
Y67359D01*
X492986Y67059D01*
Y63022D01*
X491266Y61302D01*
Y57126D01*
X491430Y56962D01*
Y49914D01*
G01X515155Y34100D02*
X513681Y35574D01*
Y36668D01*
X512248Y38101D01*
Y39324D01*
X513748Y40824D01*
Y42176D01*
X512248Y43676D01*
Y44799D01*
X513923Y46474D01*
Y47859D01*
X510881Y50901D01*
Y54029D01*
X511809Y54957D01*
G01D02*
X513786Y56934D01*
Y66339D01*
X512986Y67139D01*
Y72295D01*
X513686Y72995D01*
Y74906D01*
X512992Y75600D01*
Y83206D01*
X513686Y83900D01*
Y86074D01*
X512986Y86774D01*
Y91074D01*
X514086Y92174D01*
Y104907D01*
X512024Y106969D01*
Y112357D01*
G01X515155Y49914D02*
X513316Y51753D01*
Y53594D01*
X515986Y56264D01*
Y65859D01*
X517186Y67059D01*
Y72159D01*
X516686Y72659D01*
Y74894D01*
X517092Y75300D01*
Y83494D01*
X516686Y83900D01*
Y86074D01*
X517286Y86674D01*
Y91012D01*
X516292Y92006D01*
Y105492D01*
X514820Y106964D01*
G01X501544Y110514D02*
X504561Y107497D01*
Y83669D01*
X503592Y82700D01*
Y76001D01*
X504561Y75032D01*
Y62169D01*
X502561Y60169D01*
Y56781D01*
X503270Y56072D01*
Y53827D01*
X501543Y52100D01*
G01X506643Y33149D02*
X507753D01*
X508776Y34172D01*
Y36793D01*
X508069Y37500D01*
X507271D01*
X506670Y38101D01*
Y39299D01*
X507271Y39900D01*
X507969D01*
X508776Y40707D01*
Y42080D01*
X508056Y42800D01*
X507556D01*
X506856Y43500D01*
Y44500D01*
X507556Y45200D01*
X508070D01*
X508776Y45906D01*
Y48681D01*
X507742Y49715D01*
X506643D01*
G01Y49714D02*
Y49715D01*
G01D02*
X504920Y51438D01*
Y55739D01*
X506701Y57520D01*
Y58192D01*
X508601Y60092D01*
Y105698D01*
X506644Y107655D01*
G01X501570Y107865D02*
X503501Y105934D01*
Y84109D01*
X502532Y83140D01*
Y75561D01*
X503501Y74592D01*
Y62609D01*
X501501Y60609D01*
Y57320D01*
X499570Y55389D01*
Y51474D01*
X501544Y49500D01*
G01D02*
X501543D01*
G01X506643Y52314D02*
X508492Y54163D01*
Y55889D01*
X507761Y56620D01*
Y57749D01*
X509661Y59649D01*
Y107247D01*
X506670Y110238D01*
Y110264D01*
G01X493692Y204500D02*
X500292Y197900D01*
X511992D01*
X533766Y176126D01*
X537766D01*
X593492Y120400D01*
Y111125D01*
X594052Y110565D01*
X595432D01*
X595992Y110005D01*
Y108565D01*
X595432Y108005D01*
X594052D01*
X593492Y107445D01*
Y106005D01*
X594052Y105445D01*
X595432D01*
X595992Y104885D01*
Y103445D01*
X595432Y102885D01*
X594052D01*
X593492Y102325D01*
Y100885D01*
X594052Y100325D01*
X595432D01*
X595992Y99765D01*
Y98325D01*
X595432Y97765D01*
X594052D01*
X593492Y97205D01*
Y95548D01*
X594466Y94574D01*
Y92238D01*
X593466Y91238D01*
Y86414D01*
X594066Y85814D01*
Y84100D01*
X593592Y83626D01*
Y75100D01*
X594066Y74626D01*
Y73175D01*
X593566Y72675D01*
Y67075D01*
X594416Y66225D01*
Y54264D01*
X593466Y53314D01*
Y48374D01*
X594066Y47774D01*
Y46174D01*
X593592Y45700D01*
Y37574D01*
X594066Y37100D01*
Y35175D01*
X593566Y34675D01*
Y28999D01*
X594366Y28199D01*
Y19399D01*
X592124Y17157D01*
G01X495392Y205500D02*
X500592Y200300D01*
X512792D01*
X534592Y178500D01*
X538892D01*
X598792Y118600D01*
Y95500D01*
X596966Y93674D01*
Y91874D01*
X597566Y91274D01*
Y86614D01*
X596866Y85914D01*
Y84100D01*
X597392Y83574D01*
Y75400D01*
X596866Y74874D01*
Y73127D01*
X597466Y72527D01*
Y67049D01*
X596916Y66499D01*
Y53864D01*
X597566Y53214D01*
Y48638D01*
X596866Y47938D01*
Y46226D01*
X597692Y45400D01*
Y37726D01*
X596866Y36900D01*
Y35227D01*
X597466Y34627D01*
Y29249D01*
X596916Y28699D01*
Y18964D01*
X593566Y15614D01*
Y14018D01*
X595470Y12114D01*
G01X491842Y200450D02*
X499092Y193200D01*
X510292D01*
X535530Y167962D01*
X539630D01*
X585966Y121626D01*
Y118577D01*
X586526Y118017D01*
X588432D01*
X588992Y117457D01*
Y116017D01*
X588432Y115457D01*
X586526D01*
X585966Y114897D01*
Y113457D01*
X586526Y112897D01*
X588432D01*
X588992Y112337D01*
Y110897D01*
X588432Y110337D01*
X586526D01*
X585966Y109777D01*
Y108337D01*
X586526Y107777D01*
X588432D01*
X588992Y107217D01*
Y105777D01*
X588432Y105217D01*
X586526D01*
X585966Y104657D01*
Y102127D01*
X587266Y100827D01*
Y91614D01*
X586866Y91214D01*
Y86514D01*
X587666Y85714D01*
Y84100D01*
X587092Y83526D01*
Y75500D01*
X587666Y74926D01*
Y73375D01*
X586866Y72575D01*
Y66975D01*
X587266Y66575D01*
Y53814D01*
X586866Y53414D01*
Y48714D01*
X587666Y47914D01*
Y46400D01*
X586892Y45626D01*
Y37600D01*
X587666Y36826D01*
Y35401D01*
X586866Y34601D01*
Y29099D01*
X587466Y28499D01*
Y19192D01*
X585431Y17157D01*
G01X492592Y202800D02*
X499792Y195600D01*
X511291D01*
X535292Y171599D01*
X539092D01*
X590992Y119699D01*
Y94393D01*
X590273Y93674D01*
Y91874D01*
X590873Y91274D01*
Y86614D01*
X590173Y85914D01*
Y84100D01*
X590699Y83574D01*
Y75400D01*
X590173Y74874D01*
Y73127D01*
X590773Y72527D01*
Y67049D01*
X590223Y66499D01*
Y53864D01*
X590873Y53214D01*
Y48638D01*
X590173Y47938D01*
Y46226D01*
X590999Y45400D01*
Y37726D01*
X590173Y36900D01*
Y35227D01*
X590773Y34627D01*
Y29249D01*
X590223Y28699D01*
Y18964D01*
X586873Y15614D01*
Y14018D01*
X588777Y12114D01*
G01X486542Y195950D02*
X487389Y195103D01*
X488026D01*
X488734Y194395D01*
Y193758D01*
X489441Y193051D01*
X490148D01*
X490856Y192344D01*
Y191636D01*
X491563Y190929D01*
X492270D01*
X492978Y190222D01*
Y189514D01*
X493685Y188807D01*
X494392D01*
X495100Y188100D01*
Y187392D01*
X496432Y186060D01*
X497432D01*
X497932Y186560D01*
X498932D01*
X499432Y186060D01*
X500492D01*
X500992Y186560D01*
X501992D01*
X502492Y186060D01*
X503992D01*
X504492Y186560D01*
X505492D01*
X505992Y186060D01*
X509232D01*
X510134Y185158D01*
X510842D01*
X511550Y184450D01*
Y183742D01*
X512384Y182908D01*
X513092D01*
X513800Y182200D01*
Y181492D01*
X514507Y180785D01*
Y180783D01*
X533192Y162100D01*
X537392D01*
X575972Y123520D01*
Y117202D01*
X576841Y116333D01*
X578460D01*
X579952Y114841D01*
Y111465D01*
X578460Y109973D01*
X576741D01*
X575872Y109104D01*
Y106605D01*
X576744Y105733D01*
X577880D01*
X579472Y104141D01*
Y102285D01*
X577361Y100174D01*
Y98427D01*
X579362Y96426D01*
Y94841D01*
X578246Y93725D01*
Y48213D01*
X578696Y47763D01*
Y46763D01*
X578246Y46313D01*
Y44418D01*
X578696Y43968D01*
Y42968D01*
X578246Y42518D01*
Y41126D01*
X578696Y40676D01*
Y39676D01*
X578246Y39226D01*
Y24562D01*
X574372Y20688D01*
Y19620D01*
X575092Y18900D01*
X576092D01*
X576892Y18100D01*
Y16026D01*
X575166Y14300D01*
G01X487792Y200400D02*
X496987Y191205D01*
X509087D01*
X534732Y165560D01*
X538332D01*
X583346Y120546D01*
Y26134D01*
X583966Y25514D01*
Y24682D01*
X582630Y23346D01*
Y22470D01*
X581922Y21762D01*
X581046D01*
X580072Y20788D01*
Y19920D01*
X582092Y17900D01*
Y16340D01*
X580266Y14514D01*
G01X487042Y199650D02*
X496547Y190145D01*
X498210D01*
X498660Y189695D01*
X499660D01*
X500110Y190145D01*
X501947D01*
X502397Y189695D01*
X503397D01*
X503847Y190145D01*
X508647D01*
X534292Y164500D01*
X537892D01*
X582286Y120106D01*
Y24505D01*
X579012Y21231D01*
Y18719D01*
X578542Y18249D01*
Y13638D01*
X580266Y11914D01*
G01X496038Y410383D02*
Y411246D01*
X499852Y415060D01*
X500948D01*
X501751Y414257D01*
X504010D01*
X505612Y415859D01*
Y419361D01*
X506291Y420040D01*
X511084D01*
X527231Y436187D01*
Y441164D01*
X527813Y441746D01*
X529203D01*
X529841Y441108D01*
Y438984D01*
X531159Y437666D01*
X536037D01*
X583346Y484975D01*
Y588034D01*
X580266Y591114D01*
G01X494777Y498487D02*
Y504999D01*
X497144Y507366D01*
Y510707D01*
X495794Y512057D01*
Y516307D01*
X496944Y517457D01*
Y519400D01*
X496792Y519552D01*
Y527900D01*
X496944Y528052D01*
Y529447D01*
X495844Y530547D01*
Y535353D01*
X496994Y536503D01*
Y537600D01*
X496792Y537802D01*
Y546300D01*
X496994Y546502D01*
Y548657D01*
X493644Y552007D01*
Y554524D01*
X495077Y555957D01*
G01X497723Y550914D02*
Y550564D01*
X499644Y548643D01*
Y546548D01*
X500092Y546100D01*
Y538148D01*
X499644Y537700D01*
Y528348D01*
X500092Y527900D01*
Y519048D01*
X499644Y518600D01*
Y506330D01*
X497066Y503752D01*
Y495274D01*
X495766Y493974D01*
Y492851D01*
X497723Y490894D01*
G01X517902Y498487D02*
Y506611D01*
X520444Y509153D01*
Y511157D01*
X519944Y511657D01*
Y517057D01*
X520744Y517857D01*
Y519200D01*
X520192Y519752D01*
Y527800D01*
X520744Y528352D01*
Y529497D01*
X519644Y530597D01*
Y535342D01*
X520544Y536242D01*
Y537700D01*
X520192Y538052D01*
Y546200D01*
X520544Y546552D01*
Y548707D01*
X517144Y552107D01*
Y554599D01*
X518502Y555957D01*
G01X521048Y493844D02*
Y501456D01*
X523592Y504000D01*
Y509000D01*
X523244Y509348D01*
Y511657D01*
X523844Y512257D01*
Y516807D01*
X523294Y517357D01*
Y519300D01*
X523492Y519498D01*
Y527800D01*
X523294Y527998D01*
Y529847D01*
X524144Y530697D01*
Y535348D01*
X523144Y536348D01*
Y537600D01*
X523492Y537948D01*
Y545900D01*
X523144Y546248D01*
Y549670D01*
X521848Y550966D01*
Y550914D01*
G01X488384Y498487D02*
X490092Y500195D01*
Y508699D01*
X490444Y509051D01*
Y510757D01*
X489444Y511757D01*
Y516457D01*
X490344Y517357D01*
Y519600D01*
X490092Y519852D01*
Y528000D01*
X490344Y528252D01*
Y529449D01*
X489296Y530497D01*
Y535144D01*
X490294Y536142D01*
Y537800D01*
X490092Y538002D01*
Y546400D01*
X490294Y546602D01*
Y549186D01*
X488380Y551100D01*
G01X491430Y550914D02*
X492944Y549400D01*
Y546548D01*
X493392Y546100D01*
Y538048D01*
X492944Y537600D01*
Y535456D01*
X493544Y534856D01*
Y530697D01*
X493044Y530197D01*
Y528148D01*
X493392Y527800D01*
Y519448D01*
X493044Y519100D01*
Y517457D01*
X493294Y517207D01*
Y511007D01*
X492944Y510657D01*
Y499630D01*
X492377Y499063D01*
Y495215D01*
X493266Y494326D01*
Y492980D01*
X491430Y491144D01*
G01X511809Y498487D02*
X512266Y498944D01*
Y507774D01*
X514044Y509552D01*
Y511257D01*
X513244Y512057D01*
Y516957D01*
X513844Y517557D01*
Y519500D01*
X513492Y519852D01*
Y527800D01*
X513844Y528152D01*
Y529597D01*
X512771Y530670D01*
Y535169D01*
X514044Y536442D01*
Y537600D01*
X513492Y538152D01*
Y546600D01*
X514044Y547152D01*
Y548557D01*
X511144Y551457D01*
Y555292D01*
X511809Y555957D01*
G01X515155Y550914D02*
X516501Y549568D01*
X516544D01*
Y546448D01*
X516792Y546200D01*
Y538048D01*
X516544Y537800D01*
Y536247D01*
X517210Y535581D01*
Y530363D01*
X516644Y529797D01*
Y527948D01*
X516892Y527700D01*
Y519748D01*
X516344Y519200D01*
Y517657D01*
X517444Y516557D01*
Y512157D01*
X516544Y511257D01*
Y509248D01*
X514866Y507570D01*
Y493855D01*
X514755Y493744D01*
G01X501544Y553100D02*
X501688D01*
X503292Y551496D01*
Y550446D01*
X504624Y549114D01*
Y504632D01*
X502892Y502900D01*
Y500400D01*
X503292Y500000D01*
Y497944D01*
X501560Y496212D01*
Y496167D01*
G01X506644Y550714D02*
X507378D01*
X508664Y549428D01*
Y505073D01*
X506432Y502841D01*
Y501040D01*
X504892Y499500D01*
Y495319D01*
X506644Y493567D01*
G01X501544Y550500D02*
X501738D01*
X503564Y548674D01*
Y505072D01*
X501832Y503340D01*
Y501940D01*
X499836Y499944D01*
Y495191D01*
X501560Y493467D01*
G01X506644Y553314D02*
X508392Y551566D01*
Y551200D01*
X509724Y549868D01*
Y504633D01*
X507492Y502401D01*
Y500400D01*
X508392Y499500D01*
Y497915D01*
X506644Y496167D01*
G01X481691Y593757D02*
X479986Y595462D01*
Y605649D01*
X485037Y610700D01*
G01Y588714D02*
X484949D01*
X483263Y590400D01*
Y592092D01*
X483438Y592267D01*
Y594900D01*
X482326Y596012D01*
Y597088D01*
X483338Y598100D01*
Y599300D01*
X482326Y600312D01*
Y601388D01*
X483463Y602525D01*
Y603799D01*
X482763Y604499D01*
X481691D01*
G01X498092Y611200D02*
X493372Y606480D01*
Y595462D01*
X495077Y593757D01*
G01Y604499D02*
X496057D01*
X496656Y603900D01*
Y602700D01*
X495712Y601756D01*
Y600544D01*
X496556Y599700D01*
Y598000D01*
X495712Y597156D01*
Y595736D01*
X496856Y594592D01*
Y592999D01*
X495949Y592092D01*
Y590400D01*
X497635Y588714D01*
X497723D01*
G01X521848Y610700D02*
X516797Y605649D01*
Y595462D01*
X518502Y593757D01*
G01Y604499D02*
X519574D01*
X520274Y603799D01*
Y602525D01*
X519137Y601388D01*
Y600312D01*
X520149Y599300D01*
Y598100D01*
X519137Y597088D01*
Y596012D01*
X520249Y594900D01*
Y592267D01*
X520074Y592092D01*
Y590400D01*
X521760Y588714D01*
X521848D01*
G01X491724Y611668D02*
X487301Y607245D01*
Y606057D01*
X486679Y605435D01*
Y595462D01*
X488384Y593757D01*
G01Y604499D02*
X489456D01*
X490056Y603899D01*
Y603001D01*
X489019Y601964D01*
Y600736D01*
X489956Y599799D01*
Y598401D01*
X489019Y597464D01*
Y596136D01*
X490156Y594999D01*
Y593100D01*
X489656Y592600D01*
Y590400D01*
X491342Y588714D01*
X491430D01*
G01X515155Y610700D02*
X510104Y605649D01*
Y595462D01*
X511809Y593757D01*
G01Y604499D02*
X512881D01*
X513581Y603799D01*
Y602525D01*
X512444Y601388D01*
Y600312D01*
X513456Y599300D01*
Y598100D01*
X512444Y597088D01*
Y596012D01*
X513556Y594900D01*
Y592267D01*
X513381Y592092D01*
Y590400D01*
X515067Y588714D01*
X515155D01*
G01X531888Y593757D02*
X530183Y595462D01*
Y607115D01*
X533368Y610300D01*
X534534D01*
G01Y588714D02*
X534446D01*
X532760Y590400D01*
Y592092D01*
X533667Y592999D01*
Y594592D01*
X532523Y595736D01*
Y597156D01*
X533367Y598000D01*
Y599700D01*
X532523Y600544D01*
Y601756D01*
X533467Y602700D01*
Y603900D01*
X532868Y604499D01*
X531888D01*
G01X525195Y593757D02*
X523490Y595462D01*
Y605435D01*
X524112Y606057D01*
Y607245D01*
X527167Y610300D01*
X528155D01*
G01X528241Y588714D02*
X528153D01*
X526467Y590400D01*
Y592600D01*
X526967Y593100D01*
Y594999D01*
X525830Y596136D01*
Y597464D01*
X526767Y598401D01*
Y599799D01*
X525830Y600736D01*
Y601964D01*
X526867Y603001D01*
Y603899D01*
X526267Y604499D01*
X525195D01*
G01X501544Y590900D02*
X503256Y592612D01*
Y594200D01*
X502156Y595300D01*
X501206D01*
X500616Y595890D01*
Y597260D01*
X501136Y597780D01*
X501746D01*
X502356Y598390D01*
Y599780D01*
X501746Y600390D01*
X501166D01*
X500616Y600940D01*
Y602360D01*
X501256Y603000D01*
X502536D01*
X503275Y603739D01*
Y605645D01*
X501570Y607350D01*
G01X538355Y590900D02*
X540067Y592612D01*
Y594200D01*
X538967Y595300D01*
X538017D01*
X537427Y595890D01*
Y597260D01*
X537947Y597780D01*
X538557D01*
X539167Y598390D01*
Y599780D01*
X538557Y600390D01*
X537977D01*
X537427Y600940D01*
Y602360D01*
X538067Y603000D01*
X539347D01*
X540086Y603739D01*
Y605645D01*
X538381Y607350D01*
G01X506644Y588514D02*
X506356D01*
X504938Y589932D01*
Y594901D01*
X504109Y595730D01*
Y602270D01*
X504938Y603099D01*
Y608043D01*
X506644Y609749D01*
G01X501544Y588300D02*
X501256D01*
X499556Y590000D01*
Y608011D01*
X501544Y609999D01*
G01X538355Y588300D02*
X538067D01*
X536367Y590000D01*
Y608011D01*
X538355Y609999D01*
G01X506644Y591114D02*
X508356Y592826D01*
Y594500D01*
X507356Y595500D01*
X505840D01*
X505169Y596171D01*
Y597448D01*
X505621Y597900D01*
X505956D01*
X506656Y598600D01*
Y599688D01*
X505946Y600398D01*
X505709D01*
X505169Y600938D01*
Y601829D01*
X505940Y602600D01*
X507456D01*
X508456Y603600D01*
Y605328D01*
X506644Y607140D01*
G01X777601Y-43720D02*
X583560D01*
G03Y-46380I0J-1330D01*
G01X777156D01*
G02Y-51160I0J-2390D01*
G01X576040D01*
X572711Y-47831D01*
X551716D01*
X547246Y-52301D01*
G01X777601Y-42660D02*
X583560D01*
G03Y-47440I0J-2390D01*
G01X777156D01*
G02Y-50100I0J-1330D01*
G01X576480D01*
X573151Y-46771D01*
X551716D01*
X547246Y-42301D01*
G01X555313Y17157D02*
X554192Y16036D01*
Y13100D01*
X557534Y9758D01*
Y8700D01*
X555734Y6900D01*
Y5325D01*
X556934Y4125D01*
Y2999D01*
X555734Y1799D01*
Y426D01*
X557092Y-932D01*
Y-2133D01*
X558659Y-3700D01*
G01Y12114D02*
X560048Y10725D01*
Y-2288D01*
X560660Y-2900D01*
Y-4300D01*
X558860Y-6100D01*
X557860D01*
X556560Y-7400D01*
Y-8654D01*
X555313Y-9901D01*
G01X548620Y17157D02*
X547692Y16229D01*
Y13101D01*
X550734Y10059D01*
Y8674D01*
X549059Y6999D01*
Y5876D01*
X550559Y4376D01*
Y3024D01*
X549059Y1524D01*
Y301D01*
X550492Y-1132D01*
Y-2226D01*
X551966Y-3700D01*
G01Y12114D02*
X553355Y10725D01*
Y-2288D01*
X553967Y-2900D01*
Y-4300D01*
X552167Y-6100D01*
X551167D01*
X549867Y-7400D01*
Y-8654D01*
X548620Y-9901D01*
G01X568699Y17157D02*
X567578Y16036D01*
Y13100D01*
X570478Y10200D01*
Y8232D01*
X568945Y6699D01*
Y5500D01*
X570195Y4250D01*
Y3350D01*
X568845Y2000D01*
Y701D01*
X570478Y-932D01*
Y-3233D01*
X571345Y-4100D01*
G01Y12114D02*
X572818Y10641D01*
Y-2484D01*
X573434Y-3100D01*
Y-4444D01*
X571978Y-5900D01*
X570578D01*
X568699Y-7779D01*
Y-9901D01*
G01X592124Y17157D02*
X591003Y16036D01*
Y13100D01*
X594345Y9758D01*
Y8700D01*
X592545Y6900D01*
Y5325D01*
X593745Y4125D01*
Y2999D01*
X592545Y1799D01*
Y426D01*
X593903Y-932D01*
Y-2133D01*
X595470Y-3700D01*
G01Y12114D02*
X596859Y10725D01*
Y-2288D01*
X597471Y-2900D01*
Y-4300D01*
X595671Y-6100D01*
X594671D01*
X592124Y-8647D01*
Y-9901D01*
G01X561868Y17019D02*
X561078Y16229D01*
Y13101D01*
X563878Y10301D01*
Y8432D01*
X562495Y7049D01*
Y5650D01*
X563945Y4200D01*
Y3000D01*
X562445Y1500D01*
Y301D01*
X563878Y-1132D01*
Y-3012D01*
X564966Y-4100D01*
G01X565052Y12114D02*
X566278Y10888D01*
Y-2125D01*
X567053Y-2900D01*
Y-4524D01*
X565477Y-6100D01*
X564253D01*
X562006Y-8347D01*
Y-9901D01*
G01X585431Y17157D02*
X584503Y16229D01*
Y13101D01*
X587545Y10059D01*
Y8674D01*
X585870Y6999D01*
Y5876D01*
X587370Y4376D01*
Y3024D01*
X585870Y1524D01*
Y301D01*
X587303Y-1132D01*
Y-2226D01*
X588777Y-3700D01*
G01Y12114D02*
X590166Y10725D01*
Y-2288D01*
X590778Y-2900D01*
Y-4300D01*
X588978Y-6100D01*
X587978D01*
X586678Y-7400D01*
Y-8654D01*
X585431Y-9901D01*
G01X575166Y14300D02*
X578272Y11194D01*
Y-4952D01*
X576944Y-6280D01*
X575962D01*
X575192Y-7050D01*
G01X543455Y14514D02*
X546647Y11322D01*
Y-4068D01*
X543455Y-7260D01*
G01X580266Y14514D02*
X583458Y11322D01*
Y-4068D01*
X580266Y-7260D01*
G01X575166Y11700D02*
X576265D01*
X577212Y10753D01*
Y8220D01*
X576242Y7250D01*
X575894D01*
X575278Y6634D01*
Y5302D01*
X575780Y4800D01*
X576492D01*
X577212Y4080D01*
Y3120D01*
X576392Y2300D01*
X575892D01*
X575292Y1700D01*
Y700D01*
X577212Y-1220D01*
Y-4509D01*
X576501Y-5220D01*
X575985D01*
X575166Y-4401D01*
G01X543455Y11914D02*
Y11915D01*
X544553D01*
X545587Y10881D01*
Y8106D01*
X544881Y7400D01*
X544367D01*
X543667Y6700D01*
Y5700D01*
X544367Y5000D01*
X544867D01*
X545587Y4280D01*
Y2907D01*
X544780Y2100D01*
X544082D01*
X543481Y1499D01*
Y301D01*
X544082Y-300D01*
X544880D01*
X545587Y-1007D01*
Y-3628D01*
X544564Y-4651D01*
X543455D01*
G01X580266Y11914D02*
Y11915D01*
X581364D01*
X582398Y10881D01*
Y8106D01*
X581692Y7400D01*
X581178D01*
X580478Y6700D01*
Y5700D01*
X581178Y5000D01*
X581678D01*
X582398Y4280D01*
Y2907D01*
X581591Y2100D01*
X580893D01*
X580292Y1499D01*
Y301D01*
X580893Y-300D01*
X581691D01*
X582398Y-1007D01*
Y-3628D01*
X581375Y-4651D01*
X580266D01*
G01X555313Y593757D02*
X553608Y595462D01*
Y605649D01*
X558659Y610700D01*
G01Y588714D02*
X558571D01*
X556885Y590400D01*
Y592092D01*
X557060Y592267D01*
Y594900D01*
X555948Y596012D01*
Y597088D01*
X556960Y598100D01*
Y599300D01*
X555948Y600312D01*
Y601388D01*
X557085Y602525D01*
Y603799D01*
X556385Y604499D01*
X555313D01*
G01X548620Y593757D02*
X546915Y595462D01*
Y605649D01*
X551966Y610700D01*
G01Y588714D02*
X551878D01*
X550192Y590400D01*
Y592092D01*
X550367Y592267D01*
Y594900D01*
X549255Y596012D01*
Y597088D01*
X550267Y598100D01*
Y599300D01*
X549255Y600312D01*
Y601388D01*
X550392Y602525D01*
Y603799D01*
X549692Y604499D01*
X548620D01*
G01X568699Y593757D02*
X566994Y595462D01*
Y607115D01*
X570179Y610300D01*
X571345D01*
G01Y588714D02*
X571257D01*
X569571Y590400D01*
Y592092D01*
X570478Y592999D01*
Y594592D01*
X569334Y595736D01*
Y597156D01*
X570178Y598000D01*
Y599700D01*
X569334Y600544D01*
Y601756D01*
X570278Y602700D01*
Y603900D01*
X569679Y604499D01*
X568699D01*
G01X592124Y593757D02*
X590419Y595462D01*
Y605649D01*
X595470Y610700D01*
G01Y588714D02*
X595382D01*
X593696Y590400D01*
Y592092D01*
X593871Y592267D01*
Y594900D01*
X592759Y596012D01*
Y597088D01*
X593771Y598100D01*
Y599300D01*
X592759Y600312D01*
Y601388D01*
X593896Y602525D01*
Y603799D01*
X593196Y604499D01*
X592124D01*
G01X562006Y593757D02*
X560301Y595462D01*
Y605435D01*
X560923Y606057D01*
Y607245D01*
X563978Y610300D01*
X564966D01*
G01X565052Y588714D02*
X564964D01*
X563278Y590400D01*
Y592600D01*
X563778Y593100D01*
Y594999D01*
X562641Y596136D01*
Y597464D01*
X563578Y598401D01*
Y599799D01*
X562641Y600736D01*
Y601964D01*
X563678Y603001D01*
Y603899D01*
X563078Y604499D01*
X562006D01*
G01X585431Y593757D02*
X583726Y595462D01*
Y605649D01*
X588777Y610700D01*
G01Y588714D02*
X588689D01*
X587003Y590400D01*
Y592092D01*
X587178Y592267D01*
Y594900D01*
X586066Y596012D01*
Y597088D01*
X587078Y598100D01*
Y599300D01*
X586066Y600312D01*
Y601388D01*
X587203Y602525D01*
Y603799D01*
X586503Y604499D01*
X585431D01*
G01X575166Y590900D02*
X576878Y592612D01*
Y594200D01*
X575778Y595300D01*
X574828D01*
X574238Y595890D01*
Y597260D01*
X574758Y597780D01*
X575368D01*
X575978Y598390D01*
Y599780D01*
X575368Y600390D01*
X574788D01*
X574238Y600940D01*
Y602360D01*
X574878Y603000D01*
X576158D01*
X576897Y603739D01*
Y605645D01*
X575192Y607350D01*
G01X543455Y588514D02*
X543167D01*
X541750Y589931D01*
Y594900D01*
X540920Y595730D01*
Y602270D01*
X541750Y603100D01*
Y608044D01*
X543455Y609749D01*
G01X580266Y588514D02*
X579978D01*
X578561Y589931D01*
Y594900D01*
X577731Y595730D01*
Y602270D01*
X578561Y603100D01*
Y608044D01*
X580266Y609749D01*
G01X575166Y588300D02*
X574878D01*
X573178Y590000D01*
Y608011D01*
X575166Y609999D01*
G01X543455Y591114D02*
X545167Y592826D01*
Y594500D01*
X544167Y595500D01*
X542651D01*
X541980Y596171D01*
Y597448D01*
X542432Y597900D01*
X542767D01*
X543467Y598600D01*
Y599688D01*
X542757Y600398D01*
X542520D01*
X541980Y600938D01*
Y601829D01*
X542751Y602600D01*
X544267D01*
X545267Y603600D01*
Y605328D01*
X543455Y607140D01*
G01X580266Y591114D02*
X581978Y592826D01*
Y594500D01*
X580978Y595500D01*
X579462D01*
X578791Y596171D01*
Y597448D01*
X579243Y597900D01*
X579578D01*
X580278Y598600D01*
Y599688D01*
X579568Y600398D01*
X579331D01*
X578791Y600938D01*
Y601829D01*
X579562Y602600D01*
X581078D01*
X582078Y603600D01*
Y605328D01*
X580266Y607140D01*
G01X779921Y17157D02*
X778800Y16036D01*
Y13100D01*
X781700Y10200D01*
Y8232D01*
X780167Y6699D01*
Y5500D01*
X781417Y4250D01*
Y3350D01*
X780067Y2000D01*
Y701D01*
X781700Y-932D01*
Y-3233D01*
X782567Y-4100D01*
G01X779921Y17157D02*
Y18479D01*
X779488Y18912D01*
Y23489D01*
X781788Y25789D01*
Y28461D01*
X780638Y29611D01*
Y34239D01*
X781988Y35589D01*
Y36912D01*
X781400Y37500D01*
Y45612D01*
X781988Y46200D01*
Y47564D01*
X780638Y48914D01*
Y53138D01*
X781988Y54488D01*
Y66061D01*
X780638Y67411D01*
Y72039D01*
X781988Y73389D01*
Y74812D01*
X781200Y75600D01*
Y83312D01*
X781988Y84100D01*
Y85364D01*
X780638Y86714D01*
Y90938D01*
X781800Y92100D01*
Y93588D01*
X780100Y95288D01*
Y153757D01*
X781143Y154800D01*
X783133D01*
X784300Y155967D01*
Y157957D01*
X785343Y159000D01*
X788101D01*
X789000Y159899D01*
Y162657D01*
X790143Y163800D01*
X793800D01*
X794500Y164500D01*
Y166495D01*
X795243Y167238D01*
X799171D01*
X799672Y167739D01*
Y173329D01*
X887973Y261630D01*
X909977D01*
G01X782567Y12114D02*
X784040Y10641D01*
Y-2484D01*
X784656Y-3100D01*
Y-4444D01*
X783200Y-5900D01*
X781800D01*
X779921Y-7779D01*
Y-9901D01*
G01X782567Y12114D02*
X780494Y14187D01*
Y15194D01*
X781988Y16688D01*
Y22689D01*
X784488Y25189D01*
Y37300D01*
X785054Y37866D01*
Y45446D01*
X784488Y46012D01*
Y74988D01*
X785100Y75600D01*
Y83388D01*
X784488Y84000D01*
Y94600D01*
X782600Y96488D01*
Y151601D01*
X787399Y156400D01*
X789481D01*
X797452Y164371D01*
X798970D01*
X801940Y167341D01*
Y172061D01*
X889009Y259130D01*
X909694D01*
G01X773228Y17157D02*
X772300Y16229D01*
Y13101D01*
X775100Y10301D01*
Y8432D01*
X773717Y7049D01*
Y5650D01*
X775167Y4200D01*
Y3000D01*
X773667Y1500D01*
Y301D01*
X775100Y-1132D01*
Y-3012D01*
X776188Y-4100D01*
G01X773228Y17157D02*
Y25127D01*
X775188Y27087D01*
Y28511D01*
X774288Y29411D01*
Y34587D01*
X775288Y35587D01*
Y37112D01*
X774600Y37800D01*
Y45612D01*
X775288Y46300D01*
Y47614D01*
X774288Y48614D01*
Y53414D01*
X775188Y54314D01*
Y66211D01*
X774288Y67111D01*
Y72099D01*
X775288Y73099D01*
Y74712D01*
X774600Y75400D01*
Y83300D01*
X775288Y83988D01*
Y85414D01*
X774288Y86414D01*
Y91214D01*
X775100Y92026D01*
Y154301D01*
X887429Y266630D01*
X908929D01*
G01X776274Y12114D02*
X777500Y10888D01*
Y-2125D01*
X778275Y-2900D01*
Y-4524D01*
X776699Y-6100D01*
X775475D01*
X773228Y-8347D01*
Y-9901D01*
G01X776274Y12114D02*
X774400Y13988D01*
Y15626D01*
X775466Y16692D01*
X778000Y28156D01*
Y37400D01*
X778400Y37800D01*
Y45700D01*
X777900Y46200D01*
Y48426D01*
X778100Y48626D01*
Y53652D01*
X777888Y53864D01*
Y64800D01*
X778000Y66144D01*
Y83788D01*
X777788Y84000D01*
Y84900D01*
X778106Y87266D01*
X778138Y87500D01*
Y90360D01*
X777600Y93160D01*
Y153993D01*
X794254Y170647D01*
X796544D01*
X797104Y171207D01*
Y173497D01*
X887737Y264130D01*
X909976D01*
G01X786388Y14300D02*
X789494Y11194D01*
Y-4952D01*
X788166Y-6280D01*
X787184D01*
X786414Y-7050D01*
G01X786388Y14300D02*
X788114Y16026D01*
Y18100D01*
X787314Y18900D01*
X786314D01*
X785594Y19620D01*
Y20688D01*
X789468Y24562D01*
Y37780D01*
X790092Y38404D01*
Y39396D01*
X789468Y40020D01*
Y40780D01*
X790092Y41404D01*
Y42396D01*
X789468Y43020D01*
Y43780D01*
X790092Y44404D01*
Y45396D01*
X789468Y46020D01*
Y55680D01*
X790092Y56304D01*
Y57296D01*
X789468Y57920D01*
Y78536D01*
X790380Y79448D01*
Y82940D01*
X789468Y83852D01*
Y96403D01*
X786280Y99591D01*
Y110189D01*
X786730Y110639D01*
Y111639D01*
X786280Y112089D01*
Y113436D01*
X786730Y113886D01*
Y114886D01*
X786280Y115336D01*
Y117825D01*
X786730Y118275D01*
Y119275D01*
X786280Y119725D01*
Y122718D01*
X786730Y123168D01*
Y124168D01*
X786280Y124618D01*
Y128648D01*
X787625Y129993D01*
Y132875D01*
X786280Y134220D01*
Y141307D01*
X787152Y142179D01*
X788351D01*
X790095Y143923D01*
Y146667D01*
X787974Y148788D01*
Y152364D01*
X788482Y152872D01*
X795114D01*
X797676Y155434D01*
Y160428D01*
X798674Y161426D01*
X803025D01*
X805184Y163585D01*
Y170098D01*
X879677Y244591D01*
X880313D01*
X881021Y245299D01*
Y245935D01*
X881728Y246642D01*
X882365D01*
X883073Y247350D01*
Y247987D01*
X883786Y248700D01*
X884423D01*
X885131Y249408D01*
Y250045D01*
X886141Y251055D01*
X886778D01*
X887486Y251763D01*
Y252400D01*
X888415Y253329D01*
X889051D01*
X889759Y254037D01*
Y254673D01*
X890466Y255380D01*
X892572D01*
X893022Y254930D01*
X894022D01*
X894472Y255380D01*
X895681D01*
X896131Y254930D01*
X897131D01*
X897581Y255380D01*
X898908D01*
X899358Y254930D01*
X900358D01*
X900808Y255380D01*
X901808D01*
X902258Y254930D01*
X903258D01*
X903708Y255380D01*
X905500D01*
X905950Y254930D01*
X906950D01*
X907400Y255380D01*
X908400D01*
G01X786388Y11700D02*
X787487D01*
X788434Y10753D01*
Y8220D01*
X787464Y7250D01*
X787116D01*
X786500Y6634D01*
Y5302D01*
X787002Y4800D01*
X787714D01*
X788434Y4080D01*
Y3120D01*
X787614Y2300D01*
X787114D01*
X786514Y1700D01*
Y700D01*
X788434Y-1220D01*
Y-4509D01*
X787723Y-5220D01*
X787207D01*
X786388Y-4401D01*
G01Y11700D02*
X784534Y13554D01*
Y21131D01*
X788408Y25005D01*
Y78979D01*
X789320Y79891D01*
Y82497D01*
X788408Y83409D01*
Y95960D01*
X785220Y99148D01*
Y129088D01*
X786565Y130433D01*
Y132435D01*
X785220Y133780D01*
Y141747D01*
X786712Y143239D01*
X787911D01*
X789031Y144359D01*
Y146231D01*
X786914Y148348D01*
Y152804D01*
X788042Y153932D01*
X794674D01*
X796616Y155874D01*
Y160868D01*
X798234Y162486D01*
X802585D01*
X804124Y164025D01*
Y170538D01*
X890026Y256440D01*
X908400D01*
G01X902496Y342428D02*
X896009D01*
X853070Y385367D01*
Y387931D01*
X842101Y398900D01*
X821300D01*
X813700Y406500D01*
Y413301D01*
X804500Y422501D01*
Y424701D01*
X786901Y442300D01*
X784895D01*
X781800Y445395D01*
Y498800D01*
X780034Y500566D01*
Y507434D01*
X781988Y509388D01*
Y510711D01*
X780767Y511932D01*
Y516568D01*
X782100Y517901D01*
Y519288D01*
X781600Y519788D01*
Y527200D01*
X781988Y527588D01*
Y529267D01*
X780638Y530617D01*
Y535238D01*
X781988Y536588D01*
Y537700D01*
X781600Y538088D01*
Y546300D01*
X781988Y546688D01*
Y548507D01*
X780638Y549857D01*
Y554107D01*
X781788Y555257D01*
Y557100D01*
X781600Y557288D01*
Y565400D01*
X781788Y565588D01*
Y567267D01*
X780688Y568367D01*
Y573089D01*
X781838Y574239D01*
Y575600D01*
X781600Y575838D01*
Y584400D01*
X781838Y584638D01*
Y586457D01*
X778488Y589807D01*
Y592324D01*
X779921Y593757D01*
G01X902597Y344928D02*
X896175D01*
X854955Y386148D01*
Y389014D01*
X843169Y400800D01*
X822500D01*
X819150Y404150D01*
Y410651D01*
X806500Y423301D01*
Y425401D01*
X790400Y441501D01*
Y444200D01*
X789700Y444900D01*
X785200D01*
X784300Y445800D01*
Y448268D01*
X784860Y448828D01*
X790840D01*
X791400Y449388D01*
Y450828D01*
X790840Y451388D01*
X784860D01*
X784300Y451948D01*
Y459800D01*
X785800Y461300D01*
Y462900D01*
X784300Y464400D01*
Y499300D01*
X784900Y499900D01*
Y502422D01*
X784290Y503032D01*
X783080D01*
X782470Y503642D01*
Y505622D01*
X783080Y506232D01*
X784290D01*
X784900Y506842D01*
Y508400D01*
X784488Y508812D01*
Y518888D01*
X785000Y519400D01*
Y527500D01*
X784488Y528012D01*
Y537688D01*
X785000Y538200D01*
Y546100D01*
X784488Y546612D01*
Y556188D01*
X784900Y556600D01*
Y565500D01*
X784488Y565912D01*
Y575600D01*
X784900Y576012D01*
Y583700D01*
X784488Y584112D01*
Y586443D01*
X782567Y588364D01*
Y588714D01*
G01X906006Y338600D02*
X894504D01*
X849300Y383804D01*
Y386201D01*
X840601Y394900D01*
X818601D01*
X809400Y404101D01*
X806925Y410075D01*
X803018Y413982D01*
X800400Y420302D01*
Y423300D01*
X786500Y437200D01*
X784603D01*
X776800Y445003D01*
Y495384D01*
X775419Y498717D01*
X775100Y499488D01*
Y510716D01*
X774982Y511000D01*
X774816Y511400D01*
X774288Y512677D01*
Y516083D01*
X775188Y518256D01*
Y528650D01*
X774288Y530824D01*
Y534863D01*
X775100Y536824D01*
Y548745D01*
X774461Y550288D01*
Y553917D01*
X775188Y555672D01*
Y566560D01*
X774363Y568552D01*
Y572875D01*
X774933Y574251D01*
Y586137D01*
X774234Y587825D01*
X772763Y589296D01*
Y593292D01*
X773228Y593757D01*
G01X906364Y340500D02*
X895270D01*
X851185Y384585D01*
Y387016D01*
X841201Y397000D01*
X819300D01*
X811300Y405000D01*
Y412901D01*
X810501Y413700D01*
X806000D01*
X804664Y415036D01*
X802600Y420019D01*
Y423900D01*
X786949Y439551D01*
X784934D01*
X779300Y445185D01*
Y497900D01*
X777645Y499555D01*
Y511254D01*
X778138Y511747D01*
Y517207D01*
X777888Y517457D01*
Y519400D01*
X778300Y519812D01*
Y527700D01*
X777888Y528112D01*
Y529992D01*
X778138Y530242D01*
Y535192D01*
X777788Y535542D01*
Y537588D01*
X778300Y538100D01*
Y546500D01*
X777788Y547012D01*
Y548457D01*
X778138Y548807D01*
Y555007D01*
X777888Y555257D01*
Y557200D01*
X778300Y557612D01*
Y565200D01*
X777888Y565612D01*
Y567997D01*
X778388Y568497D01*
Y572656D01*
X777788Y573256D01*
Y575200D01*
X778300Y575712D01*
Y584000D01*
X777788Y584512D01*
Y587200D01*
X776274Y588714D01*
G01X779921Y593757D02*
X778216Y595462D01*
Y605949D01*
X782567Y610300D01*
G01Y588714D02*
X782479D01*
X780793Y590400D01*
Y592092D01*
X781700Y592999D01*
Y594592D01*
X780556Y595736D01*
Y597156D01*
X781400Y598000D01*
Y599700D01*
X780556Y600544D01*
Y601756D01*
X781500Y602700D01*
Y603900D01*
X780901Y604499D01*
X779921D01*
G01X773228Y593757D02*
X771523Y595462D01*
Y605635D01*
X776188Y610300D01*
G01X776274Y588714D02*
X776186D01*
X774500Y590400D01*
Y592600D01*
X775000Y593100D01*
Y594999D01*
X773863Y596136D01*
Y597464D01*
X774800Y598401D01*
Y599799D01*
X773863Y600736D01*
Y601964D01*
X774900Y603001D01*
Y603899D01*
X774300Y604499D01*
X773228D01*
G01X786388Y590900D02*
X788100Y592612D01*
Y594200D01*
X787000Y595300D01*
X786050D01*
X785460Y595890D01*
Y597260D01*
X785980Y597780D01*
X786590D01*
X787200Y598390D01*
Y599780D01*
X786590Y600390D01*
X786010D01*
X785460Y600940D01*
Y602360D01*
X786100Y603000D01*
X787118D01*
X788119Y604001D01*
Y605645D01*
X786414Y607350D01*
G01X907713Y348839D02*
X896431D01*
X857900Y387370D01*
Y391277D01*
X841877Y407300D01*
X826800D01*
X809500Y424600D01*
Y426600D01*
X794380Y441720D01*
Y454463D01*
X792891Y455952D01*
X789920D01*
X789420Y456452D01*
Y458892D01*
X789920Y459392D01*
X792891D01*
X794380Y460881D01*
Y464891D01*
X793101Y466170D01*
X788962D01*
X787980Y467152D01*
Y497149D01*
X789468Y498637D01*
Y579170D01*
X790088Y579790D01*
Y580790D01*
X789468Y581410D01*
Y582410D01*
X790088Y583030D01*
Y584030D01*
X789468Y584650D01*
Y587872D01*
X786440Y590900D01*
X786388D01*
G01Y588300D02*
X786100D01*
X784400Y590000D01*
Y608011D01*
X786388Y609999D01*
G01X907713Y347779D02*
X895991D01*
X856840Y386930D01*
Y390837D01*
X841437Y406240D01*
X826360D01*
X808440Y424160D01*
Y426160D01*
X793320Y441280D01*
Y454023D01*
X792451Y454892D01*
X789480D01*
X788360Y456012D01*
Y459332D01*
X789480Y460452D01*
X792451D01*
X793320Y461321D01*
Y464448D01*
X792658Y465110D01*
X788519D01*
X786920Y466709D01*
Y497592D01*
X788408Y499080D01*
Y587261D01*
X787369Y588300D01*
X786388D01*
G01X840157Y17157D02*
Y19257D01*
X842399Y21499D01*
Y28199D01*
X841599Y28999D01*
Y34899D01*
X842099Y35399D01*
Y36901D01*
X841500Y37500D01*
Y45701D01*
X842099Y46300D01*
Y48014D01*
X841499Y48614D01*
Y53314D01*
X842449Y54264D01*
Y65949D01*
X841599Y66799D01*
Y72599D01*
X842099Y73099D01*
Y74901D01*
X841600Y75400D01*
Y83501D01*
X842099Y84000D01*
Y85814D01*
X841499Y86414D01*
Y91114D01*
X841974Y91589D01*
Y114674D01*
X844700Y117400D01*
Y142242D01*
X847266Y144808D01*
X848058D01*
X848637Y144229D01*
X849429D01*
X850448Y145248D01*
Y146040D01*
X849869Y146619D01*
Y147411D01*
X850888Y148430D01*
X851680D01*
X852259Y147851D01*
X853051D01*
X854070Y148870D01*
Y149662D01*
X853491Y150241D01*
Y151033D01*
X874381Y171923D01*
Y172785D01*
X872866Y174300D01*
Y175162D01*
X873730Y176026D01*
X874592D01*
X876107Y174511D01*
X876969D01*
X877833Y175375D01*
Y176237D01*
X876318Y177752D01*
Y178614D01*
X877182Y179478D01*
X878044D01*
X879559Y177963D01*
X880421D01*
X881285Y178827D01*
Y179689D01*
X879770Y181204D01*
Y182066D01*
X880634Y182930D01*
X881496D01*
X883011Y181415D01*
X883873D01*
X886041Y183583D01*
Y184445D01*
X884480Y186006D01*
Y186868D01*
X885344Y187732D01*
X886206D01*
X887767Y186171D01*
X888629D01*
X889493Y187035D01*
Y187897D01*
X887932Y189458D01*
Y190320D01*
X888796Y191184D01*
X889658D01*
X891219Y189623D01*
X892081D01*
X892945Y190487D01*
Y191349D01*
X891384Y192910D01*
Y193772D01*
X892248Y194636D01*
X893110D01*
X894671Y193075D01*
X895533D01*
X896397Y193939D01*
Y194801D01*
X894836Y196362D01*
Y197224D01*
X895700Y198088D01*
X896562D01*
X898123Y196527D01*
X898985D01*
X899849Y197391D01*
Y198253D01*
X898288Y199814D01*
Y200676D01*
X899152Y201540D01*
X900014D01*
X901575Y199979D01*
X902437D01*
X904267Y201809D01*
Y205011D01*
X911589Y212333D01*
X912436D01*
G01X843503Y-3700D02*
X841936Y-2133D01*
Y-932D01*
X840578Y426D01*
Y1799D01*
X841778Y2999D01*
Y4125D01*
X840578Y5325D01*
Y6900D01*
X842378Y8700D01*
Y9758D01*
X839036Y13100D01*
Y16036D01*
X840157Y17157D01*
G01X843503Y12114D02*
X841599Y14018D01*
Y15614D01*
X843042Y17057D01*
Y18293D01*
X844949Y20200D01*
Y28699D01*
X845499Y29249D01*
Y34601D01*
X844899Y35201D01*
Y36799D01*
X845600Y37500D01*
Y45399D01*
X844899Y46100D01*
Y48114D01*
X845599Y48814D01*
Y53214D01*
X844949Y53864D01*
Y66499D01*
X845499Y67049D01*
Y72501D01*
X844899Y73101D01*
Y75199D01*
X845500Y75800D01*
Y83299D01*
X844899Y83900D01*
Y85914D01*
X845599Y86614D01*
Y91274D01*
X844999Y91874D01*
Y112100D01*
X849118Y116219D01*
Y140819D01*
X857600Y149301D01*
Y152065D01*
X858736Y153201D01*
X859528D01*
X860568Y152161D01*
X861360Y152162D01*
X862379Y153181D01*
Y153973D01*
X861339Y155013D01*
X861338Y155803D01*
X862358Y156823D01*
X863150D01*
X864190Y155783D01*
X864982Y155784D01*
X866001Y156803D01*
Y157595D01*
X864961Y158635D01*
X864960Y159425D01*
X867232Y161697D01*
X868094D01*
X869664Y160127D01*
X870527D01*
X871391Y160991D01*
Y161852D01*
X869820Y163423D01*
Y164285D01*
X870684Y165149D01*
X871546D01*
X873032Y163663D01*
X873894D01*
X874758Y164527D01*
Y165389D01*
X873272Y166875D01*
Y167737D01*
X874136Y168601D01*
X874998D01*
X876484Y167115D01*
X877346D01*
X878210Y167979D01*
Y168841D01*
X876724Y170327D01*
Y171189D01*
X877588Y172053D01*
X878450D01*
X879936Y170567D01*
X880798D01*
X881662Y171431D01*
Y172293D01*
X880176Y173779D01*
Y174641D01*
X881040Y175505D01*
X881902D01*
X883388Y174019D01*
X884250D01*
X885114Y174883D01*
Y175745D01*
X883628Y177231D01*
Y178093D01*
X884492Y178957D01*
X885354D01*
X886840Y177471D01*
X887702D01*
X888566Y178335D01*
Y179197D01*
X887080Y180683D01*
Y181545D01*
X887944Y182409D01*
X888806D01*
X890292Y180923D01*
X891154D01*
X892018Y181787D01*
Y182649D01*
X890532Y184135D01*
Y184997D01*
X908200Y202665D01*
Y205597D01*
X912436Y209833D01*
G01X840157Y-9901D02*
X841404Y-8654D01*
Y-7400D01*
X842704Y-6100D01*
X843704D01*
X845504Y-4300D01*
Y-2900D01*
X844892Y-2288D01*
Y10725D01*
X843503Y12114D01*
G01X810039Y17157D02*
X811999Y19117D01*
Y28501D01*
X811099Y29401D01*
Y34299D01*
X811900Y35100D01*
Y36900D01*
X811100Y37700D01*
Y45200D01*
X811900Y46000D01*
Y47813D01*
X811200Y48513D01*
Y53515D01*
X811900Y54215D01*
Y66300D01*
X811100Y67100D01*
Y72100D01*
X811900Y72900D01*
Y75000D01*
X811600Y75300D01*
Y83600D01*
X811900Y83900D01*
Y85613D01*
X811200Y86313D01*
Y91199D01*
X812088Y92087D01*
Y147071D01*
X901959Y236942D01*
X906858D01*
G01X812999Y-4100D02*
X811911Y-3012D01*
Y-1132D01*
X810478Y301D01*
Y1500D01*
X811978Y3000D01*
Y4200D01*
X810528Y5650D01*
Y7049D01*
X811911Y8432D01*
Y10301D01*
X809111Y13101D01*
Y16229D01*
X810039Y17157D01*
G01X813085Y12114D02*
X811200Y13999D01*
Y15499D01*
X814100Y18399D01*
Y28000D01*
X814949Y28849D01*
Y33800D01*
X814847Y34500D01*
X814800Y34822D01*
Y37601D01*
X815200Y38001D01*
Y45700D01*
X814599Y46301D01*
Y47500D01*
X814949Y49900D01*
Y53614D01*
X814699Y53864D01*
Y66399D01*
X814949Y66649D01*
Y71600D01*
X814700Y73900D01*
Y74400D01*
X815024Y75500D01*
X815200Y76100D01*
Y83499D01*
X814599Y84100D01*
Y84800D01*
X814897Y87266D01*
X814949Y87700D01*
Y95600D01*
X816000Y96651D01*
Y98049D01*
X814949Y99100D01*
Y146396D01*
X902995Y234442D01*
X907056D01*
G01X810039Y-9901D02*
Y-8347D01*
X812286Y-6100D01*
X813510D01*
X815086Y-4524D01*
Y-2900D01*
X814311Y-2125D01*
Y10888D01*
X813085Y12114D01*
G01X836810Y-3700D02*
X835336Y-2226D01*
Y-1132D01*
X833903Y301D01*
Y1524D01*
X835403Y3024D01*
Y4376D01*
X833903Y5876D01*
Y6999D01*
X835578Y8674D01*
Y10059D01*
X832536Y13101D01*
Y16229D01*
X833464Y17157D01*
G01D02*
Y19379D01*
X835300Y21215D01*
Y28698D01*
X834899Y29099D01*
Y34899D01*
X835699Y35699D01*
Y37000D01*
X834900Y37799D01*
Y45500D01*
X835699Y46299D01*
Y47914D01*
X834899Y48714D01*
Y53414D01*
X835299Y53814D01*
Y66499D01*
X834899Y66899D01*
Y72599D01*
X835699Y73399D01*
Y74901D01*
X835100Y75500D01*
Y83601D01*
X835699Y84200D01*
Y85714D01*
X834899Y86514D01*
Y91214D01*
X835299Y91614D01*
Y106602D01*
X833492Y108409D01*
X830365D01*
X829565Y109209D01*
Y110809D01*
X830365Y111609D01*
X832900D01*
X833700Y112409D01*
Y114009D01*
X832900Y114809D01*
X830365D01*
X829565Y115609D01*
Y117209D01*
X830365Y118009D01*
X832800D01*
X833500Y118709D01*
Y142500D01*
X834300Y143300D01*
X835900D01*
X836700Y142500D01*
Y135500D01*
X837500Y134700D01*
X839100D01*
X839900Y135500D01*
Y145214D01*
X842771Y148085D01*
Y148877D01*
X841470Y150178D01*
Y150970D01*
X842489Y151989D01*
X843281D01*
X844582Y150688D01*
X845374D01*
X864028Y169342D01*
Y174194D01*
X907167Y217333D01*
X912436D01*
G01X836810Y12114D02*
X834999Y13925D01*
Y16014D01*
X836449Y17464D01*
Y18828D01*
X838299Y20678D01*
Y28699D01*
X839099Y29499D01*
Y34401D01*
X838199Y35301D01*
Y37300D01*
X838600Y37701D01*
Y45700D01*
X838199Y46101D01*
Y47914D01*
X838999Y48714D01*
Y53214D01*
X838299Y53914D01*
Y66499D01*
X839099Y67299D01*
Y72301D01*
X838199Y73201D01*
Y74899D01*
X838800Y75500D01*
Y83499D01*
X838199Y84100D01*
Y85714D01*
X838999Y86514D01*
Y91014D01*
X838299Y91714D01*
Y108102D01*
X836000Y110401D01*
Y131100D01*
X836800Y131900D01*
X838400D01*
X839200Y131100D01*
Y120300D01*
X840000Y119500D01*
X841600D01*
X842400Y120300D01*
Y143784D01*
X869203Y170587D01*
Y175603D01*
X902000Y208400D01*
Y209500D01*
X907333Y214833D01*
X912436D01*
G01X833464Y-9901D02*
X834711Y-8654D01*
Y-7400D01*
X836011Y-6100D01*
X837011D01*
X838811Y-4300D01*
Y-2900D01*
X838199Y-2288D01*
Y10725D01*
X836810Y12114D01*
G01X846850Y17157D02*
X845922Y16229D01*
Y13101D01*
X848722Y10301D01*
Y8432D01*
X847339Y7049D01*
Y5650D01*
X848789Y4200D01*
Y3000D01*
X847289Y1500D01*
Y301D01*
X848722Y-1132D01*
Y-3012D01*
X849810Y-4100D01*
G01X846850Y17157D02*
Y18149D01*
X848810Y20109D01*
Y28491D01*
X847910Y29391D01*
Y34299D01*
X848910Y35299D01*
Y37200D01*
X848200Y37910D01*
Y45600D01*
X848910Y46310D01*
Y47614D01*
X847910Y48614D01*
Y53414D01*
X848810Y54314D01*
Y66291D01*
X847910Y67191D01*
Y72099D01*
X848910Y73099D01*
Y74790D01*
X848200Y75500D01*
Y83490D01*
X848910Y84200D01*
Y85414D01*
X847910Y86414D01*
Y91214D01*
X849200Y92504D01*
Y110528D01*
X853200Y114528D01*
Y138304D01*
X895214Y180318D01*
Y185214D01*
X916688Y206688D01*
Y206810D01*
G01X849896Y12114D02*
X851122Y10888D01*
Y-2125D01*
X851897Y-2900D01*
Y-4524D01*
X850321Y-6100D01*
X849097D01*
X846850Y-8347D01*
Y-9901D01*
G01X849896Y12114D02*
X847910Y14100D01*
Y15514D01*
X851100Y18704D01*
Y28189D01*
X851760Y28849D01*
Y35049D01*
X851410Y35399D01*
Y37310D01*
X852000Y37900D01*
Y45410D01*
X851410Y46000D01*
Y48314D01*
X851760Y48664D01*
Y53614D01*
X851510Y53864D01*
Y66399D01*
X851760Y66649D01*
Y72849D01*
X851410Y73199D01*
Y75210D01*
X852000Y75800D01*
Y83310D01*
X851410Y83900D01*
Y86114D01*
X851760Y86464D01*
Y91414D01*
X851743Y91431D01*
Y108957D01*
X855700Y112914D01*
Y136690D01*
X897637Y178627D01*
Y183737D01*
X918556Y204656D01*
Y204941D01*
G01X803346Y17157D02*
X804300Y18111D01*
Y25712D01*
X805588Y27000D01*
Y28199D01*
X804788Y28999D01*
Y34687D01*
X805288Y35187D01*
Y36800D01*
X804700Y37388D01*
Y45700D01*
X805288Y46288D01*
Y48014D01*
X804688Y48614D01*
Y53314D01*
X805638Y54264D01*
Y65949D01*
X804788Y66799D01*
Y72587D01*
X805288Y73087D01*
Y74912D01*
X804800Y75400D01*
Y83612D01*
X805288Y84100D01*
Y85814D01*
X804688Y86414D01*
Y91114D01*
X805300Y91726D01*
Y100801D01*
X806436Y101937D01*
Y128099D01*
X805876Y128659D01*
X804260D01*
X803700Y129219D01*
Y130659D01*
X804260Y131219D01*
X805876D01*
X806436Y131779D01*
Y149153D01*
X836111Y178828D01*
Y179690D01*
X834138Y181663D01*
Y182525D01*
X835002Y183389D01*
X835864D01*
X837837Y181416D01*
X838699D01*
X839563Y182280D01*
Y183142D01*
X837590Y185115D01*
Y185977D01*
X838454Y186841D01*
X839316D01*
X841289Y184868D01*
X842151D01*
X843015Y185732D01*
Y186594D01*
X841042Y188567D01*
Y189429D01*
X841906Y190293D01*
X842768D01*
X844741Y188320D01*
X845603D01*
X846467Y189184D01*
Y190046D01*
X844494Y192019D01*
Y192881D01*
X845358Y193745D01*
X846220D01*
X848193Y191772D01*
X849055D01*
X849919Y192636D01*
Y193498D01*
X847946Y195471D01*
Y196333D01*
X848810Y197197D01*
X849672D01*
X851645Y195224D01*
X852507D01*
X853371Y196088D01*
Y196950D01*
X851398Y198923D01*
Y199785D01*
X852262Y200649D01*
X853124D01*
X855097Y198676D01*
X855959D01*
X856823Y199540D01*
Y200402D01*
X854850Y202375D01*
Y203237D01*
X855714Y204101D01*
X856576D01*
X858549Y202128D01*
X859411D01*
X861104Y203821D01*
Y209800D01*
X882376Y231072D01*
X885888D01*
X898296Y243480D01*
X908617D01*
G01X806692Y-3700D02*
X805125Y-2133D01*
Y-932D01*
X803767Y426D01*
Y1799D01*
X804967Y2999D01*
Y4125D01*
X803767Y5325D01*
Y6900D01*
X805567Y8700D01*
Y9758D01*
X802225Y13100D01*
Y16036D01*
X803346Y17157D01*
G01X806692Y12114D02*
X804788Y14018D01*
Y15614D01*
X808138Y18964D01*
Y22062D01*
X807000Y23200D01*
Y24500D01*
X808138Y25638D01*
Y28699D01*
X808688Y29249D01*
Y34911D01*
X808088Y35511D01*
Y37100D01*
X808700Y37712D01*
Y45500D01*
X808088Y46112D01*
Y48064D01*
X808599Y48575D01*
Y53453D01*
X808138Y53914D01*
Y66499D01*
X808638Y66999D01*
Y72461D01*
X808088Y73011D01*
Y75200D01*
X808500Y75612D01*
Y83600D01*
X808088Y84012D01*
Y85914D01*
X808788Y86614D01*
Y91274D01*
X807800Y92262D01*
Y94139D01*
X808796Y95135D01*
Y148130D01*
X866402Y205736D01*
Y206598D01*
X864247Y208753D01*
Y209615D01*
X865111Y210479D01*
X865973D01*
X868128Y208324D01*
X868990D01*
X869854Y209188D01*
Y210050D01*
X867699Y212205D01*
Y213067D01*
X868563Y213931D01*
X869425D01*
X871580Y211776D01*
X872442D01*
X873306Y212640D01*
Y213502D01*
X871151Y215657D01*
Y216519D01*
X872015Y217383D01*
X872877D01*
X875032Y215228D01*
X875894D01*
X876758Y216092D01*
Y216954D01*
X874603Y219109D01*
Y219971D01*
X875467Y220835D01*
X876329D01*
X878484Y218680D01*
X879346D01*
X880210Y219544D01*
Y220406D01*
X878055Y222561D01*
Y223423D01*
X878919Y224287D01*
X879781D01*
X881936Y222132D01*
X882798D01*
X883662Y222996D01*
Y223858D01*
X881507Y226013D01*
Y226875D01*
X882371Y227739D01*
X883233D01*
X885388Y225584D01*
X886250D01*
X901646Y240980D01*
X908695D01*
G01X803346Y-9901D02*
X804593Y-8654D01*
Y-7400D01*
X805893Y-6100D01*
X806893D01*
X808693Y-4300D01*
Y-2900D01*
X808081Y-2288D01*
Y10725D01*
X806692Y12114D01*
G01X796653Y17157D02*
X798688Y19192D01*
Y28311D01*
X798088Y28911D01*
Y35087D01*
X798888Y35887D01*
Y37012D01*
X798300Y37600D01*
Y45712D01*
X798888Y46300D01*
Y47914D01*
X798088Y48714D01*
Y53414D01*
X798488Y53814D01*
Y66499D01*
X798088Y66899D01*
Y72687D01*
X798888Y73487D01*
Y74712D01*
X798100Y75500D01*
Y83312D01*
X798888Y84100D01*
Y85714D01*
X798088Y86514D01*
Y91214D01*
X798488Y91614D01*
Y98812D01*
X792700Y104600D01*
Y124300D01*
X793500Y125100D01*
X795100D01*
X795900Y124300D01*
Y111900D01*
X796800Y111000D01*
X798300D01*
X799100Y111800D01*
Y148584D01*
X814208Y163692D01*
Y164554D01*
X811778Y166984D01*
Y167846D01*
X812642Y168710D01*
X813504D01*
X815934Y166280D01*
X816796D01*
X818581Y168065D01*
Y174349D01*
X880882Y236650D01*
X882776D01*
X894611Y248485D01*
X908114D01*
G01X799999Y-3700D02*
X798525Y-2226D01*
Y-1132D01*
X797092Y301D01*
Y1524D01*
X798592Y3024D01*
Y4376D01*
X797092Y5876D01*
Y6999D01*
X798767Y8674D01*
Y10059D01*
X795725Y13101D01*
Y16229D01*
X796653Y17157D01*
G01Y-9901D02*
X797900Y-8654D01*
Y-7400D01*
X799200Y-6100D01*
X800200D01*
X802000Y-4300D01*
Y-2900D01*
X801388Y-2288D01*
Y10725D01*
X799999Y12114D01*
G01D02*
X798150Y13963D01*
Y15650D01*
X801500Y19000D01*
Y28499D01*
X802288Y29287D01*
Y34611D01*
X801388Y35511D01*
Y36900D01*
X802100Y37612D01*
Y45600D01*
X801388Y46312D01*
Y47914D01*
X802188Y48714D01*
Y53214D01*
X801488Y53914D01*
Y66499D01*
X802288Y67299D01*
Y72211D01*
X801388Y73111D01*
Y74788D01*
X801900Y75300D01*
Y83388D01*
X801388Y83900D01*
Y85714D01*
X802188Y86514D01*
Y91014D01*
X801488Y91714D01*
Y104600D01*
X800988Y105100D01*
X796000D01*
X795200Y105900D01*
Y106957D01*
X796043Y107800D01*
X800640D01*
X801200Y108360D01*
Y134200D01*
X804041Y137041D01*
Y138990D01*
X803481Y139550D01*
X801760D01*
X801200Y140110D01*
Y141550D01*
X801760Y142110D01*
X803481D01*
X804041Y142670D01*
Y144110D01*
X803481Y144670D01*
X801760D01*
X801200Y145230D01*
Y146670D01*
X801760Y147230D01*
X803481D01*
X804041Y147790D01*
Y149685D01*
X823970Y169614D01*
Y170476D01*
X821815Y172631D01*
Y173493D01*
X822679Y174357D01*
X823541D01*
X825696Y172202D01*
X826558D01*
X827422Y173066D01*
Y173928D01*
X825267Y176083D01*
Y176945D01*
X826131Y177809D01*
X826993D01*
X829148Y175654D01*
X830010D01*
X831383Y177027D01*
Y183615D01*
X881308Y233540D01*
X883872D01*
X896312Y245980D01*
X907380D01*
G01X816732Y17157D02*
X815611Y16036D01*
Y13100D01*
X818511Y10200D01*
Y8232D01*
X816978Y6699D01*
Y5500D01*
X818228Y4250D01*
Y3350D01*
X816878Y2000D01*
Y701D01*
X818511Y-932D01*
Y-3233D01*
X819378Y-4100D01*
G01X816732Y17157D02*
Y24732D01*
X818599Y26599D01*
Y28451D01*
X817449Y29601D01*
Y34249D01*
X818799Y35599D01*
Y36800D01*
X818000Y37599D01*
Y45500D01*
X818799Y46299D01*
Y47564D01*
X817449Y48914D01*
Y53248D01*
X818799Y54598D01*
Y66051D01*
X817449Y67401D01*
Y72149D01*
X818799Y73499D01*
Y74601D01*
X818100Y75300D01*
Y83601D01*
X818799Y84300D01*
Y85364D01*
X817449Y86714D01*
Y90998D01*
X818600Y92149D01*
Y100468D01*
X817849Y101219D01*
Y145760D01*
X840473Y168384D01*
X841335D01*
X842629Y167090D01*
X843490D01*
X844354Y167954D01*
Y168816D01*
X843061Y170109D01*
Y170972D01*
X843925Y171836D01*
X844786D01*
X846130Y170492D01*
X846992D01*
X847856Y171356D01*
Y172219D01*
X846513Y173562D01*
Y174424D01*
X903631Y231542D01*
X906736D01*
G01X819378Y12114D02*
X820851Y10641D01*
Y-2484D01*
X821467Y-3100D01*
Y-4444D01*
X820011Y-5900D01*
X818611D01*
X816732Y-7779D01*
Y-9901D01*
G01X819378Y12114D02*
X817305Y14187D01*
Y15204D01*
X818799Y16698D01*
Y22999D01*
X821299Y25499D01*
Y37200D01*
X821900Y37801D01*
Y45650D01*
X821299Y46251D01*
Y74799D01*
X821900Y75400D01*
Y83199D01*
X821299Y83800D01*
Y101516D01*
X819861Y102954D01*
Y144236D01*
X839425Y163800D01*
X843305D01*
X850454Y170949D01*
Y174829D01*
X904667Y229042D01*
X906736D01*
G01X791488Y14514D02*
X794680Y11322D01*
Y-4068D01*
X791488Y-7260D01*
G01Y14514D02*
X793314Y16340D01*
Y17900D01*
X791294Y19920D01*
Y20788D01*
X794568Y24062D01*
Y98403D01*
X790080Y102891D01*
Y126939D01*
X790952Y127811D01*
X795104D01*
X796596Y129303D01*
Y132579D01*
X795004Y134171D01*
X791701D01*
X790278Y135594D01*
Y137521D01*
X791177Y138420D01*
X793337D01*
X794568Y139651D01*
Y147892D01*
X808979Y162303D01*
Y168451D01*
X882301Y241773D01*
X882937D01*
X883645Y242481D01*
Y243117D01*
X884587Y244059D01*
X885223D01*
X885931Y244767D01*
Y245403D01*
X887124Y246596D01*
X887761D01*
X888469Y247304D01*
Y247941D01*
X889957Y249429D01*
X890593D01*
X891301Y250137D01*
Y250773D01*
X892008Y251480D01*
X894721D01*
X895171Y251030D01*
X896171D01*
X896621Y251480D01*
X897785D01*
X898235Y251030D01*
X899235D01*
X899685Y251480D01*
X900848D01*
X901298Y251030D01*
X902298D01*
X902748Y251480D01*
X905009D01*
X905459Y251030D01*
X906459D01*
X906909Y251480D01*
X910622D01*
G01X823225Y-7050D02*
X823995Y-6280D01*
X824977D01*
X826305Y-4952D01*
Y11194D01*
X823199Y14300D01*
G01X907500Y224180D02*
X905012D01*
X903180Y222348D01*
Y221711D01*
X902472Y221003D01*
X901835D01*
X901128Y220296D01*
Y219660D01*
X900420Y218952D01*
X899784D01*
X898859Y218027D01*
Y217390D01*
X898151Y216682D01*
X897514D01*
X896801Y215969D01*
Y215333D01*
X896093Y214625D01*
X895457D01*
X894584Y213752D01*
Y213115D01*
X893876Y212407D01*
X893239D01*
X892343Y211511D01*
Y210875D01*
X891635Y210167D01*
X890999D01*
X890292Y209460D01*
Y208824D01*
X889584Y208116D01*
X888948D01*
X888241Y207409D01*
Y206773D01*
X887533Y206065D01*
X886897D01*
X886171Y205339D01*
Y204702D01*
X885463Y203994D01*
X884826D01*
X884113Y203281D01*
Y202645D01*
X883405Y201937D01*
X882769D01*
X881689Y200857D01*
Y200221D01*
X880981Y199513D01*
X880345D01*
X879014Y198182D01*
Y197546D01*
X878306Y196838D01*
X877670D01*
X876614Y195782D01*
Y195145D01*
X875906Y194437D01*
X875269D01*
X874442Y193610D01*
Y192973D01*
X873734Y192265D01*
X873097D01*
X872156Y191324D01*
Y190688D01*
X871448Y189980D01*
X870812D01*
X869756Y188924D01*
Y188287D01*
X869048Y187579D01*
X868411D01*
X867538Y186706D01*
Y186069D01*
X866830Y185361D01*
X866193D01*
X854864Y174032D01*
Y170236D01*
X844828Y160200D01*
X841032D01*
X822980Y142148D01*
Y140920D01*
X823752Y140148D01*
X825448D01*
X826568Y139028D01*
Y134908D01*
X825448Y133788D01*
X823952D01*
X823080Y132916D01*
Y104852D01*
X826279Y101653D01*
Y45420D01*
X826899Y44800D01*
Y43800D01*
X826279Y43180D01*
Y42420D01*
X826899Y41800D01*
Y40800D01*
X826279Y40180D01*
Y39420D01*
X826899Y38800D01*
Y37800D01*
X826279Y37180D01*
Y27122D01*
X826779Y26622D01*
Y25062D01*
X822405Y20688D01*
Y19620D01*
X823125Y18900D01*
X824125D01*
X824925Y18100D01*
Y16026D01*
X823199Y14300D01*
G01X828299Y-7260D02*
X831491Y-4068D01*
Y11322D01*
X828299Y14514D01*
G01D02*
X830125Y16340D01*
Y17900D01*
X828105Y19920D01*
Y20788D01*
X829079Y21762D01*
X829955D01*
X830663Y22470D01*
Y23346D01*
X831999Y24682D01*
Y25514D01*
X831379Y26134D01*
Y102452D01*
X826880Y106951D01*
Y119442D01*
X827752Y120314D01*
X828991D01*
X830580Y121903D01*
Y125225D01*
X829131Y126674D01*
X827952D01*
X827080Y127546D01*
Y129719D01*
X830880Y133519D01*
Y143279D01*
X842001Y154400D01*
X846301D01*
X850862Y158961D01*
Y160521D01*
X861378Y171037D01*
Y174946D01*
X891341Y204909D01*
X891977D01*
X892685Y205617D01*
Y206253D01*
X893398Y206966D01*
X894035D01*
X894743Y207674D01*
Y208311D01*
X895456Y209024D01*
X896092D01*
X896800Y209732D01*
Y210368D01*
X898382Y211950D01*
X899019D01*
X899727Y212658D01*
Y213295D01*
X901148Y214716D01*
X901785D01*
X902493Y215424D01*
Y216061D01*
X906600Y220168D01*
X907318D01*
G01X791488Y11914D02*
Y11915D01*
X792586D01*
X793620Y10881D01*
Y8106D01*
X792914Y7400D01*
X792400D01*
X791700Y6700D01*
Y5700D01*
X792400Y5000D01*
X792900D01*
X793620Y4280D01*
Y2907D01*
X792813Y2100D01*
X792115D01*
X791514Y1499D01*
Y301D01*
X792115Y-300D01*
X792913D01*
X793620Y-1007D01*
Y-3628D01*
X792597Y-4651D01*
X791488D01*
G01Y11914D02*
X789764Y13638D01*
Y18365D01*
X790234Y18835D01*
Y21231D01*
X793508Y24505D01*
Y97960D01*
X789020Y102448D01*
Y127382D01*
X790509Y128871D01*
X794664D01*
X795536Y129743D01*
Y132139D01*
X794564Y133111D01*
X791261D01*
X789218Y135154D01*
Y137961D01*
X790737Y139480D01*
X792897D01*
X793508Y140091D01*
Y148332D01*
X807919Y162743D01*
Y168891D01*
X891568Y252540D01*
X910622D01*
G01X823199Y-4401D02*
X824018Y-5220D01*
X824534D01*
X825245Y-4509D01*
Y-1220D01*
X823325Y700D01*
Y1700D01*
X823925Y2300D01*
X824425D01*
X825245Y3120D01*
Y4080D01*
X824525Y4800D01*
X823813D01*
X823311Y5302D01*
Y6634D01*
X823927Y7250D01*
X824275D01*
X825245Y8220D01*
Y10753D01*
X824298Y11700D01*
X823199D01*
G01X907500Y225240D02*
X904572D01*
X853804Y174472D01*
Y170676D01*
X844388Y161260D01*
X840592D01*
X821920Y142588D01*
Y140480D01*
X823312Y139088D01*
X825008D01*
X825508Y138588D01*
Y135348D01*
X825008Y134848D01*
X823509D01*
X822020Y133359D01*
Y104409D01*
X825219Y101210D01*
Y25005D01*
X821345Y21131D01*
Y13554D01*
X823199Y11700D01*
G01X828299Y11914D02*
X826575Y13638D01*
Y18275D01*
X827045Y18745D01*
Y21231D01*
X830319Y24505D01*
Y102012D01*
X825820Y106511D01*
Y119885D01*
X827309Y121374D01*
X828551D01*
X829520Y122343D01*
Y124785D01*
X828691Y125614D01*
X827512D01*
X826020Y127106D01*
Y130159D01*
X829820Y133959D01*
Y143719D01*
X841561Y155460D01*
X845861D01*
X849802Y159401D01*
Y160961D01*
X860318Y171477D01*
Y175386D01*
X906160Y221228D01*
X907318D01*
G01X828299Y-4651D02*
X829408D01*
X830431Y-3628D01*
Y-1007D01*
X829724Y-300D01*
X828926D01*
X828325Y301D01*
Y1499D01*
X828926Y2100D01*
X829624D01*
X830431Y2907D01*
Y4280D01*
X829711Y5000D01*
X829211D01*
X828511Y5700D01*
Y6700D01*
X829211Y7400D01*
X829725D01*
X830431Y8106D01*
Y10881D01*
X829397Y11915D01*
X828299D01*
Y11914D01*
G01X904056Y367427D02*
X904029Y367400D01*
X898936D01*
X882200Y384136D01*
Y393256D01*
X812900Y462556D01*
Y500100D01*
X810400Y502600D01*
Y507600D01*
X811771Y508971D01*
Y511125D01*
X811099Y511797D01*
Y516457D01*
X811841Y517199D01*
Y519658D01*
X811700Y519799D01*
Y527801D01*
X811840Y527941D01*
Y529661D01*
X811099Y530402D01*
Y535242D01*
X811907Y536050D01*
Y537792D01*
X811700Y537999D01*
Y546000D01*
X812099Y546399D01*
Y548557D01*
X811099Y549557D01*
Y554257D01*
X811999Y555157D01*
Y557000D01*
X811700Y557299D01*
Y565400D01*
X811999Y565699D01*
Y567201D01*
X810951Y568249D01*
Y572944D01*
X811949Y573942D01*
Y575600D01*
X811700Y575849D01*
Y583800D01*
X811949Y584049D01*
Y586457D01*
X808799Y589607D01*
Y592517D01*
X810039Y593757D01*
G01X903166Y369931D02*
X902997Y370100D01*
X898902D01*
X884100Y384902D01*
Y394892D01*
X815933Y463059D01*
Y466400D01*
X814900Y467433D01*
Y468767D01*
X815933Y469800D01*
Y474268D01*
X814900Y475301D01*
Y476899D01*
X815933Y477932D01*
Y480068D01*
X815000Y481001D01*
Y482367D01*
X815933Y483300D01*
Y487500D01*
X814800Y488633D01*
Y490867D01*
X815933Y492000D01*
Y495468D01*
X814900Y496501D01*
Y497799D01*
X815933Y498832D01*
Y502377D01*
X815130Y503180D01*
X813700D01*
X813200Y503680D01*
Y505880D01*
X813700Y506380D01*
X815391D01*
X815959Y506948D01*
Y508258D01*
X814699Y509518D01*
Y511497D01*
X815417Y512215D01*
Y516291D01*
X814337Y517371D01*
Y520162D01*
X815100Y520925D01*
Y527364D01*
X814436Y528028D01*
Y529729D01*
X814949Y530242D01*
Y535192D01*
X814367Y535774D01*
Y537814D01*
X815100Y538547D01*
Y546200D01*
X814599Y546701D01*
Y548457D01*
X814949Y548807D01*
Y554417D01*
X814225Y555141D01*
Y556626D01*
X815100Y557501D01*
Y565500D01*
X814699Y565901D01*
Y567997D01*
X815199Y568497D01*
Y572656D01*
X814599Y573256D01*
Y575400D01*
X815100Y575901D01*
Y583800D01*
X814599Y584301D01*
Y587200D01*
X813085Y588714D01*
G01X905605Y387789D02*
X903211D01*
X899200Y391800D01*
Y401199D01*
X853766Y446633D01*
Y447765D01*
X854897Y448896D01*
X856029D01*
X867897Y437028D01*
X869029D01*
X870160Y438159D01*
Y439291D01*
X836500Y472951D01*
Y507100D01*
X835300Y508300D01*
Y511656D01*
X834899Y512057D01*
Y516957D01*
X835299Y517357D01*
Y529842D01*
X834899Y530242D01*
Y535698D01*
X835699Y536498D01*
Y537400D01*
X835100Y537999D01*
Y546500D01*
X835699Y547099D01*
Y549057D01*
X834899Y549857D01*
Y554757D01*
X835499Y555357D01*
Y557300D01*
X835100Y557699D01*
Y565500D01*
X835499Y565899D01*
Y567397D01*
X834426Y568470D01*
Y572969D01*
X835400Y573943D01*
Y575499D01*
X835100Y575799D01*
Y584500D01*
X835699Y585099D01*
Y586357D01*
X832799Y589257D01*
Y593092D01*
X833464Y593757D01*
G01X899229Y360856D02*
X899185Y360900D01*
X897400D01*
X869700Y388600D01*
Y396562D01*
X849562Y416700D01*
X840511D01*
X829014Y428197D01*
Y429129D01*
X830145Y430260D01*
X831477D01*
X842702Y419035D01*
X843834D01*
X844965Y420166D01*
Y421298D01*
X831677Y434586D01*
X830445D01*
X827051Y431192D01*
X826019D01*
X805900Y451311D01*
Y454400D01*
X808081Y456581D01*
Y458182D01*
X805900Y460363D01*
Y499000D01*
X804750Y500150D01*
Y508450D01*
X805288Y508988D01*
Y511157D01*
X804788Y511657D01*
Y516489D01*
X805900Y517601D01*
Y529154D01*
X804688Y530366D01*
Y535688D01*
X805700Y536700D01*
Y538000D01*
X805000Y538700D01*
Y546700D01*
X805700Y547400D01*
Y549101D01*
X804788Y550013D01*
Y554389D01*
X805800Y555401D01*
Y556888D01*
X805000Y557688D01*
Y564700D01*
X805800Y565500D01*
Y567085D01*
X804488Y568397D01*
Y573142D01*
X805600Y574254D01*
Y576400D01*
X804800Y577200D01*
Y584000D01*
X805388Y584588D01*
Y586507D01*
X801988Y589907D01*
Y592399D01*
X803346Y593757D01*
G01X898813Y363373D02*
X898027D01*
X872300Y389100D01*
Y397499D01*
X831616Y438183D01*
X830484D01*
X827090Y434789D01*
X825958D01*
X808489Y452258D01*
Y453390D01*
X809620Y454521D01*
X810752D01*
X826120Y439153D01*
X827252D01*
X828383Y440284D01*
Y441416D01*
X808400Y461399D01*
Y464038D01*
X809596Y465234D01*
Y467238D01*
X808400Y468434D01*
Y470438D01*
X809596Y471634D01*
Y473638D01*
X808400Y474834D01*
Y476838D01*
X809596Y478034D01*
Y480038D01*
X808400Y481234D01*
Y483238D01*
X809596Y484434D01*
Y486438D01*
X808400Y487634D01*
Y489638D01*
X809596Y490834D01*
Y492838D01*
X808400Y494034D01*
Y496038D01*
X809596Y497234D01*
Y499204D01*
X807403Y501397D01*
Y510972D01*
X808688Y512257D01*
Y516807D01*
X807800Y517695D01*
Y520496D01*
X808900Y521596D01*
Y523056D01*
X807800Y524156D01*
Y529478D01*
X808788Y530466D01*
Y535712D01*
X807900Y536600D01*
Y539600D01*
X809100Y540800D01*
Y543300D01*
X807900Y544500D01*
Y549269D01*
X808688Y550057D01*
Y554607D01*
X808138Y555157D01*
Y558800D01*
X809300Y559962D01*
Y562638D01*
X808138Y563800D01*
Y567647D01*
X808988Y568497D01*
Y573012D01*
X807988Y574012D01*
Y576800D01*
X808900Y577712D01*
Y581488D01*
X807988Y582400D01*
Y587470D01*
X806692Y588766D01*
Y588714D01*
G01X899065Y355736D02*
X896764D01*
X863900Y388600D01*
Y394464D01*
X845564Y412800D01*
X828200D01*
X827465Y413535D01*
Y414327D01*
X831623Y418485D01*
Y419277D01*
X830604Y420296D01*
X829812D01*
X825654Y416138D01*
X824862D01*
X823843Y417157D01*
Y417949D01*
X828001Y422107D01*
Y422899D01*
X826982Y423918D01*
X826190D01*
X822032Y419760D01*
X821240D01*
X814400Y426600D01*
Y428600D01*
X800900Y442100D01*
Y487604D01*
X799500Y489004D01*
Y490500D01*
X800900Y491900D01*
Y497400D01*
X797400Y500900D01*
Y508000D01*
X799100Y509700D01*
Y510601D01*
X797500Y512201D01*
Y516001D01*
X799043Y517544D01*
Y519045D01*
X798300Y519788D01*
Y527700D01*
X798899Y528299D01*
Y529431D01*
X797600Y530730D01*
Y535300D01*
X799151Y536851D01*
Y538349D01*
X798300Y539200D01*
Y546200D01*
X798888Y546788D01*
Y549057D01*
X797700Y550245D01*
Y553901D01*
X798943Y555144D01*
Y556745D01*
X798300Y557388D01*
Y565500D01*
X798876Y566076D01*
Y567209D01*
X797300Y568785D01*
Y572654D01*
X798888Y574242D01*
Y575500D01*
X798300Y576088D01*
Y583900D01*
X799200Y584800D01*
Y586045D01*
X795988Y589257D01*
Y593092D01*
X796653Y593757D01*
G01X899044Y358236D02*
X898680Y358600D01*
X896700D01*
X866800Y388500D01*
Y395100D01*
X847100Y414800D01*
X838874D01*
X823015Y430659D01*
X822223D01*
X819678Y428114D01*
X818786D01*
X817775Y429125D01*
Y429833D01*
X820412Y432470D01*
Y433262D01*
X819393Y434281D01*
X818601D01*
X815456Y431136D01*
X814664D01*
X813645Y432155D01*
Y432947D01*
X816790Y436092D01*
Y436884D01*
X815771Y437903D01*
X814979D01*
X811834Y434758D01*
X811042D01*
X810023Y435777D01*
Y436569D01*
X813168Y439714D01*
Y440506D01*
X812149Y441525D01*
X811357D01*
X808212Y438380D01*
X807420D01*
X806401Y439399D01*
Y440191D01*
X809546Y443336D01*
Y444128D01*
X808527Y445147D01*
X807735D01*
X804590Y442002D01*
X803798D01*
X802779Y443021D01*
Y443813D01*
X805924Y446958D01*
Y447750D01*
X803400Y450274D01*
Y498700D01*
X802622Y499478D01*
Y502454D01*
X802012Y503064D01*
X799951D01*
X799341Y503674D01*
Y505654D01*
X799951Y506264D01*
X802012D01*
X802622Y506874D01*
Y507878D01*
X801388Y509112D01*
Y511257D01*
X802500Y512369D01*
Y516001D01*
X801083Y517418D01*
Y519483D01*
X802367Y520767D01*
Y527033D01*
X801089Y528311D01*
Y529443D01*
X802500Y530854D01*
Y535200D01*
X801100Y536600D01*
Y538300D01*
X801700Y538900D01*
Y546200D01*
X801000Y546900D01*
Y548669D01*
X802400Y550069D01*
Y553901D01*
X800983Y555318D01*
Y556795D01*
X801700Y557512D01*
Y565700D01*
X801212Y566188D01*
Y567321D01*
X802300Y568409D01*
Y573099D01*
X800900Y574499D01*
Y575700D01*
X801700Y576500D01*
Y584200D01*
X801388Y584512D01*
Y587368D01*
X801345D01*
X799999Y588714D01*
G01X816732Y593757D02*
X815299Y592324D01*
Y589807D01*
X818649Y586457D01*
Y584649D01*
X818400Y584400D01*
Y575749D01*
X818649Y575500D01*
Y574349D01*
X817499Y573199D01*
Y568367D01*
X818599Y567267D01*
Y565699D01*
X818400Y565500D01*
Y557199D01*
X818599Y557000D01*
Y555257D01*
X817449Y554107D01*
Y549857D01*
X818799Y548507D01*
Y546499D01*
X818400Y546100D01*
Y538199D01*
X818799Y537800D01*
Y536700D01*
X817449Y535350D01*
Y530617D01*
X818799Y529267D01*
Y527799D01*
X817607Y526607D01*
Y520792D01*
X818799Y519600D01*
Y517657D01*
X817449Y516307D01*
Y512057D01*
X818500Y511006D01*
Y508700D01*
X817900Y508100D01*
Y497018D01*
X818700Y496218D01*
X819400D01*
X820200Y495418D01*
Y493818D01*
X819400Y493018D01*
X818700D01*
X817900Y492218D01*
Y464628D01*
X886400Y396128D01*
Y385268D01*
X898968Y372700D01*
X902757D01*
X902856Y372601D01*
G01Y375168D02*
X902824Y375200D01*
X899134D01*
X888700Y385634D01*
Y397364D01*
X822500Y463564D01*
Y465662D01*
X821700Y466462D01*
X820669D01*
X819869Y467262D01*
Y468862D01*
X820669Y469662D01*
X821700D01*
X822500Y470462D01*
Y472062D01*
X821700Y472862D01*
X820753D01*
X819953Y473662D01*
Y475262D01*
X820753Y476062D01*
X821700D01*
X822500Y476862D01*
Y478462D01*
X821700Y479262D01*
X820600D01*
X819800Y480062D01*
Y481662D01*
X820600Y482462D01*
X821700D01*
X822500Y483262D01*
Y484862D01*
X821700Y485662D01*
X820669D01*
X819925Y486406D01*
Y488006D01*
X820781Y488862D01*
X821700D01*
X822500Y489662D01*
Y501961D01*
X821890Y502571D01*
X820658D01*
X820048Y503181D01*
Y505161D01*
X820658Y505771D01*
X821890D01*
X822500Y506381D01*
Y508000D01*
X820700Y509800D01*
Y511100D01*
X821299Y511699D01*
Y518600D01*
X822600Y519901D01*
Y521609D01*
X821990Y522219D01*
X820732D01*
X820122Y522829D01*
Y524809D01*
X820732Y525419D01*
X821990D01*
X822600Y526029D01*
Y527100D01*
X821299Y528401D01*
Y537700D01*
X821700Y538101D01*
Y545700D01*
X821299Y546101D01*
Y556400D01*
X821800Y556901D01*
Y565600D01*
X821299Y566101D01*
Y575500D01*
X821800Y576001D01*
Y584200D01*
X821299Y584701D01*
Y586443D01*
X819378Y588364D01*
Y588714D01*
G01X899326Y351676D02*
X896524D01*
X860300Y387900D01*
Y392791D01*
X843251Y409840D01*
X826960D01*
X811440Y425360D01*
Y427360D01*
X797220Y441580D01*
Y468080D01*
X796351Y468949D01*
X793386D01*
X791864Y470471D01*
Y473053D01*
X793320Y474509D01*
X796348D01*
X797220Y475381D01*
Y477077D01*
X796348Y477949D01*
X792568D01*
X791079Y479438D01*
Y482020D01*
X792568Y483509D01*
X796348D01*
X797220Y484381D01*
Y486077D01*
X796348Y486949D01*
X792209D01*
X790720Y488438D01*
Y491020D01*
X792209Y492509D01*
X796168D01*
X797040Y493381D01*
Y495188D01*
X793508Y498720D01*
Y538169D01*
X793035Y538642D01*
Y539642D01*
X793508Y540115D01*
Y541377D01*
X793003Y541882D01*
Y542882D01*
X793508Y543387D01*
Y544502D01*
X792888Y545122D01*
Y546122D01*
X793508Y546742D01*
Y557139D01*
X792888Y557759D01*
Y558759D01*
X793508Y559379D01*
Y560379D01*
X792888Y560999D01*
Y561999D01*
X793508Y562619D01*
Y563619D01*
X792888Y564239D01*
Y565239D01*
X793508Y565859D01*
Y576356D01*
X792888Y576976D01*
Y577976D01*
X793508Y578596D01*
Y579596D01*
X792888Y580216D01*
Y581216D01*
X793508Y581836D01*
Y582836D01*
X792888Y583456D01*
Y584456D01*
X793508Y585076D01*
Y587459D01*
X792453Y588514D01*
X791488D01*
G01X903680Y379475D02*
X899025D01*
X892400Y386100D01*
Y398871D01*
X826279Y464992D01*
Y487319D01*
X827151Y488191D01*
X828933D01*
X830422Y489680D01*
Y492262D01*
X828933Y493751D01*
X827151D01*
X826279Y494623D01*
Y496319D01*
X827151Y497191D01*
X828969D01*
X830506Y498728D01*
Y501310D01*
X829065Y502751D01*
X827151D01*
X826279Y503623D01*
Y579416D01*
X826899Y580036D01*
Y581036D01*
X826279Y581656D01*
Y582656D01*
X826899Y583276D01*
Y584276D01*
X826279Y584896D01*
Y587849D01*
X823228Y590900D01*
X823199D01*
G01X902185Y382660D02*
X901574Y382672D01*
X899028D01*
X895340Y386360D01*
Y399831D01*
X845496Y449675D01*
X845494D01*
Y451784D01*
X848355Y454646D01*
Y455872D01*
X847146Y457081D01*
X845922D01*
X843061Y454219D01*
X840949D01*
X839127Y456041D01*
Y458151D01*
X841988Y461013D01*
Y462242D01*
X840782Y463448D01*
X839553D01*
X837222Y461117D01*
X834582D01*
X832820Y462879D01*
Y468806D01*
X831948Y469678D01*
X831309D01*
X829920Y471067D01*
Y473849D01*
X831309Y475238D01*
X831948D01*
X832820Y476110D01*
Y477806D01*
X831948Y478678D01*
X831309D01*
X829820Y480167D01*
Y482749D01*
X831309Y484238D01*
X831948D01*
X832820Y485110D01*
Y505108D01*
X830319Y507609D01*
Y578633D01*
X829782Y579170D01*
Y580170D01*
X830319Y580707D01*
Y581874D01*
X829783Y582410D01*
Y583410D01*
X830319Y583946D01*
Y587595D01*
X829400Y588514D01*
X828299D01*
G01X899326Y352736D02*
X896964D01*
X861360Y388340D01*
Y393231D01*
X843691Y410900D01*
X827400D01*
X812500Y425800D01*
Y427800D01*
X798280Y442020D01*
Y468520D01*
X796791Y470009D01*
X793826D01*
X792924Y470911D01*
Y472613D01*
X793760Y473449D01*
X796788D01*
X798280Y474941D01*
Y477517D01*
X796788Y479009D01*
X793008D01*
X792139Y479878D01*
Y481580D01*
X793008Y482449D01*
X796788D01*
X798280Y483941D01*
Y486520D01*
X796791Y488009D01*
X792652D01*
X791780Y488881D01*
Y490580D01*
X792649Y491449D01*
X796608D01*
X798100Y492941D01*
Y495628D01*
X794568Y499160D01*
Y588070D01*
X791524Y591114D01*
X791488D01*
G01X903680Y378415D02*
X898585D01*
X891340Y385660D01*
Y398431D01*
X825221Y464550D01*
X825219D01*
Y487759D01*
X826711Y489251D01*
X828490D01*
X829362Y490123D01*
Y491822D01*
X828493Y492691D01*
X826711D01*
X825219Y494183D01*
Y496759D01*
X826711Y498251D01*
X828529D01*
X829446Y499168D01*
Y500870D01*
X828625Y501691D01*
X826711D01*
X825219Y503183D01*
Y587409D01*
X824328Y588300D01*
X823199D01*
G01X902205Y383720D02*
X901585Y383732D01*
X899468D01*
X896400Y386800D01*
Y400271D01*
X846554Y450117D01*
Y451345D01*
X849415Y454207D01*
Y456315D01*
X847589Y458141D01*
X845479D01*
X842618Y455279D01*
X841392D01*
X840187Y456484D01*
Y457712D01*
X843048Y460574D01*
Y462682D01*
X841222Y464508D01*
X839113D01*
X836782Y462177D01*
X835025D01*
X833880Y463322D01*
Y469249D01*
X832391Y470738D01*
X831752D01*
X830980Y471510D01*
Y473406D01*
X831752Y474178D01*
X832391D01*
X833880Y475667D01*
Y478249D01*
X832391Y479738D01*
X831752D01*
X830880Y480610D01*
Y482306D01*
X831752Y483178D01*
X832391D01*
X833880Y484667D01*
Y505551D01*
X831379Y508052D01*
Y588035D01*
X828300Y591114D01*
X828299D01*
G01X909107Y393292D02*
X909099Y393300D01*
X907200D01*
X904000Y396500D01*
Y403571D01*
X887452Y420119D01*
Y421251D01*
X888583Y422382D01*
X889715D01*
X900883Y411214D01*
X902015D01*
X903146Y412345D01*
Y413477D01*
X841800Y474823D01*
Y508900D01*
X842500Y509600D01*
Y510756D01*
X841599Y511657D01*
Y516499D01*
X842900Y517800D01*
Y518949D01*
X841800Y520049D01*
Y527700D01*
X842449Y528349D01*
Y529416D01*
X841499Y530366D01*
Y535598D01*
X842512Y536611D01*
Y538087D01*
X841900Y538699D01*
Y546100D01*
X842862Y547062D01*
Y548194D01*
X841599Y549457D01*
Y554857D01*
X842399Y555657D01*
Y557200D01*
X841800Y557799D01*
Y565500D01*
X842399Y566099D01*
Y567297D01*
X841299Y568397D01*
Y573142D01*
X842199Y574042D01*
Y575500D01*
X841800Y575899D01*
Y584200D01*
X842199Y584599D01*
Y586507D01*
X838799Y589907D01*
Y592399D01*
X840157Y593757D01*
G01X909107Y395823D02*
X906800Y398130D01*
Y406745D01*
X906162Y407383D01*
X903438D01*
X902856Y407965D01*
Y409355D01*
X903494Y409993D01*
X906162D01*
X906800Y410631D01*
Y413359D01*
X850900Y469259D01*
Y490100D01*
X850100Y490900D01*
X848500D01*
X847700Y490100D01*
Y474931D01*
X846900Y474131D01*
X845300D01*
X844500Y474931D01*
Y495033D01*
X845084Y495617D01*
X846696D01*
X847454Y496375D01*
Y497975D01*
X846612Y498817D01*
X845506D01*
X844899Y499424D01*
Y511657D01*
X845800Y512558D01*
Y516506D01*
X844949Y517357D01*
Y519200D01*
X845200Y519451D01*
Y526800D01*
X844600Y527400D01*
Y529467D01*
X845599Y530466D01*
Y535502D01*
X844600Y536501D01*
Y538201D01*
X845200Y538801D01*
Y546800D01*
X844899Y547101D01*
Y549457D01*
X845499Y550057D01*
Y554401D01*
X844400Y555500D01*
Y557399D01*
X845200Y558199D01*
Y564800D01*
X844500Y565500D01*
Y567198D01*
X845799Y568497D01*
Y573302D01*
X844400Y574701D01*
Y575801D01*
X845600Y577001D01*
Y583900D01*
X844799Y584701D01*
Y587470D01*
X843503Y588766D01*
Y588714D01*
G01X905285Y390289D02*
X901600Y393974D01*
Y402399D01*
X870465Y433534D01*
Y434666D01*
X871596Y435797D01*
X872728D01*
X885346Y423179D01*
X886578D01*
X887709Y424310D01*
Y425342D01*
X839000Y474051D01*
Y508300D01*
X838100Y509200D01*
Y511158D01*
X839099Y512157D01*
Y516301D01*
X837894Y517506D01*
Y518895D01*
X838500Y519501D01*
Y527600D01*
X837845Y528255D01*
Y529388D01*
X839500Y531043D01*
Y535001D01*
X837800Y536701D01*
Y538001D01*
X838500Y538701D01*
Y546200D01*
X837800Y546900D01*
Y548658D01*
X839400Y550258D01*
Y553700D01*
X837566Y555534D01*
Y556867D01*
X838500Y557801D01*
Y565200D01*
X837767Y565933D01*
Y567065D01*
X839100Y568398D01*
Y573300D01*
X837866Y574534D01*
Y576166D01*
X838500Y576800D01*
Y584299D01*
X838199Y584600D01*
Y587368D01*
X838156D01*
X836810Y588714D01*
G01X915307Y400093D02*
X909810Y405590D01*
Y416006D01*
X854900Y470916D01*
Y491800D01*
X851200Y495500D01*
Y499200D01*
X848900Y501500D01*
Y510807D01*
X848111Y511596D01*
Y516658D01*
X848576Y517123D01*
Y519434D01*
X848500Y519510D01*
Y527800D01*
X848702Y528002D01*
Y529598D01*
X847910Y530390D01*
Y535242D01*
X848726Y536058D01*
Y537784D01*
X848500Y538010D01*
Y546200D01*
X848811Y546511D01*
Y548656D01*
X848031Y549436D01*
Y554378D01*
X848659Y555006D01*
Y565959D01*
X848799Y566099D01*
Y567200D01*
X848015Y567984D01*
Y573197D01*
X848575Y573757D01*
Y584475D01*
X848760Y584660D01*
Y586457D01*
X846425Y588792D01*
Y593332D01*
X846850Y593757D01*
G01X840157D02*
X838452Y595462D01*
Y605649D01*
X843503Y610700D01*
G01Y588714D02*
X843415D01*
X841729Y590400D01*
Y592092D01*
X841904Y592267D01*
Y594900D01*
X840792Y596012D01*
Y597088D01*
X841804Y598100D01*
Y599300D01*
X840792Y600312D01*
Y601388D01*
X841929Y602525D01*
Y603799D01*
X841229Y604499D01*
X840157D01*
G01X810039Y593757D02*
X808334Y595462D01*
Y605635D01*
X812999Y610300D01*
G01X813085Y588714D02*
X812997D01*
X811311Y590400D01*
Y592600D01*
X811811Y593100D01*
Y594999D01*
X810674Y596136D01*
Y597464D01*
X811611Y598401D01*
Y599799D01*
X810674Y600736D01*
Y601964D01*
X811711Y603001D01*
Y603899D01*
X811111Y604499D01*
X810039D01*
G01X833464Y593757D02*
X831759Y595462D01*
Y605649D01*
X836810Y610700D01*
G01Y588714D02*
X836722D01*
X835036Y590400D01*
Y592092D01*
X835211Y592267D01*
Y594900D01*
X834099Y596012D01*
Y597088D01*
X835111Y598100D01*
Y599300D01*
X834099Y600312D01*
Y601388D01*
X835236Y602525D01*
Y603799D01*
X834536Y604499D01*
X833464D01*
G01X846850Y593757D02*
X845145Y595462D01*
Y605435D01*
X845767Y606057D01*
Y607245D01*
X848822Y610300D01*
X849810D01*
G01X849896Y588714D02*
X849808D01*
X848122Y590400D01*
Y592600D01*
X848622Y593100D01*
Y594999D01*
X847485Y596136D01*
Y597464D01*
X848422Y598401D01*
Y599799D01*
X847485Y600736D01*
Y601964D01*
X848522Y603001D01*
Y603899D01*
X847922Y604499D01*
X846850D01*
G01X803346Y593757D02*
X801641Y595462D01*
Y605649D01*
X806692Y610700D01*
G01Y588714D02*
X806604D01*
X804918Y590400D01*
Y592092D01*
X805093Y592267D01*
Y594900D01*
X803981Y596012D01*
Y597088D01*
X804993Y598100D01*
Y599300D01*
X803981Y600312D01*
Y601388D01*
X805118Y602525D01*
Y603799D01*
X804418Y604499D01*
X803346D01*
G01X796653Y593757D02*
X794948Y595462D01*
Y605649D01*
X799999Y610700D01*
G01Y588714D02*
X799911D01*
X798225Y590400D01*
Y592092D01*
X798400Y592267D01*
Y594900D01*
X797288Y596012D01*
Y597088D01*
X798300Y598100D01*
Y599300D01*
X797288Y600312D01*
Y601388D01*
X798425Y602525D01*
Y603799D01*
X797725Y604499D01*
X796653D01*
G01X819378Y610300D02*
X815027Y605949D01*
Y595462D01*
X816732Y593757D01*
G01X819378Y588714D02*
X819290D01*
X817604Y590400D01*
Y592092D01*
X818511Y592999D01*
Y594592D01*
X817367Y595736D01*
Y597156D01*
X818211Y598000D01*
Y599700D01*
X817367Y600544D01*
Y601756D01*
X818311Y602700D01*
Y603900D01*
X817712Y604499D01*
X816732D01*
G01X791488Y588514D02*
X791200D01*
X789783Y589931D01*
Y594900D01*
X788953Y595730D01*
Y602270D01*
X789783Y603100D01*
Y608044D01*
X791488Y609749D01*
G01X823199Y590900D02*
X824911Y592612D01*
Y594200D01*
X823811Y595300D01*
X822861D01*
X822271Y595890D01*
Y597260D01*
X822791Y597780D01*
X823401D01*
X824011Y598390D01*
Y599780D01*
X823401Y600390D01*
X822821D01*
X822271Y600940D01*
Y602360D01*
X822911Y603000D01*
X824191D01*
X824930Y603739D01*
Y605645D01*
X823225Y607350D01*
G01X828299Y588514D02*
X828011D01*
X826594Y589931D01*
Y594900D01*
X825764Y595730D01*
Y602270D01*
X826594Y603100D01*
Y608044D01*
X828299Y609749D01*
G01X791488Y591114D02*
X793200Y592826D01*
Y594500D01*
X792200Y595500D01*
X790684D01*
X790013Y596171D01*
Y597448D01*
X790465Y597900D01*
X790800D01*
X791500Y598600D01*
Y599688D01*
X790790Y600398D01*
X790553D01*
X790013Y600938D01*
Y601829D01*
X790784Y602600D01*
X792240D01*
X793300Y603660D01*
Y605328D01*
X791488Y607140D01*
G01X823199Y588300D02*
X822911D01*
X821211Y590000D01*
Y608011D01*
X823199Y609999D01*
G01X828299Y591114D02*
X830011Y592826D01*
Y594532D01*
X829043Y595500D01*
X827495D01*
X826824Y596171D01*
Y597448D01*
X827276Y597900D01*
X827611D01*
X828311Y598600D01*
Y599688D01*
X827601Y600398D01*
X827364D01*
X826824Y600938D01*
Y601829D01*
X827595Y602600D01*
X829111D01*
X830111Y603600D01*
Y605328D01*
X828299Y607140D01*
G01X853543Y17157D02*
X852422Y16036D01*
Y13100D01*
X855322Y10200D01*
Y8232D01*
X853789Y6699D01*
Y5500D01*
X855039Y4250D01*
Y3350D01*
X853689Y2000D01*
Y701D01*
X855322Y-932D01*
Y-3233D01*
X856189Y-4100D01*
G01X853543Y17157D02*
Y24442D01*
X855410Y26309D01*
Y28444D01*
X854260Y29594D01*
Y34259D01*
X855610Y35609D01*
Y36790D01*
X855000Y37400D01*
Y45790D01*
X855610Y46400D01*
Y47564D01*
X854260Y48914D01*
Y53160D01*
X855610Y54510D01*
Y66067D01*
X854260Y67417D01*
Y72059D01*
X855610Y73409D01*
Y74590D01*
X854800Y75400D01*
Y83200D01*
X855610Y84010D01*
Y85364D01*
X854260Y86714D01*
Y90960D01*
X855400Y92100D01*
Y108316D01*
X858200Y111116D01*
Y135532D01*
X902442Y179774D01*
Y180636D01*
X900520Y182558D01*
Y183420D01*
X901510Y184410D01*
X902372D01*
X904294Y182488D01*
X905156D01*
X906736Y184068D01*
Y184864D01*
X905328Y186272D01*
Y187064D01*
X918095Y199831D01*
X918296D01*
G01X856189Y12114D02*
X854116Y14187D01*
Y15216D01*
X855400Y16500D01*
Y22601D01*
X858110Y25311D01*
Y36810D01*
X858800Y37500D01*
Y45510D01*
X858110Y46200D01*
Y74810D01*
X858700Y75400D01*
Y83462D01*
X858110Y84052D01*
Y94290D01*
X857500Y94900D01*
Y106800D01*
X860700Y110000D01*
Y134556D01*
X909205Y183061D01*
Y187405D01*
X919131Y197331D01*
X919945D01*
G01X853543Y-9901D02*
Y-7779D01*
X855422Y-5900D01*
X856822D01*
X858278Y-4444D01*
Y-3100D01*
X857662Y-2484D01*
Y10641D01*
X856189Y12114D01*
G01X876968Y17157D02*
X878800Y18989D01*
Y28609D01*
X878500Y28909D01*
Y35001D01*
X878910Y35411D01*
Y36990D01*
X878344Y37556D01*
Y45534D01*
X878910Y46100D01*
Y48014D01*
X878310Y48614D01*
Y53314D01*
X879260Y54264D01*
Y65949D01*
X878410Y66799D01*
Y72611D01*
X878910Y73111D01*
Y74990D01*
X878500Y75400D01*
Y83590D01*
X878910Y84000D01*
Y85814D01*
X878310Y86414D01*
Y91114D01*
X878961Y91765D01*
Y109611D01*
X878461Y110111D01*
X877084D01*
X876010Y111185D01*
Y112221D01*
X876620Y112831D01*
X878372D01*
X878982Y113441D01*
Y114416D01*
X878372Y115026D01*
X876620D01*
X876010Y115636D01*
Y116565D01*
X876620Y117175D01*
X878372D01*
X878982Y117785D01*
Y119034D01*
X878372Y119644D01*
X876620D01*
X876010Y120254D01*
Y125010D01*
X893033Y142033D01*
Y142825D01*
X892075Y143783D01*
Y144575D01*
X893094Y145594D01*
X893886D01*
X894844Y144636D01*
X895636D01*
X901928Y150928D01*
Y151790D01*
X900421Y153297D01*
Y154159D01*
X901285Y155023D01*
X902147D01*
X903654Y153516D01*
X904516D01*
X905380Y154380D01*
Y155242D01*
X903873Y156749D01*
Y157611D01*
X904737Y158475D01*
X905599D01*
X907106Y156968D01*
X907968D01*
X908832Y157832D01*
Y158694D01*
X907325Y160201D01*
Y161063D01*
X909023Y162761D01*
X913261D01*
X915606Y165106D01*
Y168705D01*
X929801Y182900D01*
X931569D01*
X938139Y189470D01*
G01X880314Y-3700D02*
X878747Y-2133D01*
Y-932D01*
X877389Y426D01*
Y1799D01*
X878589Y2999D01*
Y4125D01*
X877389Y5325D01*
Y6900D01*
X879189Y8700D01*
Y9758D01*
X875847Y13100D01*
Y16036D01*
X876968Y17157D01*
G01X880314Y12114D02*
X878410Y14018D01*
Y15614D01*
X881760Y18964D01*
Y28699D01*
X882310Y29249D01*
Y34691D01*
X881710Y35291D01*
Y36910D01*
X882400Y37600D01*
Y45610D01*
X881710Y46300D01*
Y48064D01*
X882221Y48575D01*
Y53453D01*
X881760Y53914D01*
Y66499D01*
X882260Y66999D01*
Y72541D01*
X881710Y73091D01*
Y74610D01*
X882100Y75000D01*
Y83610D01*
X881710Y84000D01*
Y85914D01*
X882410Y86614D01*
Y91274D01*
X881461Y92223D01*
Y121699D01*
X880851Y122309D01*
X878769D01*
X878159Y122919D01*
Y124139D01*
X878769Y124749D01*
X880851D01*
X881461Y125359D01*
Y126926D01*
X917984Y163449D01*
Y167884D01*
X920566Y170466D01*
X922672D01*
X928279Y176073D01*
X929071D01*
X930027Y175117D01*
X930889D01*
X931753Y175981D01*
Y176843D01*
X929779Y178817D01*
Y179679D01*
X930800Y180700D01*
X933119D01*
X934186Y179633D01*
X935359D01*
X936708Y180982D01*
Y182562D01*
X937208Y183062D01*
X938788D01*
X939920Y184194D01*
Y186920D01*
G01X876968Y-9901D02*
X878215Y-8654D01*
Y-7400D01*
X879515Y-6100D01*
X880515D01*
X882315Y-4300D01*
Y-2900D01*
X881703Y-2288D01*
Y10725D01*
X880314Y12114D01*
G01X873621Y-3700D02*
X872147Y-2226D01*
Y-1132D01*
X870714Y301D01*
Y1524D01*
X872214Y3024D01*
Y4376D01*
X870714Y5876D01*
Y6999D01*
X872389Y8674D01*
Y10059D01*
X869347Y13101D01*
Y16229D01*
X870275Y17157D01*
G01D02*
X872100Y18982D01*
Y28709D01*
X871710Y29099D01*
Y34811D01*
X872100Y35201D01*
Y37300D01*
X871700Y37700D01*
Y45600D01*
X872100Y46000D01*
Y48324D01*
X871710Y48714D01*
Y53414D01*
X872110Y53814D01*
Y66499D01*
X871710Y66899D01*
Y72611D01*
X872510Y73411D01*
Y74790D01*
X871800Y75500D01*
Y83490D01*
X872510Y84200D01*
Y85714D01*
X871710Y86514D01*
Y91214D01*
X872100Y91604D01*
Y96556D01*
X870810Y97846D01*
Y130509D01*
X872299Y131998D01*
X873161D01*
X874365Y130794D01*
X875227D01*
X876091Y131658D01*
Y132520D01*
X874887Y133724D01*
Y134586D01*
X875751Y135450D01*
X876613D01*
X877817Y134246D01*
X878679D01*
X879543Y135110D01*
Y135972D01*
X878339Y137176D01*
Y138038D01*
X879203Y138902D01*
X880065D01*
X881269Y137698D01*
X882131D01*
X882995Y138562D01*
Y139424D01*
X881791Y140628D01*
Y141490D01*
X921469Y181168D01*
Y182030D01*
X920121Y183378D01*
Y184240D01*
X920985Y185104D01*
X921847D01*
X923195Y183756D01*
X924057D01*
X924921Y184620D01*
Y185482D01*
X923573Y186830D01*
Y187692D01*
X924437Y188556D01*
X925299D01*
X926647Y187208D01*
X927509D01*
X931741Y191440D01*
X933097D01*
G01X873621Y12114D02*
X871810Y13925D01*
Y16014D01*
X875100Y19304D01*
Y28689D01*
X875500Y29089D01*
Y34901D01*
X875100Y35301D01*
Y37300D01*
X875400Y37600D01*
Y45900D01*
X875100Y46200D01*
Y48004D01*
X875810Y48714D01*
Y53214D01*
X875110Y53914D01*
Y66499D01*
X875910Y67299D01*
Y72191D01*
X875010Y73091D01*
Y74810D01*
X875600Y75400D01*
Y83310D01*
X875010Y83900D01*
Y85714D01*
X875810Y86514D01*
Y91014D01*
X875100Y91724D01*
Y97077D01*
X873310Y98867D01*
Y100852D01*
X873920Y101462D01*
X874988D01*
X875598Y102072D01*
Y103292D01*
X874988Y103902D01*
X873920D01*
X873310Y104512D01*
Y105732D01*
X873920Y106342D01*
X874988D01*
X875598Y106952D01*
Y108172D01*
X874988Y108782D01*
X873920D01*
X873310Y109392D01*
Y126010D01*
X888996Y141696D01*
Y145495D01*
X894589Y151088D01*
X895452D01*
X895979Y150561D01*
X896687D01*
X897705Y151579D01*
Y152287D01*
X897177Y152815D01*
Y153676D01*
X929101Y185600D01*
X930733D01*
X934570Y189437D01*
G01X870275Y-9901D02*
X871522Y-8654D01*
Y-7400D01*
X872822Y-6100D01*
X873822D01*
X875622Y-4300D01*
Y-2900D01*
X875010Y-2288D01*
Y10725D01*
X873621Y12114D01*
G01X890354Y17157D02*
X889233Y16036D01*
Y13100D01*
X892133Y10200D01*
Y8232D01*
X890600Y6699D01*
Y5500D01*
X891850Y4250D01*
Y3350D01*
X890500Y2000D01*
Y701D01*
X892133Y-932D01*
Y-3233D01*
X893000Y-4100D01*
G01X890354Y17157D02*
Y25054D01*
X892221Y26921D01*
Y28444D01*
X891200Y29465D01*
Y34400D01*
X892200Y35400D01*
Y37200D01*
X891800Y37600D01*
Y45900D01*
X892200Y46300D01*
Y47785D01*
X891071Y48914D01*
Y53172D01*
X892300Y54401D01*
Y66188D01*
X891100Y67388D01*
Y72012D01*
X892421Y73333D01*
Y74579D01*
X891900Y75100D01*
Y83579D01*
X892421Y84100D01*
Y85364D01*
X891071Y86714D01*
Y90972D01*
X892421Y92322D01*
Y104827D01*
X891074Y106174D01*
Y110374D01*
X892174Y111474D01*
Y115585D01*
X894260Y117671D01*
Y118802D01*
X892335Y120727D01*
Y121435D01*
X893890Y122990D01*
X894598D01*
X896524Y121064D01*
X897653D01*
X898889Y122300D01*
Y123433D01*
X896443Y125879D01*
Y126587D01*
X916094Y146238D01*
Y148830D01*
X957600Y190336D01*
Y197503D01*
X963497Y203400D01*
G01X890354Y-9901D02*
Y-7779D01*
X892233Y-5900D01*
X893633D01*
X895089Y-4444D01*
Y-3100D01*
X894473Y-2484D01*
Y10641D01*
X893000Y12114D01*
G01D02*
X890927Y14187D01*
Y15228D01*
X892421Y16722D01*
Y23421D01*
X894921Y25921D01*
Y37221D01*
X895500Y37800D01*
Y45521D01*
X894921Y46100D01*
Y74821D01*
X895500Y75400D01*
Y83401D01*
X894921Y83980D01*
Y114796D01*
X900800Y120675D01*
Y127654D01*
X918502Y145356D01*
Y147702D01*
X960500Y189700D01*
Y196533D01*
X965732Y201765D01*
G01X886621Y-4100D02*
X885533Y-3012D01*
Y-1132D01*
X884100Y301D01*
Y1500D01*
X885600Y3000D01*
Y4200D01*
X884150Y5650D01*
Y7049D01*
X885533Y8432D01*
Y10301D01*
X882733Y13101D01*
Y16229D01*
X883661Y17157D01*
G01D02*
X885621Y19117D01*
Y28479D01*
X884721Y29379D01*
Y34299D01*
X885721Y35299D01*
Y36779D01*
X885200Y37300D01*
Y45679D01*
X885721Y46200D01*
Y47614D01*
X884721Y48614D01*
Y53414D01*
X885621Y54314D01*
Y66179D01*
X884721Y67079D01*
Y72099D01*
X885721Y73099D01*
Y74679D01*
X885200Y75200D01*
Y83499D01*
X885721Y84020D01*
Y85414D01*
X884721Y86414D01*
Y91214D01*
X885621Y92114D01*
Y105027D01*
X884774Y105874D01*
Y110674D01*
X885461Y111361D01*
Y125269D01*
X922442Y162250D01*
Y163382D01*
X921708Y164116D01*
Y164908D01*
X923179Y166379D01*
X923971D01*
X924705Y165645D01*
X925837D01*
X949700Y189508D01*
Y192100D01*
X948700Y193100D01*
Y196900D01*
X951500Y199700D01*
Y201980D01*
X954120Y204600D01*
G01X886707Y12114D02*
X887933Y10888D01*
Y-2125D01*
X888708Y-2900D01*
Y-4524D01*
X887132Y-6100D01*
X885908D01*
X883661Y-8347D01*
Y-9901D01*
G01X886707Y12114D02*
X884721Y14100D01*
Y15514D01*
X888000Y18793D01*
Y28278D01*
X888554Y28832D01*
Y36796D01*
X889700Y37942D01*
Y44721D01*
X888221Y46200D01*
Y48314D01*
X888571Y48664D01*
Y53614D01*
X888321Y53864D01*
Y64521D01*
X888500Y64700D01*
Y74899D01*
X889000Y75399D01*
Y83300D01*
X888400Y83900D01*
Y86293D01*
X888550Y86443D01*
Y103350D01*
X888321Y103579D01*
Y105621D01*
X888574Y105874D01*
Y111174D01*
X887974Y111774D01*
Y124246D01*
X954700Y190972D01*
Y201636D01*
X956000Y202936D01*
G01X910432Y-3700D02*
X908958Y-2226D01*
Y-1132D01*
X907525Y301D01*
Y1524D01*
X909025Y3024D01*
Y4376D01*
X907525Y5876D01*
Y6999D01*
X909200Y8674D01*
Y10059D01*
X906158Y13101D01*
Y16229D01*
X907086Y17157D01*
G01D02*
Y19379D01*
X909121Y21414D01*
Y28499D01*
X908521Y29099D01*
Y34721D01*
X909321Y35521D01*
Y36979D01*
X908600Y37700D01*
Y45679D01*
X909321Y46400D01*
Y47914D01*
X908521Y48714D01*
Y53414D01*
X908921Y53814D01*
Y66499D01*
X908521Y66899D01*
Y72521D01*
X909321Y73321D01*
Y74979D01*
X908700Y75600D01*
Y83499D01*
X909321Y84120D01*
Y85714D01*
X908521Y86514D01*
Y91214D01*
X908921Y91614D01*
Y105627D01*
X908174Y106374D01*
Y110474D01*
X909174Y111474D01*
Y114682D01*
X934138Y139646D01*
Y140508D01*
X930912Y143734D01*
Y144596D01*
X931776Y145460D01*
X932638D01*
X935903Y142195D01*
X936695D01*
X937629Y143129D01*
Y143921D01*
X934300Y147250D01*
Y149165D01*
X978000Y192865D01*
Y195407D01*
X977976Y195431D01*
G01X910432Y12114D02*
X908621Y13925D01*
Y16014D01*
X910071Y17464D01*
Y18828D01*
X911921Y20678D01*
Y25355D01*
X911621Y25655D01*
Y28399D01*
X912721Y29499D01*
Y34379D01*
X911821Y35279D01*
Y37121D01*
X912400Y37700D01*
Y45621D01*
X911821Y46200D01*
Y47914D01*
X912621Y48714D01*
Y53214D01*
X911921Y53914D01*
Y66499D01*
X912721Y67299D01*
Y72279D01*
X911821Y73179D01*
Y75121D01*
X912400Y75700D01*
Y83221D01*
X911821Y83800D01*
Y85714D01*
X912621Y86514D01*
Y91014D01*
X911921Y91714D01*
Y105121D01*
X912574Y105774D01*
Y110674D01*
X911774Y111474D01*
Y113746D01*
X940700Y142672D01*
Y152029D01*
X980326Y191655D01*
Y195421D01*
G01X907086Y-9901D02*
X908333Y-8654D01*
Y-7400D01*
X909633Y-6100D01*
X910633D01*
X912433Y-4300D01*
Y-2900D01*
X911821Y-2288D01*
Y10725D01*
X910432Y12114D01*
G01X860010Y14300D02*
X863116Y11194D01*
Y-4952D01*
X861788Y-6280D01*
X860806D01*
X860036Y-7050D01*
G01X860010Y14300D02*
X861736Y16026D01*
Y18100D01*
X860936Y18900D01*
X859936D01*
X859216Y19620D01*
Y20688D01*
X863090Y24562D01*
Y36780D01*
X863710Y37400D01*
Y38400D01*
X863090Y39020D01*
Y39780D01*
X863710Y40400D01*
Y41400D01*
X863090Y42020D01*
Y42780D01*
X863710Y43400D01*
Y44400D01*
X863090Y45020D01*
Y55980D01*
X863710Y56600D01*
Y57600D01*
X863090Y58220D01*
Y98193D01*
X860680Y100603D01*
Y103125D01*
X862257Y104702D01*
X862888D01*
X864380Y106194D01*
Y133572D01*
X893377Y162569D01*
X894013D01*
X894721Y163277D01*
Y163913D01*
X895633Y164825D01*
X896269D01*
X896977Y165533D01*
Y166169D01*
X897684Y166876D01*
X898320D01*
X899028Y167584D01*
Y168220D01*
X899735Y168927D01*
X900371D01*
X901079Y169635D01*
Y170271D01*
X901786Y170978D01*
X902422D01*
X903130Y171686D01*
Y172322D01*
X903837Y173029D01*
X904473D01*
X905181Y173737D01*
Y174373D01*
X905888Y175080D01*
X906524D01*
X907232Y175788D01*
Y176424D01*
X907939Y177131D01*
X908576D01*
X909284Y177839D01*
Y178476D01*
X910477Y179669D01*
X911113D01*
X911821Y180377D01*
Y181013D01*
X912598Y181790D01*
Y185567D01*
X914189Y187158D01*
X914827D01*
X915535Y187866D01*
Y188503D01*
X916636Y189604D01*
X917273D01*
X917981Y190312D01*
Y190949D01*
X920466Y193434D01*
X923802Y195507D01*
X924749Y197181D01*
G01X896821Y14300D02*
X899927Y11194D01*
Y-4952D01*
X898599Y-6280D01*
X897617D01*
X896847Y-7050D01*
G01X896821Y14300D02*
X898547Y16026D01*
Y17752D01*
X897399Y18900D01*
X896747D01*
X896027Y19620D01*
Y21088D01*
X899901Y24962D01*
Y36780D01*
X900521Y37400D01*
Y38400D01*
X899901Y39020D01*
Y39780D01*
X900521Y40400D01*
Y41400D01*
X899901Y42020D01*
Y42780D01*
X900521Y43400D01*
Y44400D01*
X899901Y45020D01*
Y55880D01*
X900521Y56500D01*
Y57500D01*
X899901Y58120D01*
Y114569D01*
X907142Y121810D01*
Y123922D01*
X904725Y126339D01*
Y127379D01*
X906625Y129279D01*
X907785D01*
X910142Y126922D01*
X912254D01*
X923471Y138139D01*
Y147464D01*
X947167Y171160D01*
X947803D01*
X948511Y171868D01*
Y172504D01*
X949218Y173211D01*
X949854D01*
X950562Y173919D01*
Y174555D01*
X951343Y175336D01*
X951980D01*
X952688Y176044D01*
Y176681D01*
X953659Y177652D01*
X954295D01*
X955003Y178360D01*
Y178996D01*
X955710Y179703D01*
X956347D01*
X957055Y180411D01*
Y181048D01*
X957866Y181859D01*
X958502D01*
X959210Y182567D01*
Y183203D01*
X959917Y183910D01*
X960553D01*
X961261Y184618D01*
Y185254D01*
X962180Y186173D01*
X962817D01*
X963525Y186881D01*
Y187518D01*
X964260Y188253D01*
Y190343D01*
X964710Y190793D01*
Y191793D01*
X964260Y192243D01*
Y193448D01*
X969300Y198488D01*
G01X865110Y14514D02*
X868302Y11322D01*
Y-4068D01*
X865110Y-7260D01*
G01Y14514D02*
X866936Y16340D01*
Y17900D01*
X864916Y19920D01*
Y20788D01*
X865890Y21762D01*
X866766D01*
X867474Y22470D01*
Y23346D01*
X868810Y24682D01*
Y25514D01*
X868190Y26134D01*
Y131897D01*
X916132Y179839D01*
Y183725D01*
X917289Y184882D01*
X917926D01*
X918634Y185590D01*
Y186227D01*
X919941Y187534D01*
X920578D01*
X921286Y188242D01*
Y188879D01*
X922453Y190046D01*
X928711Y195088D01*
X930741Y197119D01*
G01X901921Y14514D02*
X905113Y11322D01*
Y-4068D01*
X901921Y-7260D01*
G01Y14514D02*
X903747Y16340D01*
Y17900D01*
X901727Y19920D01*
Y20788D01*
X902701Y21762D01*
X903577D01*
X904285Y22470D01*
Y23346D01*
X905001Y24062D01*
Y32500D01*
X905600Y33099D01*
Y33901D01*
X905001Y34500D01*
Y36980D01*
X905621Y37600D01*
Y38600D01*
X905001Y39220D01*
Y39980D01*
X905621Y40600D01*
Y41600D01*
X905001Y42220D01*
Y114269D01*
X928043Y137311D01*
Y146618D01*
X972990Y191565D01*
Y193803D01*
X975468Y196281D01*
G01X860010Y11700D02*
X861109D01*
X862056Y10753D01*
Y8220D01*
X861086Y7250D01*
X860738D01*
X860122Y6634D01*
Y5302D01*
X860624Y4800D01*
X861336D01*
X862056Y4080D01*
Y3120D01*
X861236Y2300D01*
X860736D01*
X860136Y1700D01*
Y700D01*
X862056Y-1220D01*
Y-4509D01*
X861345Y-5220D01*
X860829D01*
X860010Y-4401D01*
G01Y11700D02*
X858156Y13554D01*
Y21131D01*
X862030Y25005D01*
Y97753D01*
X859620Y100163D01*
Y103565D01*
X861817Y105762D01*
X862448D01*
X863320Y106634D01*
Y134012D01*
X911538Y182230D01*
Y186007D01*
X919802Y194271D01*
X923012Y196265D01*
X923826Y197703D01*
G01X896821Y11700D02*
X897920D01*
X898867Y10753D01*
Y8220D01*
X897897Y7250D01*
X897549D01*
X896933Y6634D01*
Y5302D01*
X897435Y4800D01*
X898147D01*
X898867Y4080D01*
Y3120D01*
X898047Y2300D01*
X897547D01*
X896947Y1700D01*
Y700D01*
X898867Y-1220D01*
Y-4509D01*
X898156Y-5220D01*
X897640D01*
X896821Y-4401D01*
G01Y11700D02*
X894967Y13554D01*
Y21531D01*
X898841Y25405D01*
Y115009D01*
X906082Y122250D01*
Y123482D01*
X903665Y125899D01*
Y127819D01*
X906185Y130339D01*
X908225D01*
X910582Y127982D01*
X911814D01*
X922411Y138579D01*
Y147904D01*
X963200Y188693D01*
Y193888D01*
X968550Y199238D01*
G01X865110Y-4651D02*
X866219D01*
X867242Y-3628D01*
Y-1007D01*
X866535Y-300D01*
X865737D01*
X865136Y301D01*
Y1499D01*
X865737Y2100D01*
X866435D01*
X867242Y2907D01*
Y4280D01*
X866522Y5000D01*
X866022D01*
X865322Y5700D01*
Y6700D01*
X866022Y7400D01*
X866536D01*
X867242Y8106D01*
Y10881D01*
X866208Y11915D01*
X865110D01*
Y11914D01*
G01D02*
X863386Y13638D01*
Y18285D01*
X863856Y18755D01*
Y21231D01*
X867130Y24505D01*
Y132337D01*
X915072Y180279D01*
Y184165D01*
X921743Y190836D01*
X928001Y195878D01*
X929992Y197869D01*
G01X901921Y-4651D02*
X903030D01*
X904053Y-3628D01*
Y-1007D01*
X903346Y-300D01*
X902548D01*
X901947Y301D01*
Y1499D01*
X902548Y2100D01*
X903246D01*
X904053Y2907D01*
Y4280D01*
X903333Y5000D01*
X902833D01*
X902133Y5700D01*
Y6700D01*
X902833Y7400D01*
X903347D01*
X904053Y8106D01*
Y10881D01*
X903019Y11915D01*
X901921D01*
Y11914D01*
G01D02*
X900197Y13638D01*
Y18097D01*
X900667Y18567D01*
Y21231D01*
X903941Y24505D01*
Y114709D01*
X926983Y137751D01*
Y147058D01*
X967293Y187368D01*
Y188005D01*
X968001Y188713D01*
X968638D01*
X969740Y189815D01*
Y190451D01*
X970448Y191159D01*
X971084D01*
X971930Y192005D01*
Y194243D01*
X972637Y194950D01*
Y195586D01*
X973345Y196294D01*
X973981D01*
X974718Y197031D01*
G01X918712Y404597D02*
X913580Y409729D01*
Y419308D01*
X860200Y472688D01*
Y494100D01*
X856300Y498000D01*
Y506300D01*
X855610Y506990D01*
Y510707D01*
X854260Y512057D01*
Y516307D01*
X855610Y517657D01*
Y519500D01*
X855200Y519910D01*
Y527800D01*
X855610Y528210D01*
Y529267D01*
X854260Y530617D01*
Y535260D01*
X855610Y536610D01*
Y538490D01*
X855200Y538900D01*
Y546100D01*
X855610Y546510D01*
Y548507D01*
X854260Y549857D01*
Y554107D01*
X855410Y555257D01*
Y557400D01*
X855200Y557610D01*
Y565700D01*
X855410Y565910D01*
Y567267D01*
X854310Y568367D01*
Y573109D01*
X855460Y574259D01*
Y575600D01*
X855200Y575860D01*
Y584300D01*
X855460Y584560D01*
Y586457D01*
X852110Y589807D01*
Y592324D01*
X853543Y593757D01*
G01X920480Y406365D02*
X915465Y411380D01*
Y420959D01*
X864118Y472306D01*
Y474725D01*
X863508Y475335D01*
X862697D01*
X862087Y475945D01*
Y477925D01*
X862697Y478535D01*
X863508D01*
X864118Y479145D01*
Y481125D01*
X863508Y481735D01*
X862697D01*
X862087Y482345D01*
Y484325D01*
X862697Y484935D01*
X863704D01*
X864314Y485545D01*
Y487525D01*
X863704Y488135D01*
X862697D01*
X862087Y488745D01*
Y490725D01*
X862697Y491335D01*
X863508D01*
X864118Y491945D01*
Y493882D01*
X858900Y499100D01*
Y507920D01*
X858057Y508763D01*
Y518557D01*
X859600Y520100D01*
Y521416D01*
X858057Y522959D01*
Y524801D01*
X859287Y526031D01*
Y527413D01*
X858110Y528590D01*
Y537710D01*
X859063Y538663D01*
Y540400D01*
X858000Y541463D01*
Y542737D01*
X859063Y543800D01*
Y545737D01*
X858110Y546690D01*
Y556610D01*
X858600Y557100D01*
Y559900D01*
X857600Y560900D01*
Y563400D01*
X858600Y564400D01*
Y565900D01*
X858110Y566390D01*
Y575610D01*
X858600Y576100D01*
Y578200D01*
X857600Y579200D01*
Y580700D01*
X858600Y581700D01*
Y583700D01*
X858110Y584190D01*
Y586443D01*
X856189Y588364D01*
Y588714D01*
G01X936511Y414896D02*
X932900Y418507D01*
Y434633D01*
X931646Y435887D01*
Y437017D01*
X932999Y438369D01*
Y439499D01*
X931866Y440632D01*
X930736D01*
X929383Y439280D01*
X928253D01*
X916752Y450781D01*
X915622D01*
X913787Y448945D01*
X912657D01*
X911738Y449864D01*
Y450996D01*
X913655Y452913D01*
Y454045D01*
X912524Y455176D01*
X911392D01*
X909475Y453259D01*
X908343D01*
X878811Y482791D01*
Y511256D01*
X878100Y511967D01*
Y516307D01*
X878800Y517007D01*
Y526500D01*
X879600Y527300D01*
Y529100D01*
X878000Y530700D01*
Y535400D01*
X879273Y536673D01*
Y537727D01*
X878100Y538900D01*
Y546100D01*
X879400Y547400D01*
Y549099D01*
X878410Y550089D01*
Y554309D01*
X879600Y555499D01*
Y557500D01*
X878700Y558400D01*
Y564200D01*
X879600Y565100D01*
Y566907D01*
X878110Y568397D01*
Y573210D01*
X879400Y574500D01*
Y575800D01*
X878300Y576900D01*
Y584200D01*
X879200Y585100D01*
Y587101D01*
X878201Y588100D01*
X876800D01*
X875610Y589290D01*
Y592399D01*
X876968Y593757D01*
G01X938279Y416664D02*
X935500Y419443D01*
Y441000D01*
X932051Y444449D01*
X930919D01*
X929501Y443031D01*
X928369D01*
X927238Y444162D01*
Y445294D01*
X929285Y447341D01*
Y448424D01*
X928154Y449555D01*
X926973D01*
X924975Y447557D01*
X923843D01*
X922712Y448688D01*
Y449820D01*
X925001Y452109D01*
Y453192D01*
X923870Y454323D01*
X922689D01*
X920449Y452083D01*
X919317D01*
X918047Y453353D01*
Y454485D01*
X920180Y456618D01*
Y457630D01*
X919049Y458761D01*
X917797D01*
X915784Y456748D01*
X914652D01*
X913500Y457900D01*
X907500D01*
X881100Y484300D01*
Y500100D01*
X882100Y501100D01*
Y508800D01*
X881710Y509190D01*
Y511657D01*
X882310Y512257D01*
Y516807D01*
X881760Y517357D01*
Y519200D01*
X882000Y519440D01*
Y527700D01*
X881760Y527940D01*
Y529816D01*
X882410Y530466D01*
Y535490D01*
X881710Y536190D01*
Y537500D01*
X882000Y537790D01*
Y540500D01*
X881200Y541300D01*
Y543600D01*
X882000Y544400D01*
Y546300D01*
X881710Y546590D01*
Y549457D01*
X882310Y550057D01*
Y554607D01*
X881760Y555157D01*
Y556900D01*
X882000Y557140D01*
Y565500D01*
X881760Y565740D01*
Y567647D01*
X882610Y568497D01*
Y573190D01*
X881610Y574190D01*
Y575400D01*
X882000Y575790D01*
Y584400D01*
X881610Y584790D01*
Y587470D01*
X880314Y588766D01*
Y588714D01*
G01X917084Y401870D02*
X911695Y407259D01*
Y417657D01*
X857500Y471852D01*
Y493000D01*
X853800Y496700D01*
Y501400D01*
X852600Y502600D01*
Y508310D01*
X851410Y509500D01*
Y511397D01*
X852164Y512151D01*
Y516803D01*
X851242Y517725D01*
Y520108D01*
X852443Y521309D01*
Y526813D01*
X851510Y527746D01*
Y529992D01*
X851996Y530478D01*
Y535194D01*
X851046Y536144D01*
Y537988D01*
X852303Y539245D01*
Y545397D01*
X851270Y546430D01*
Y548317D01*
X852136Y549183D01*
Y554303D01*
X851242Y555197D01*
Y556732D01*
X851900Y557390D01*
Y565044D01*
X851270Y565674D01*
Y567757D01*
X852010Y568497D01*
Y573146D01*
X851158Y573998D01*
Y575558D01*
X852600Y577000D01*
Y578600D01*
X851300Y579900D01*
Y581200D01*
X852600Y582500D01*
Y583600D01*
X851410Y584790D01*
Y587790D01*
X850486Y588714D01*
X849896D01*
G01X932706Y410791D02*
X927900Y415597D01*
Y426300D01*
X926106Y428094D01*
Y429226D01*
X927824Y430944D01*
Y432076D01*
X926693Y433207D01*
X925561D01*
X923543Y431189D01*
X922411D01*
X921272Y432328D01*
Y433460D01*
X921890Y434078D01*
Y435210D01*
X920759Y436341D01*
X919627D01*
X919309Y436023D01*
X918177D01*
X873700Y480500D01*
Y499300D01*
X871134Y501866D01*
Y508134D01*
X872555Y509555D01*
Y511212D01*
X871300Y512467D01*
Y516547D01*
X872110Y517357D01*
Y529842D01*
X871710Y530242D01*
Y535710D01*
X872700Y536700D01*
Y538000D01*
X871700Y539000D01*
Y546500D01*
X872510Y547310D01*
Y549057D01*
X871200Y550367D01*
Y554099D01*
X872500Y555399D01*
Y556710D01*
X872000Y557210D01*
Y564200D01*
X872600Y564800D01*
Y567107D01*
X871237Y568470D01*
Y572969D01*
X872468Y574200D01*
Y575332D01*
X871500Y576300D01*
Y584000D01*
X872510Y585010D01*
Y586357D01*
X869610Y589257D01*
Y593092D01*
X870275Y593757D01*
G01X934724Y412309D02*
X930400Y416633D01*
Y433500D01*
X926070Y437830D01*
X924938D01*
X924520Y437412D01*
X923388D01*
X922257Y438543D01*
Y439675D01*
X922675Y440093D01*
Y441225D01*
X921313Y442587D01*
X920181D01*
X918263Y440669D01*
X917131D01*
X916000Y441800D01*
Y442932D01*
X917918Y444850D01*
Y445982D01*
X916787Y447113D01*
X915655D01*
X913837Y445295D01*
X912705D01*
X876300Y481700D01*
Y502106D01*
X875690Y502716D01*
X874017D01*
X873407Y503326D01*
Y505306D01*
X874017Y505916D01*
X875690D01*
X876300Y506526D01*
Y507800D01*
X874800Y509300D01*
Y511047D01*
X875800Y512047D01*
Y516199D01*
X874500Y517499D01*
Y518428D01*
X876261Y520189D01*
Y521475D01*
X875651Y522085D01*
X874961D01*
X874351Y522695D01*
Y524675D01*
X874961Y525285D01*
X875651D01*
X876261Y525895D01*
Y527131D01*
X874700Y528692D01*
Y529432D01*
X875810Y530542D01*
Y535490D01*
X874700Y536600D01*
Y538600D01*
X875400Y539300D01*
Y540600D01*
X874404Y541596D01*
Y543204D01*
X875400Y544200D01*
Y546000D01*
X874800Y546600D01*
Y548847D01*
X876000Y550047D01*
Y553899D01*
X874500Y555399D01*
Y556890D01*
X875300Y557690D01*
Y559400D01*
X874100Y560600D01*
Y561800D01*
X875300Y563000D01*
Y565500D01*
X874717Y566083D01*
Y567216D01*
X876000Y568499D01*
Y573001D01*
X874567Y574434D01*
Y575867D01*
X875300Y576600D01*
Y578200D01*
X874100Y579400D01*
Y580900D01*
X875300Y582100D01*
Y584800D01*
X874600Y585500D01*
Y587735D01*
X873621Y588714D01*
G01X953983Y403882D02*
Y409517D01*
X939600Y423900D01*
Y442900D01*
X920665Y461835D01*
X909289D01*
X885774Y485350D01*
Y488426D01*
X884774Y489426D01*
Y502174D01*
X885000Y502400D01*
Y508600D01*
X885800Y509400D01*
Y510718D01*
X884721Y511797D01*
Y516457D01*
X885621Y517357D01*
Y519300D01*
X885300Y519621D01*
Y527900D01*
X885883Y528483D01*
Y529216D01*
X884721Y530378D01*
Y535242D01*
X885721Y536242D01*
Y537800D01*
X885300Y538221D01*
Y546600D01*
X885721Y547021D01*
Y548557D01*
X884721Y549557D01*
Y554221D01*
X886076Y555576D01*
Y557125D01*
X885300Y557901D01*
Y565400D01*
X885621Y565721D01*
Y567179D01*
X884573Y568227D01*
Y572944D01*
X885571Y573942D01*
Y575728D01*
X885300Y575999D01*
Y583900D01*
X885571Y584171D01*
Y586457D01*
X882421Y589607D01*
Y592517D01*
X883661Y593757D01*
G01X923224Y409536D02*
X918560Y414200D01*
Y423072D01*
X867280Y474352D01*
Y495952D01*
X863090Y500142D01*
Y587849D01*
X860039Y590900D01*
X860010D01*
G01X924361Y412486D02*
X921440Y415407D01*
Y425732D01*
X919648Y427524D01*
X919008D01*
X916285Y430247D01*
Y432544D01*
X914938Y433891D01*
X911878D01*
X909918Y435851D01*
Y438911D01*
X908571Y440258D01*
X905511D01*
X903551Y442218D01*
Y445278D01*
X902204Y446625D01*
X899144D01*
X897184Y448585D01*
Y451645D01*
X895837Y452992D01*
X892777D01*
X890817Y454952D01*
Y458012D01*
X889470Y459359D01*
X886410D01*
X884450Y461319D01*
Y464379D01*
X883103Y465726D01*
X880046D01*
X878083Y467689D01*
Y470114D01*
X876104Y472093D01*
X874676D01*
X871716Y475053D01*
Y477113D01*
X870020Y478809D01*
Y497209D01*
X867194Y500035D01*
Y522200D01*
X866574Y522820D01*
Y523820D01*
X867194Y524440D01*
Y525776D01*
X866574Y526396D01*
Y527396D01*
X867194Y528016D01*
Y538181D01*
X866574Y538801D01*
Y539801D01*
X867194Y540421D01*
Y541421D01*
X866574Y542041D01*
Y543041D01*
X867194Y543661D01*
Y544661D01*
X866574Y545281D01*
Y546281D01*
X867194Y546901D01*
Y556844D01*
X866574Y557464D01*
Y558464D01*
X867194Y559084D01*
Y560084D01*
X866574Y560704D01*
Y561704D01*
X867194Y562324D01*
Y563324D01*
X866574Y563944D01*
Y564944D01*
X867194Y565564D01*
Y575812D01*
X866574Y576432D01*
Y577432D01*
X867194Y578052D01*
Y579052D01*
X866574Y579672D01*
Y580672D01*
X867194Y581292D01*
Y582292D01*
X866574Y582912D01*
Y583912D01*
X867194Y584532D01*
Y587375D01*
X866055Y588514D01*
X865110D01*
G01X922474Y408786D02*
X917500Y413760D01*
Y422632D01*
X866222Y473910D01*
X866220D01*
Y495509D01*
X862030Y499699D01*
Y587409D01*
X861139Y588300D01*
X860010D01*
G01X925111Y413237D02*
X922500Y415847D01*
Y426172D01*
X920088Y428584D01*
X919448D01*
X917345Y430687D01*
Y432987D01*
X915381Y434951D01*
X912321D01*
X910978Y436294D01*
Y439354D01*
X909014Y441318D01*
X905954D01*
X904611Y442661D01*
Y445721D01*
X902647Y447685D01*
X899587D01*
X898244Y449028D01*
Y452088D01*
X896280Y454052D01*
X893220D01*
X891877Y455395D01*
Y458455D01*
X889913Y460419D01*
X886853D01*
X885510Y461762D01*
Y464822D01*
X883546Y466786D01*
X880486D01*
X879143Y468129D01*
Y470554D01*
X876544Y473153D01*
X875116D01*
X872776Y475493D01*
Y477553D01*
X871080Y479249D01*
Y497652D01*
X868254Y500478D01*
Y587986D01*
X866666Y589574D01*
X866651D01*
X865111Y591114D01*
X865110D01*
G01X959283Y404426D02*
Y411417D01*
X944600Y426100D01*
Y445100D01*
X923739Y465961D01*
X913040D01*
X892421Y486580D01*
Y488680D01*
X890900Y490201D01*
Y507900D01*
X892113Y509113D01*
Y511087D01*
X891071Y512129D01*
Y516371D01*
X892239Y517539D01*
Y529449D01*
X891071Y530617D01*
Y535270D01*
X892196Y536395D01*
Y548732D01*
X891071Y549857D01*
Y554107D01*
X892221Y555257D01*
Y567267D01*
X891121Y568367D01*
Y573121D01*
X892169Y574169D01*
Y575802D01*
X892000Y575971D01*
Y586728D01*
X889319Y589409D01*
Y592722D01*
X890354Y593757D01*
G01X961783Y404426D02*
Y412517D01*
X947200Y427100D01*
Y448700D01*
X943428Y452472D01*
X942296D01*
X942178Y452354D01*
X941046D01*
X939915Y453485D01*
Y454617D01*
X940033Y454735D01*
Y455867D01*
X938902Y456998D01*
X937770D01*
X937652Y456880D01*
X936520D01*
X935389Y458011D01*
Y459143D01*
X935507Y459261D01*
Y460393D01*
X934376Y461524D01*
X933244D01*
X933126Y461406D01*
X931994D01*
X930863Y462537D01*
Y463669D01*
X930981Y463787D01*
Y464919D01*
X929850Y466050D01*
X928718D01*
X928600Y465932D01*
X927468D01*
X926337Y467063D01*
Y468195D01*
X926455Y468313D01*
Y469445D01*
X925400Y470500D01*
X923778D01*
X923168Y469890D01*
Y468693D01*
X922558Y468083D01*
X920578D01*
X919968Y468693D01*
Y470518D01*
X919358Y471128D01*
X917378D01*
X916768Y470518D01*
Y468693D01*
X916158Y468083D01*
X914178D01*
X913568Y468693D01*
Y469890D01*
X912958Y470500D01*
X912100D01*
X894921Y487679D01*
Y518500D01*
X895400Y518979D01*
Y528400D01*
X894921Y528879D01*
Y537700D01*
X895400Y538179D01*
Y546300D01*
X894921Y546779D01*
Y556500D01*
X895400Y556979D01*
Y565600D01*
X894921Y566079D01*
Y575620D01*
X895400Y576099D01*
Y584100D01*
X894921Y584579D01*
Y586443D01*
X893000Y588364D01*
Y588714D01*
G01X956483Y403882D02*
Y410617D01*
X942100Y425000D01*
Y444000D01*
X922221Y463879D01*
X912313D01*
X909732Y466460D01*
X908870D01*
X908534Y466124D01*
X907672D01*
X906271Y467525D01*
Y468387D01*
X906607Y468723D01*
Y469585D01*
X905206Y470986D01*
X904344D01*
X904008Y470650D01*
X903146D01*
X901745Y472051D01*
Y472913D01*
X902081Y473249D01*
Y474111D01*
X900680Y475512D01*
X899818D01*
X899482Y475176D01*
X898620D01*
X897219Y476577D01*
Y477439D01*
X897555Y477775D01*
Y478637D01*
X896154Y480038D01*
X895292D01*
X894956Y479702D01*
X894094D01*
X892693Y481103D01*
Y481965D01*
X893029Y482301D01*
Y483163D01*
X891628Y484564D01*
X890766D01*
X890430Y484228D01*
X889568D01*
X888200Y485596D01*
Y494200D01*
X887100Y495300D01*
Y502299D01*
X889100Y504299D01*
Y508500D01*
X888000Y509600D01*
Y511176D01*
X888571Y511747D01*
Y516629D01*
X887966Y517234D01*
Y519265D01*
X888700Y519999D01*
Y527800D01*
X888321Y528179D01*
Y529992D01*
X888571Y530242D01*
Y535192D01*
X888000Y535763D01*
Y537179D01*
X888700Y537879D01*
Y546100D01*
X887700Y547100D01*
Y549000D01*
X888571Y549871D01*
Y555007D01*
X887900Y555678D01*
Y557199D01*
X888700Y557999D01*
Y564200D01*
X887600Y565300D01*
Y567200D01*
X888821Y568421D01*
Y573080D01*
X887900Y574001D01*
Y575399D01*
X888700Y576199D01*
Y583900D01*
X888221Y584379D01*
Y587200D01*
X886707Y588714D01*
G01X972983Y406172D02*
Y415817D01*
X957700Y431100D01*
Y452900D01*
X951200Y459400D01*
Y463600D01*
X933800Y481000D01*
X916600D01*
X908700Y488900D01*
Y494600D01*
X909321Y495221D01*
Y511257D01*
X908521Y512057D01*
Y516957D01*
X908921Y517357D01*
Y519300D01*
X908800Y519421D01*
Y527600D01*
X908921Y527721D01*
Y529842D01*
X908521Y530242D01*
Y535722D01*
X909321Y536522D01*
Y538180D01*
X908754Y538747D01*
Y545954D01*
X909321Y546521D01*
Y549057D01*
X908521Y549857D01*
Y554757D01*
X909121Y555357D01*
Y557400D01*
X908800Y557721D01*
Y565800D01*
X909121Y566121D01*
Y567397D01*
X908048Y568470D01*
Y572969D01*
X909321Y574242D01*
Y575500D01*
X908800Y576021D01*
Y584400D01*
X909321Y584921D01*
Y586379D01*
X906400Y589300D01*
Y593071D01*
X907086Y593757D01*
G01X965813Y406287D02*
Y413859D01*
X951080Y428592D01*
Y450052D01*
X926552Y474580D01*
X913549D01*
X901762Y486367D01*
X899901Y490860D01*
Y587849D01*
X896850Y590900D01*
X896821D01*
G01X968983Y408160D02*
Y414589D01*
X953822Y429750D01*
X953820D01*
Y451248D01*
X946232Y458836D01*
Y460950D01*
X946792Y461510D01*
Y462736D01*
X945585Y463943D01*
X944359D01*
X943799Y463383D01*
X941685D01*
X939865Y465203D01*
Y467317D01*
X940425Y467877D01*
Y469106D01*
X939221Y470310D01*
X936779D01*
X933498Y473591D01*
Y475474D01*
X931652Y477320D01*
X914909D01*
X903941Y488288D01*
Y507212D01*
X903530Y507623D01*
Y508623D01*
X903941Y509034D01*
Y519493D01*
X903447Y519987D01*
Y520987D01*
X903941Y521481D01*
Y522509D01*
X903321Y523129D01*
Y524129D01*
X903941Y524749D01*
Y525749D01*
X903321Y526369D01*
Y527369D01*
X903941Y527989D01*
Y538042D01*
X903321Y538662D01*
Y539662D01*
X903941Y540282D01*
Y541282D01*
X903321Y541902D01*
Y542902D01*
X903941Y543522D01*
Y544522D01*
X903321Y545142D01*
Y546142D01*
X903941Y546762D01*
Y556983D01*
X903321Y557603D01*
Y558603D01*
X903941Y559223D01*
Y560223D01*
X903321Y560843D01*
Y561843D01*
X903941Y562463D01*
Y563463D01*
X903321Y564083D01*
Y565083D01*
X903941Y565703D01*
Y576036D01*
X903321Y576656D01*
Y577656D01*
X903941Y578276D01*
Y579276D01*
X903321Y579896D01*
Y580896D01*
X903941Y581516D01*
Y582516D01*
X903321Y583136D01*
Y584136D01*
X903941Y584756D01*
Y587595D01*
X903022Y588514D01*
X901921D01*
G01X964753Y406287D02*
Y413419D01*
X950022Y428150D01*
X950020D01*
Y449609D01*
X926109Y473520D01*
X913109D01*
X900863Y485766D01*
X898841Y490649D01*
Y577044D01*
X898361Y577524D01*
Y578524D01*
X898841Y579004D01*
Y580004D01*
X898361Y580484D01*
Y581484D01*
X898841Y581964D01*
Y582964D01*
X898361Y583444D01*
Y584444D01*
X898841Y584924D01*
Y587409D01*
X897950Y588300D01*
X896821D01*
G01X970043Y408160D02*
Y415029D01*
X954880Y430192D01*
Y451691D01*
X947292Y459279D01*
Y460507D01*
X947852Y461067D01*
Y463179D01*
X946028Y465003D01*
X943916D01*
X943356Y464443D01*
X942128D01*
X940925Y465646D01*
Y466874D01*
X941485Y467434D01*
Y469546D01*
X939661Y471370D01*
X937219D01*
X934558Y474031D01*
Y475914D01*
X932092Y478380D01*
X915349D01*
X905001Y488728D01*
Y588035D01*
X901922Y591114D01*
X901921D01*
G01X853543Y593757D02*
X851838Y595462D01*
Y607115D01*
X855023Y610300D01*
X856189D01*
G01Y588714D02*
X856101D01*
X854415Y590400D01*
Y592092D01*
X855322Y592999D01*
Y594592D01*
X854178Y595736D01*
Y597156D01*
X855022Y598000D01*
Y599700D01*
X854178Y600544D01*
Y601756D01*
X855122Y602700D01*
Y603900D01*
X854523Y604499D01*
X853543D01*
G01X876968Y593757D02*
X875263Y595462D01*
Y605649D01*
X880314Y610700D01*
G01Y588714D02*
X880226D01*
X878540Y590400D01*
Y592092D01*
X878715Y592267D01*
Y594900D01*
X877603Y596012D01*
Y597088D01*
X878615Y598100D01*
Y599300D01*
X877603Y600312D01*
Y601388D01*
X878740Y602525D01*
Y603799D01*
X878040Y604499D01*
X876968D01*
G01X873621Y610700D02*
X868570Y605649D01*
Y595462D01*
X870275Y593757D01*
G01D02*
Y593761D01*
G01X873621Y588714D02*
X873533D01*
X871847Y590400D01*
Y592092D01*
X872022Y592267D01*
Y594900D01*
X870910Y596012D01*
Y597088D01*
X871922Y598100D01*
Y599300D01*
X870910Y600312D01*
Y601388D01*
X872047Y602525D01*
Y603799D01*
X871347Y604499D01*
X870275D01*
G01X890354Y593757D02*
X888649Y595462D01*
Y605949D01*
X893000Y610300D01*
G01Y588714D02*
X892912D01*
X891226Y590400D01*
Y592092D01*
X892133Y592999D01*
Y594592D01*
X890989Y595736D01*
Y597156D01*
X891833Y598000D01*
Y599700D01*
X890989Y600544D01*
Y601756D01*
X891933Y602700D01*
Y603900D01*
X891334Y604499D01*
X890354D01*
G01X883661Y593757D02*
X881956Y595462D01*
Y605635D01*
X886621Y610300D01*
G01X886707Y588714D02*
X886619D01*
X884933Y590400D01*
Y592600D01*
X885433Y593100D01*
Y594999D01*
X884296Y596136D01*
Y597464D01*
X885233Y598401D01*
Y599799D01*
X884296Y600736D01*
Y601964D01*
X885333Y603001D01*
Y603899D01*
X884733Y604499D01*
X883661D01*
G01X907086Y593757D02*
X905381Y595462D01*
Y605649D01*
X910432Y610700D01*
G01Y588714D02*
X910344D01*
X908658Y590400D01*
Y592092D01*
X908833Y592267D01*
Y594900D01*
X907721Y596012D01*
Y597088D01*
X908733Y598100D01*
Y599300D01*
X907721Y600312D01*
Y601388D01*
X908858Y602525D01*
Y603799D01*
X908158Y604499D01*
X907086D01*
G01X860010Y590900D02*
X861722Y592612D01*
Y594200D01*
X860622Y595300D01*
X859672D01*
X859082Y595890D01*
Y597260D01*
X859602Y597780D01*
X860142D01*
X860752Y598390D01*
Y599780D01*
X860142Y600390D01*
X859632D01*
X859082Y600940D01*
Y602360D01*
X859722Y603000D01*
X861002D01*
X861741Y603739D01*
Y605645D01*
X860036Y607350D01*
G01X896821Y590900D02*
X898533Y592612D01*
Y594200D01*
X897433Y595300D01*
X896483D01*
X895893Y595890D01*
Y597260D01*
X896413Y597780D01*
X897023D01*
X897633Y598390D01*
Y599780D01*
X897023Y600390D01*
X896443D01*
X895893Y600940D01*
Y602360D01*
X896533Y603000D01*
X897813D01*
X898552Y603739D01*
Y605645D01*
X896847Y607350D01*
G01X865110Y588514D02*
X864822D01*
X863405Y589931D01*
Y594900D01*
X862575Y595730D01*
Y602270D01*
X863405Y603100D01*
Y608044D01*
X865110Y609749D01*
G01X901921Y588514D02*
X901633D01*
X900216Y589931D01*
Y594900D01*
X899386Y595730D01*
Y602270D01*
X900216Y603100D01*
Y608044D01*
X901921Y609749D01*
G01X860010Y588300D02*
X859722D01*
X858022Y590000D01*
Y608011D01*
X860010Y609999D01*
G01X896821Y588300D02*
X896533D01*
X894833Y590000D01*
Y608011D01*
X896821Y609999D01*
G01X865110Y591114D02*
X866822Y592826D01*
Y594500D01*
X865822Y595500D01*
X864306D01*
X863635Y596171D01*
Y597448D01*
X864087Y597900D01*
X864422D01*
X865122Y598600D01*
Y599688D01*
X864412Y600398D01*
X864175D01*
X863635Y600938D01*
Y601829D01*
X864406Y602600D01*
X865922D01*
X866922Y603600D01*
Y605328D01*
X865110Y607140D01*
G01X901921Y591114D02*
X903633Y592826D01*
Y594500D01*
X902633Y595500D01*
X901117D01*
X900446Y596171D01*
Y597448D01*
X900898Y597900D01*
X901233D01*
X901933Y598600D01*
Y599688D01*
X901223Y600398D01*
X900986D01*
X900446Y600938D01*
Y601829D01*
X901217Y602600D01*
X902733D01*
X903733Y603600D01*
Y605328D01*
X901921Y607140D01*
G01X933632Y52100D02*
X936738Y48994D01*
Y32848D01*
X935410Y31520D01*
X934428D01*
X933658Y30750D01*
G01X933632Y49500D02*
X934731D01*
X935678Y48553D01*
Y46020D01*
X934708Y45050D01*
X934360D01*
X933744Y44434D01*
Y43102D01*
X934246Y42600D01*
X934958D01*
X935678Y41880D01*
Y40920D01*
X934858Y40100D01*
X934358D01*
X933758Y39500D01*
Y38500D01*
X935678Y36580D01*
Y33291D01*
X934967Y32580D01*
X934451D01*
X933632Y33399D01*
G01X938732Y52314D02*
X941924Y49122D01*
Y33732D01*
X938732Y30540D01*
G01X927165Y27899D02*
Y30021D01*
X929044Y31900D01*
X930444D01*
X931900Y33356D01*
Y34700D01*
X931284Y35316D01*
Y48441D01*
X929811Y49914D01*
G01X950590Y27899D02*
X951837Y29146D01*
Y30400D01*
X953137Y31700D01*
X954137D01*
X955937Y33500D01*
Y34900D01*
X955325Y35512D01*
Y48525D01*
X953936Y49914D01*
G01X923518D02*
X924744Y48688D01*
Y35675D01*
X925519Y34900D01*
Y33276D01*
X923943Y31700D01*
X922719D01*
X921600Y30581D01*
Y29027D01*
X920472Y27899D01*
G01X943897D02*
X945144Y29146D01*
Y30400D01*
X946444Y31700D01*
X947444D01*
X949244Y33500D01*
Y34900D01*
X948632Y35512D01*
Y48525D01*
X947243Y49914D01*
G01X913779Y17157D02*
Y17773D01*
X916021Y20015D01*
Y28199D01*
X915221Y28999D01*
Y34821D01*
X915721Y35321D01*
Y37179D01*
X915154Y37746D01*
Y45633D01*
X915721Y46200D01*
Y48014D01*
X915121Y48614D01*
Y53314D01*
X916071Y54264D01*
Y65949D01*
X915221Y66799D01*
Y72621D01*
X915721Y73121D01*
Y74679D01*
X915000Y75400D01*
Y83279D01*
X915721Y84000D01*
Y85814D01*
X915121Y86414D01*
Y91114D01*
X915674Y91667D01*
Y104974D01*
X915074Y105574D01*
Y110574D01*
X915674Y111174D01*
Y114110D01*
X943200Y141636D01*
Y150994D01*
X945060Y152854D01*
X945852D01*
X948957Y149749D01*
X949749D01*
X950768Y150768D01*
Y151560D01*
X947663Y154665D01*
Y155457D01*
X982826Y190620D01*
Y194591D01*
G01X917125Y-3700D02*
X915558Y-2133D01*
Y-932D01*
X914200Y426D01*
Y1799D01*
X915400Y2999D01*
Y4125D01*
X914200Y5325D01*
Y6900D01*
X916000Y8700D01*
Y9758D01*
X912658Y13100D01*
Y16036D01*
X913779Y17157D01*
G01X917125Y12114D02*
X915221Y14018D01*
Y15614D01*
X918571Y18964D01*
Y28699D01*
X919121Y29249D01*
Y34779D01*
X918521Y35379D01*
Y36900D01*
X919200Y37579D01*
Y45500D01*
X918521Y46179D01*
Y48114D01*
X918900Y48493D01*
Y53535D01*
X918571Y53864D01*
Y66499D01*
X919121Y67049D01*
Y72579D01*
X918521Y73179D01*
Y74621D01*
X919200Y75300D01*
Y83221D01*
X918521Y83900D01*
Y85914D01*
X919221Y86614D01*
Y91274D01*
X918621Y91874D01*
Y105420D01*
X919142Y105941D01*
Y110606D01*
X918474Y111274D01*
Y113374D01*
X953700Y148600D01*
Y157957D01*
X985326Y189583D01*
Y194591D01*
G01X913779Y-9901D02*
X915026Y-8654D01*
Y-7400D01*
X916326Y-6100D01*
X917326D01*
X919126Y-4300D01*
Y-2900D01*
X918514Y-2288D01*
Y10725D01*
X917125Y12114D01*
G01X933658Y-7050D02*
X934428Y-6280D01*
X935410D01*
X936738Y-4952D01*
Y11194D01*
X933632Y14300D01*
G01X938732Y-7260D02*
X941924Y-4068D01*
Y11322D01*
X938732Y14514D01*
G01X933632Y-4401D02*
X934451Y-5220D01*
X934967D01*
X935678Y-4509D01*
Y-1220D01*
X933758Y700D01*
Y1700D01*
X934358Y2300D01*
X934858D01*
X935678Y3120D01*
Y4080D01*
X934958Y4800D01*
X934246D01*
X933744Y5302D01*
Y6634D01*
X934360Y7250D01*
X934708D01*
X935678Y8220D01*
Y10753D01*
X934731Y11700D01*
X933632D01*
G01X938732Y-4651D02*
X939841D01*
X940864Y-3628D01*
Y-1007D01*
X940157Y-300D01*
X939359D01*
X938758Y301D01*
Y1499D01*
X939359Y2100D01*
X940057D01*
X940864Y2907D01*
Y4280D01*
X940144Y5000D01*
X939644D01*
X938944Y5700D01*
Y6700D01*
X939644Y7400D01*
X940158D01*
X940864Y8106D01*
Y10881D01*
X939830Y11915D01*
X938732D01*
Y11914D01*
G01X927165Y17157D02*
X926044Y16036D01*
Y13100D01*
X928944Y10200D01*
Y-3233D01*
X929811Y-4100D01*
G01Y12114D02*
X931284Y10641D01*
Y-2484D01*
X931900Y-3100D01*
Y-4444D01*
X930444Y-5900D01*
X929044D01*
X927165Y-7779D01*
Y-9901D01*
G01X950590Y17157D02*
X949344Y15911D01*
Y13699D01*
X952337Y10706D01*
Y-2101D01*
X953936Y-3700D01*
G01Y12114D02*
X955325Y10725D01*
Y-2288D01*
X955937Y-2900D01*
Y-4300D01*
X954137Y-6100D01*
X953137D01*
X951837Y-7400D01*
Y-8654D01*
X950590Y-9901D01*
G01X920472Y17157D02*
X919544Y16229D01*
Y13101D01*
X922344Y10301D01*
Y-3012D01*
X923432Y-4100D01*
G01X923518Y12114D02*
X924744Y10888D01*
Y-2125D01*
X925519Y-2900D01*
Y-4524D01*
X923943Y-6100D01*
X922719D01*
X920472Y-8347D01*
Y-9901D01*
G01X943897Y17157D02*
X942644Y15904D01*
Y14150D01*
X945644Y11150D01*
Y-2101D01*
X947243Y-3700D01*
G01Y12114D02*
X948632Y10725D01*
Y-2288D01*
X949244Y-2900D01*
Y-4300D01*
X947444Y-6100D01*
X946444D01*
X945144Y-7400D01*
Y-8654D01*
X943897Y-9901D01*
G01X976700Y103021D02*
X974379Y100700D01*
X973884D01*
X966800Y93616D01*
Y92300D01*
X965300Y90800D01*
Y89200D01*
X966100Y88400D01*
Y86700D01*
X965434Y86034D01*
Y83766D01*
X965699Y83501D01*
Y72499D01*
X963976Y70776D01*
Y65814D01*
G01X933632Y110514D02*
X936649Y107497D01*
Y61747D01*
X934649Y59747D01*
Y56451D01*
X935358Y55742D01*
Y53826D01*
X933632Y52100D01*
G01X938732Y107655D02*
X940689Y105698D01*
Y60092D01*
X938789Y58192D01*
Y57520D01*
X937008Y55739D01*
Y51438D01*
X938732Y49714D01*
G01D02*
Y49715D01*
X939830D01*
X940864Y48681D01*
Y45906D01*
X940158Y45200D01*
X939644D01*
X938944Y44500D01*
Y43500D01*
X939644Y42800D01*
X940144D01*
X940864Y42080D01*
Y40707D01*
X940057Y39900D01*
X939522D01*
X938921Y39299D01*
Y38101D01*
X939522Y37500D01*
X940157D01*
X940864Y36793D01*
Y34172D01*
X939841Y33149D01*
X938732D01*
G01X933658Y107865D02*
X935589Y105934D01*
Y62190D01*
X933589Y60190D01*
Y57320D01*
X931658Y55389D01*
Y51474D01*
X933632Y49500D01*
G01X938758Y110264D02*
Y110238D01*
X941749Y107247D01*
Y59649D01*
X939849Y57749D01*
Y56620D01*
X940558Y55911D01*
Y54140D01*
X938732Y52314D01*
G01X927165Y112327D02*
X927874Y111618D01*
Y105974D01*
X928974Y104874D01*
Y92074D01*
X927574Y90674D01*
Y86874D01*
X928974Y85474D01*
Y84000D01*
X928500Y83526D01*
Y75600D01*
X928974Y75126D01*
Y73275D01*
X927974Y72275D01*
Y67327D01*
X928106Y67195D01*
Y67193D01*
X929074Y66225D01*
Y64759D01*
X927165Y62850D01*
Y54957D01*
G01D02*
X926200Y53992D01*
Y50744D01*
X928944Y48000D01*
Y34567D01*
X929811Y33700D01*
G01Y49914D02*
X928100Y51625D01*
Y53350D01*
X929224Y54474D01*
Y61809D01*
X931674Y64259D01*
Y74874D01*
X932400Y75600D01*
Y83274D01*
X931674Y84000D01*
Y105071D01*
X929811Y106934D01*
G01X950590Y54957D02*
X953074Y57441D01*
Y66059D01*
X951874Y67259D01*
Y72475D01*
X952674Y73275D01*
Y74626D01*
X952000Y75300D01*
Y83326D01*
X952674Y84000D01*
Y85774D01*
X952074Y86374D01*
Y91374D01*
X952574Y91874D01*
Y103426D01*
X950590Y105410D01*
Y109700D01*
G01X953936Y34100D02*
X952337Y35699D01*
Y48506D01*
X949344Y51499D01*
Y53711D01*
X950590Y54957D01*
G01X953936Y49914D02*
X952100Y51750D01*
Y53400D01*
X955483Y56783D01*
Y65083D01*
X955774Y65374D01*
Y72627D01*
X955174Y73227D01*
Y75159D01*
X955874Y75859D01*
Y90974D01*
X955174Y91674D01*
Y103074D01*
X955874Y103774D01*
Y105596D01*
X953786Y107684D01*
G01X920472Y112327D02*
X921574Y111225D01*
Y105874D01*
X922374Y105074D01*
Y91774D01*
X921574Y90974D01*
Y86374D01*
X922374Y85574D01*
Y84000D01*
X921800Y83426D01*
Y75300D01*
X922374Y74726D01*
Y72959D01*
X921574Y72159D01*
Y67027D01*
X922374Y66227D01*
Y56859D01*
X920472Y54957D01*
G01D02*
X921700Y53729D01*
Y48745D01*
X922344Y48101D01*
Y34788D01*
X923432Y33700D01*
G01X923518Y107284D02*
X925174Y105628D01*
Y91474D01*
X925474Y91174D01*
Y86474D01*
X925074Y86074D01*
Y84100D01*
X925800Y83374D01*
Y75900D01*
X925074Y75174D01*
Y72959D01*
X925374Y72659D01*
Y67359D01*
X925000Y66985D01*
Y55500D01*
X924200Y54700D01*
Y50596D01*
X923518Y49914D01*
G01X943897Y54957D02*
X945874Y56934D01*
Y66309D01*
X945074Y67109D01*
Y72175D01*
X945774Y72875D01*
Y74800D01*
X945200Y75374D01*
Y83400D01*
X945774Y83974D01*
Y86074D01*
X945074Y86774D01*
Y91074D01*
X946174Y92174D01*
Y103127D01*
X945274Y104027D01*
Y110150D01*
X944497Y110927D01*
G01X947243Y34100D02*
X945644Y35699D01*
Y48950D01*
X942644Y51950D01*
Y53704D01*
X943897Y54957D01*
G01X947243Y49914D02*
X945538Y51619D01*
Y53321D01*
X948074Y55857D01*
Y65859D01*
X949274Y67059D01*
Y72159D01*
X948774Y72659D01*
Y75274D01*
X949100Y75600D01*
Y83600D01*
X948774Y83926D01*
Y86074D01*
X949374Y86674D01*
Y91012D01*
X948674Y91712D01*
Y103653D01*
X947243Y105084D01*
G01X978356Y405699D02*
Y417644D01*
X962800Y433200D01*
Y461214D01*
X938014Y486000D01*
X919301D01*
X915500Y489801D01*
Y495100D01*
X915721Y495321D01*
Y511157D01*
X915221Y511657D01*
Y517057D01*
X916071Y517907D01*
Y519100D01*
X915500Y519671D01*
Y527800D01*
X916027Y528327D01*
Y529460D01*
X915121Y530366D01*
Y535822D01*
X915721Y536422D01*
Y537800D01*
X915400Y538121D01*
Y546300D01*
X915721Y546621D01*
Y548957D01*
X915221Y549457D01*
Y554857D01*
X916021Y555657D01*
Y556900D01*
X915500Y557421D01*
Y565700D01*
X916021Y566221D01*
Y567297D01*
X914921Y568397D01*
Y573142D01*
X915821Y574042D01*
Y575500D01*
X915400Y575921D01*
Y584400D01*
X915821Y584821D01*
Y586507D01*
X912421Y589907D01*
Y592399D01*
X913779Y593757D01*
G01X980856Y405851D02*
Y418744D01*
X965300Y434300D01*
Y461387D01*
X959916Y466771D01*
Y467633D01*
X960703Y468421D01*
Y469283D01*
X959302Y470684D01*
X958440D01*
X958200Y470444D01*
X957653Y469896D01*
X956791D01*
X955390Y471297D01*
Y472159D01*
X956625Y473396D01*
Y474257D01*
X955224Y475658D01*
X954361D01*
X953127Y474422D01*
X952265D01*
X950864Y475823D01*
Y476685D01*
X952281Y478104D01*
Y478965D01*
X950880Y480366D01*
X950017D01*
X948601Y478948D01*
X947739D01*
X946338Y480349D01*
Y481211D01*
X947783Y482658D01*
Y483519D01*
X946382Y484920D01*
X945519D01*
X944075Y483474D01*
X943213D01*
X938087Y488600D01*
X923700D01*
X921800Y490500D01*
Y492000D01*
X919000Y494800D01*
Y496926D01*
X918521Y497405D01*
Y511657D01*
X919121Y512257D01*
Y516807D01*
X918571Y517357D01*
Y519100D01*
X918800Y519329D01*
Y527900D01*
X918571Y528129D01*
Y529816D01*
X919221Y530466D01*
Y535578D01*
X918521Y536278D01*
Y537600D01*
X918800Y537879D01*
Y546200D01*
X918521Y546479D01*
Y549200D01*
G01X918571Y555500D02*
Y567647D01*
X919421Y568497D01*
Y573178D01*
X918421Y574178D01*
Y575300D01*
X918800Y575679D01*
Y583700D01*
X918421Y584079D01*
Y587470D01*
X917125Y588766D01*
Y588714D01*
G01X975483Y406172D02*
Y416917D01*
X960300Y432100D01*
Y454100D01*
X958461Y455939D01*
Y457071D01*
X959579Y458189D01*
Y459321D01*
X958448Y460452D01*
X957316D01*
X956198Y459334D01*
X955066D01*
X953900Y460500D01*
Y464500D01*
X953135Y465265D01*
Y466127D01*
X953666Y466658D01*
Y467520D01*
X952265Y468921D01*
X951403D01*
X950872Y468390D01*
X950010D01*
X948609Y469791D01*
Y470653D01*
X949140Y471184D01*
Y472046D01*
X947739Y473447D01*
X946877D01*
X946346Y472916D01*
X945484D01*
X944083Y474317D01*
Y475179D01*
X944614Y475710D01*
Y476572D01*
X943213Y477973D01*
X942351D01*
X941820Y477442D01*
X940958D01*
X939557Y478843D01*
Y479705D01*
X940088Y480236D01*
Y481098D01*
X938687Y482499D01*
X937825D01*
X937294Y481968D01*
X936432D01*
X934900Y483500D01*
X918001D01*
X912387Y489114D01*
Y494313D01*
X911821Y494879D01*
Y511257D01*
X912721Y512157D01*
Y516557D01*
X911921Y517357D01*
Y519300D01*
X912100Y519479D01*
Y527700D01*
X911921Y527879D01*
Y529842D01*
X912621Y530542D01*
Y535478D01*
X911821Y536278D01*
Y537700D01*
X912100Y537979D01*
Y546400D01*
X911821Y546679D01*
Y549057D01*
X912721Y549957D01*
Y554357D01*
X911621Y555457D01*
Y557400D01*
X912100Y557879D01*
Y565800D01*
X911921Y565979D01*
Y567597D01*
X912487Y568163D01*
Y573413D01*
X911821Y574079D01*
Y575600D01*
X912100Y575879D01*
Y584500D01*
X911821Y584779D01*
Y587368D01*
X911778D01*
X910432Y588714D01*
G01X960629Y536957D02*
X962360Y535226D01*
Y527840D01*
X965900Y524300D01*
Y520138D01*
X969148Y516890D01*
Y513923D01*
X968824Y513599D01*
Y511248D01*
X970206Y509866D01*
Y500394D01*
X973430Y497170D01*
X976530D01*
G01X933632Y553100D02*
X933661D01*
X936712Y550049D01*
Y505358D01*
X935412Y504058D01*
Y497840D01*
X933647Y496075D01*
Y495944D01*
G01X938732Y493344D02*
X936972Y495104D01*
Y499672D01*
X939440Y502140D01*
Y502989D01*
X940752Y504301D01*
Y520400D01*
X938740Y522412D01*
Y525440D01*
X940752Y527452D01*
Y540148D01*
X939800Y541100D01*
Y545400D01*
X940752Y546352D01*
Y548695D01*
X938733Y550714D01*
X938732D01*
G01X933632Y550500D02*
X933661D01*
X935652Y548509D01*
Y505798D01*
X931920Y502066D01*
Y495102D01*
X933647Y493375D01*
Y493344D01*
G01X938732Y553314D02*
X938733D01*
X941812Y550235D01*
Y545912D01*
X940860Y544960D01*
Y541540D01*
X941812Y540588D01*
Y527012D01*
X939800Y525000D01*
Y522852D01*
X941812Y520840D01*
Y503861D01*
X940500Y502549D01*
Y497712D01*
X938732Y495944D01*
G01X927165Y498644D02*
Y505042D01*
X929232Y507109D01*
Y510707D01*
X927882Y512057D01*
Y516307D01*
X929032Y517457D01*
Y519600D01*
X928800Y519832D01*
Y527900D01*
X929032Y528132D01*
Y529467D01*
X927932Y530567D01*
Y535233D01*
X929082Y536383D01*
Y537700D01*
X928800Y537982D01*
Y546500D01*
X929082Y546782D01*
Y548657D01*
X925732Y552007D01*
Y554524D01*
X927165Y555957D01*
G01X929811Y493244D02*
Y503890D01*
X931732Y505811D01*
Y518432D01*
X932200Y518900D01*
Y527800D01*
X931732Y528268D01*
Y537700D01*
X932200Y538168D01*
Y546300D01*
X931732Y546768D01*
Y548643D01*
X929811Y550564D01*
Y550914D01*
G01X950590Y555957D02*
X949232Y554599D01*
Y552107D01*
X952632Y548707D01*
Y546532D01*
X952200Y546100D01*
Y538332D01*
X952632Y537900D01*
Y536242D01*
X951732Y535342D01*
Y530597D01*
X952832Y529497D01*
Y517857D01*
X952032Y517057D01*
Y511657D01*
X952532Y511157D01*
Y502133D01*
X952300Y501901D01*
Y494900D01*
X950700Y493300D01*
G01X953936Y550914D02*
Y550966D01*
X955232Y549670D01*
Y536568D01*
X955874Y535926D01*
Y530339D01*
X955382Y529847D01*
Y517357D01*
X955932Y516807D01*
Y512257D01*
X955332Y511657D01*
Y510468D01*
X956174Y509626D01*
Y496874D01*
X954000Y494700D01*
G01X920700Y498644D02*
Y506778D01*
X922532Y508610D01*
Y510757D01*
X921532Y511757D01*
Y516457D01*
X922432Y517357D01*
Y519300D01*
X922200Y519532D01*
Y527700D01*
X922432Y527932D01*
Y529469D01*
X921384Y530517D01*
Y535144D01*
X922382Y536142D01*
Y538000D01*
X922200Y538182D01*
Y546600D01*
X922382Y546782D01*
Y548657D01*
G01X923518Y550914D02*
X925032Y549400D01*
Y546368D01*
X925500Y545900D01*
Y537968D01*
X925032Y537500D01*
Y535456D01*
X925632Y534856D01*
Y530697D01*
X925132Y530197D01*
Y528268D01*
X925500Y527900D01*
Y519768D01*
X925132Y519400D01*
Y517457D01*
X925382Y517207D01*
Y511007D01*
X925200Y510825D01*
Y503400D01*
X925400Y503200D01*
Y495544D01*
X923600Y493744D01*
G01X943897Y555957D02*
X943232Y555292D01*
Y551457D01*
X946132Y548557D01*
Y546732D01*
X945600Y546200D01*
Y538232D01*
X946132Y537700D01*
Y536442D01*
X944859Y535169D01*
Y530670D01*
X945932Y529597D01*
Y528232D01*
X945600Y527900D01*
Y519732D01*
X945932Y519400D01*
Y517557D01*
X945332Y516957D01*
Y512057D01*
X946132Y511257D01*
Y502532D01*
X945700Y502100D01*
Y494800D01*
X944000Y493100D01*
G01X947243Y550914D02*
X948589Y549568D01*
X948632D01*
Y546568D01*
X948900Y546300D01*
Y537968D01*
X948632Y537700D01*
Y536167D01*
X949298Y535501D01*
Y530363D01*
X948732Y529797D01*
Y528068D01*
X948900Y527900D01*
Y519568D01*
X948432Y519100D01*
Y517657D01*
X949532Y516557D01*
Y512157D01*
X948632Y511257D01*
Y502532D01*
X948290Y502190D01*
Y499910D01*
X949500Y498700D01*
Y497001D01*
X947443Y494944D01*
G01X913779Y593757D02*
X912074Y595462D01*
Y605649D01*
X917125Y610700D01*
G01Y588714D02*
X917037D01*
X915351Y590400D01*
Y592092D01*
X915526Y592267D01*
Y594900D01*
X914414Y596012D01*
Y597088D01*
X915426Y598100D01*
Y599300D01*
X914414Y600312D01*
Y601388D01*
X915551Y602525D01*
Y603799D01*
X914851Y604499D01*
X913779D01*
G01X933658Y607350D02*
X935405Y605603D01*
Y603487D01*
X934605Y602687D01*
X933325D01*
X932704Y602066D01*
Y600940D01*
X933254Y600390D01*
X933742D01*
X934365Y599767D01*
Y598377D01*
X933768Y597780D01*
X933224D01*
X932704Y597260D01*
Y595890D01*
X933294Y595300D01*
X934244D01*
X935344Y594200D01*
Y592612D01*
X933632Y590900D01*
G01X938732Y609749D02*
X937027Y608044D01*
Y602824D01*
X936197Y601994D01*
Y595730D01*
X937027Y594900D01*
Y589931D01*
X938444Y588514D01*
X938732D01*
G01X933632Y609999D02*
X931644Y608011D01*
Y590288D01*
X933632Y588300D01*
G01X938732Y607140D02*
X940544Y605328D01*
Y603854D01*
X939290Y602600D01*
X938320D01*
X937326Y601606D01*
Y600898D01*
X937826Y600398D01*
X938034D01*
X938775Y599657D01*
Y598631D01*
X938044Y597900D01*
X937709D01*
X937257Y597448D01*
Y596171D01*
X937928Y595500D01*
X939444D01*
X940444Y594500D01*
Y592826D01*
X938732Y591114D01*
G01X929811Y610300D02*
X925460Y605949D01*
Y595462D01*
X927165Y593757D01*
G01Y604499D02*
X928145D01*
X928744Y603900D01*
Y602700D01*
X927800Y601756D01*
Y600544D01*
X928644Y599700D01*
Y598000D01*
X927800Y597156D01*
Y595736D01*
X928944Y594592D01*
Y592999D01*
X928037Y592092D01*
Y590488D01*
X929811Y588714D01*
G01X953936Y610700D02*
X948885Y605649D01*
Y595462D01*
X950590Y593757D01*
G01Y604499D02*
X951662D01*
X952362Y603799D01*
Y602525D01*
X951225Y601388D01*
Y600312D01*
X952237Y599300D01*
Y598100D01*
X951225Y597088D01*
Y596012D01*
X952337Y594900D01*
Y592267D01*
X952162Y592092D01*
Y590400D01*
X953848Y588714D01*
X953936D01*
G01X923432Y610300D02*
X918767Y605635D01*
Y595462D01*
X920472Y593757D01*
G01Y604499D02*
X921544D01*
X922144Y603899D01*
Y603001D01*
X921107Y601964D01*
Y600736D01*
X922044Y599799D01*
Y598401D01*
X921107Y597464D01*
Y596136D01*
X922244Y594999D01*
Y593100D01*
X921744Y592600D01*
Y590400D01*
X923430Y588714D01*
X923518D01*
G01X947243Y610700D02*
X942192Y605649D01*
Y595462D01*
X943897Y593757D01*
G01Y604499D02*
X944969D01*
X945669Y603799D01*
Y602525D01*
X944532Y601388D01*
Y600312D01*
X945544Y599300D01*
Y598100D01*
X944532Y597088D01*
Y596012D01*
X945644Y594900D01*
Y592267D01*
X945469Y592092D01*
Y590400D01*
X947155Y588714D01*
X947243D01*
G01X980708Y54857D02*
Y54208D01*
X978970Y52470D01*
Y35118D01*
X977992Y34140D01*
Y30730D01*
X980708Y28014D01*
G01X984054D02*
X985700Y29660D01*
Y53212D01*
X984055Y54857D01*
G01X1017726Y198724D02*
Y103159D01*
X1024141Y96744D01*
Y88583D01*
X1023240Y87682D01*
Y82678D01*
X1025700Y80218D01*
Y44700D01*
X1031975Y38425D01*
Y29124D01*
X1035932Y25167D01*
X1044103D01*
X1049245Y20025D01*
Y15155D01*
X1050275Y14125D01*
Y12500D01*
X1050983Y11792D01*
Y9124D01*
X1050985Y9122D01*
G01X1009426Y199064D02*
Y104434D01*
X1008626Y103634D01*
X1007026D01*
X1006226Y104434D01*
Y109894D01*
X1005465Y110655D01*
X1003657D01*
X1003026Y110024D01*
Y101427D01*
X1002033Y100434D01*
Y91168D01*
X1002543Y90658D01*
Y88383D01*
X1002242Y88082D01*
Y86249D01*
X1002752Y85739D01*
Y83511D01*
X1006300Y79963D01*
Y73604D01*
X1002500Y69804D01*
Y59990D01*
X999180Y56670D01*
Y52860D01*
X998420Y52100D01*
X996700D01*
X992470Y47870D01*
Y45000D01*
X990650Y43180D01*
Y41460D01*
X992487Y39623D01*
Y34087D01*
X989135Y30735D01*
Y27235D01*
X988100Y26200D01*
X979400D01*
X978600Y25400D01*
Y22662D01*
X975657Y19719D01*
Y10756D01*
X974015Y9114D01*
G01D02*
Y-4536D01*
G01X984054Y9114D02*
Y6194D01*
X984664Y5584D01*
X986898D01*
X987508Y4974D01*
Y3074D01*
X986898Y2464D01*
X984664D01*
X984054Y1854D01*
Y-1742D01*
X984055Y-1743D01*
G01X1015687Y198554D02*
Y102369D01*
X1022031Y96025D01*
Y89131D01*
X1021400Y88500D01*
Y80075D01*
X1020500Y79175D01*
Y75996D01*
X1021400Y75096D01*
Y52400D01*
X1023200Y50600D01*
Y46844D01*
X1020156Y43800D01*
X1013663D01*
X1006246Y36383D01*
Y33646D01*
X1002500Y29900D01*
Y15968D01*
X1000151Y13619D01*
X996519D01*
X995400Y12500D01*
X987440D01*
X984054Y9114D01*
G01X980708Y-9786D02*
Y-7439D01*
X978858Y-5589D01*
Y-2942D01*
X979500Y-2300D01*
Y7600D01*
X978974Y8126D01*
Y10274D01*
X979600Y10900D01*
Y15949D01*
X980708Y17057D01*
G01X1011426Y198627D02*
Y98486D01*
X1009526Y96586D01*
Y83926D01*
X1008634Y83034D01*
Y76020D01*
X1011466Y73188D01*
Y67066D01*
X1005940Y61540D01*
Y54340D01*
X1001300Y49700D01*
X1000300D01*
X999060Y48460D01*
Y34860D01*
X997100Y32900D01*
X996180D01*
X992400Y29120D01*
Y24708D01*
X989637Y21945D01*
X985596D01*
X980708Y17057D01*
G01X984055D02*
Y15767D01*
X981938Y13650D01*
Y11768D01*
X982419Y11287D01*
Y8019D01*
X982200Y7800D01*
Y-3500D01*
X984055Y-5355D01*
Y-7108D01*
G01X1013476Y198651D02*
Y99893D01*
X1020175Y93186D01*
Y89716D01*
X1019400Y88941D01*
Y81648D01*
X1018500Y80748D01*
Y75151D01*
X1019400Y74251D01*
Y54204D01*
X1018296Y53100D01*
X1014456D01*
X1009200Y47844D01*
Y44590D01*
X1002500Y37890D01*
Y34600D01*
X999175Y31275D01*
Y27050D01*
X991608Y19483D01*
X986481D01*
X984055Y17057D01*
G01X974015Y73757D02*
X975335Y75077D01*
Y82193D01*
X974015Y83513D01*
Y84599D01*
G01D02*
Y87115D01*
X975900Y89000D01*
Y91200D01*
X974885Y92215D01*
Y96685D01*
X978950Y100750D01*
Y105800D01*
X975000Y109750D01*
Y117361D01*
X990596Y132957D01*
Y200519D01*
G01X994596Y199498D02*
Y131299D01*
X981700Y118403D01*
Y108899D01*
X983700Y106899D01*
Y97436D01*
X982000Y95736D01*
Y91800D01*
X982800Y91000D01*
Y88647D01*
X984055Y87392D01*
G01D02*
X982881Y86218D01*
Y74931D01*
X984055Y73757D01*
G01X980708Y89964D02*
X979600Y91072D01*
Y97300D01*
X981050Y98750D01*
Y106600D01*
X979400Y108250D01*
Y118932D01*
X992596Y132128D01*
Y199608D01*
G01X980708Y65814D02*
Y68018D01*
X979929Y68797D01*
X976832D01*
X976222Y69407D01*
Y70797D01*
X976832Y71407D01*
X978386D01*
X978996Y72017D01*
Y80951D01*
X978430Y81517D01*
Y85348D01*
X980708Y87626D01*
Y89964D01*
G01X984055Y92757D02*
Y94369D01*
X985700Y96014D01*
Y104200D01*
X986400Y104900D01*
Y106880D01*
X983800Y109480D01*
Y110987D01*
X984600Y111787D01*
X988674D01*
X989476Y112589D01*
Y114771D01*
X988678Y115569D01*
X984600D01*
X983800Y116369D01*
Y117674D01*
X996596Y130470D01*
Y199062D01*
G01X984054Y65814D02*
X985782Y67542D01*
Y83618D01*
X985600Y83800D01*
Y86100D01*
X985966Y86466D01*
Y88434D01*
X985400Y89000D01*
Y91412D01*
X984055Y92757D01*
G01X1050985Y46922D02*
X1050983Y46924D01*
Y49592D01*
X1050275Y50300D01*
X1046000D01*
X1042300Y54000D01*
Y57800D01*
X1039300Y60800D01*
X1035986D01*
X1031900Y64886D01*
Y73000D01*
X1033200Y74300D01*
Y75600D01*
X1030200Y78600D01*
Y113644D01*
X1029322Y114522D01*
X1028190D01*
X1027050Y113382D01*
X1025918D01*
X1024787Y114513D01*
Y115645D01*
X1025927Y116785D01*
Y117917D01*
X1023726Y120118D01*
Y197381D01*
G01X974015Y46914D02*
Y49215D01*
X975650Y50850D01*
Y56250D01*
X976151Y56751D01*
Y60804D01*
X978848Y63501D01*
X988017D01*
X989121Y64605D01*
Y66937D01*
X989500Y67316D01*
Y72000D01*
X989015Y72485D01*
Y75215D01*
X989500Y75700D01*
Y85800D01*
X988900Y86400D01*
Y88300D01*
X989500Y88900D01*
Y90900D01*
X988600Y91800D01*
Y93100D01*
X989100Y93600D01*
Y101900D01*
X992100Y104900D01*
Y106301D01*
X991300Y107101D01*
X990800D01*
X990000Y107901D01*
Y109501D01*
X990800Y110301D01*
X991300D01*
X992100Y111101D01*
Y120900D01*
X999796Y128596D01*
Y199305D01*
G01X974015Y35957D02*
Y46914D01*
G01X1054331Y46922D02*
X1054330Y46923D01*
Y49370D01*
X1051500Y52200D01*
X1051000D01*
X1049269Y53931D01*
Y58602D01*
X1042400Y65471D01*
Y74608D01*
X1041660Y75348D01*
Y76210D01*
X1042216Y76766D01*
Y77628D01*
X1041232Y78612D01*
X1040370D01*
X1039814Y78056D01*
X1038952D01*
X1037908Y79100D01*
X1034072D01*
X1032300Y80872D01*
Y114374D01*
X1025726Y120948D01*
Y196930D01*
G01X984055Y35957D02*
Y38545D01*
X982882Y39718D01*
Y45742D01*
X984054Y46914D01*
G01X1003796Y200166D02*
Y126936D01*
X996139Y119279D01*
Y94000D01*
X995600Y93461D01*
Y91400D01*
X995900Y91100D01*
Y88900D01*
X995641Y88641D01*
Y85759D01*
X995900Y85500D01*
Y84000D01*
X995800Y83900D01*
Y72400D01*
X996100Y72100D01*
Y70100D01*
X995714Y69714D01*
Y64114D01*
X990900Y59300D01*
X984200D01*
X982350Y57450D01*
Y52300D01*
X981353Y51303D01*
Y49615D01*
X984054Y46914D01*
G01X980708Y54857D02*
Y58908D01*
X983044Y61244D01*
X989185D01*
X992461Y64520D01*
Y69639D01*
X992294Y69806D01*
Y72594D01*
X992461Y72761D01*
Y74739D01*
X991800Y75400D01*
Y85600D01*
X992548Y86348D01*
Y88652D01*
X992288Y88912D01*
Y91088D01*
X992548Y91348D01*
Y101848D01*
X994139Y103439D01*
Y120109D01*
X1001796Y127766D01*
Y199802D01*
G01X984055Y54857D02*
Y54957D01*
X986168Y57070D01*
X996036D01*
X998300Y59334D01*
Y63020D01*
X999161Y63881D01*
Y69539D01*
X998800Y69900D01*
Y72400D01*
X999054Y72654D01*
Y83646D01*
X998900Y83800D01*
Y85400D01*
X999300Y85800D01*
Y88600D01*
X998900Y89000D01*
Y91100D01*
X999300Y91500D01*
Y93600D01*
X998583Y94317D01*
Y101383D01*
X999826Y102626D01*
Y112026D01*
X1000750Y112950D01*
Y114050D01*
X998294Y116506D01*
Y117594D01*
X999726Y119026D01*
X1000858D01*
X1003963Y115921D01*
X1005095D01*
X1006226Y117052D01*
Y118184D01*
X1003266Y121144D01*
Y122276D01*
X1005796Y124806D01*
Y200081D01*
G01X1019726Y198554D02*
Y105302D01*
X1027000Y98028D01*
Y85200D01*
X1027700Y84500D01*
Y72700D01*
X1028500Y71900D01*
Y55050D01*
X1033300Y50250D01*
Y45400D01*
X1037427Y41273D01*
X1038289D01*
X1040130Y43114D01*
X1040892D01*
X1042364Y41642D01*
Y40934D01*
X1040496Y39066D01*
Y38204D01*
X1042150Y36550D01*
Y30134D01*
X1052696Y19588D01*
Y15996D01*
X1052300Y15600D01*
Y13400D01*
X1054331Y11369D01*
Y9122D01*
G01X1028926Y191223D02*
Y122274D01*
X1045270Y105930D01*
Y104656D01*
X1044409Y103795D01*
X1042694D01*
X1041864Y102965D01*
Y101365D01*
X1042634Y100595D01*
X1044500D01*
X1045300Y99795D01*
Y95700D01*
X1049900Y91100D01*
Y88475D01*
X1050983Y87392D01*
G01X1030926Y190630D02*
Y123574D01*
X1048900Y105600D01*
Y101556D01*
X1052000Y98456D01*
Y94300D01*
X1052800Y93500D01*
Y91600D01*
X1052500Y91300D01*
Y89100D01*
X1052800Y88800D01*
Y86129D01*
X1054330Y84599D01*
G01X1077757Y46922D02*
X1077755Y46924D01*
Y51445D01*
X1076041Y53159D01*
Y57583D01*
X1069428Y64196D01*
Y66572D01*
X1065982Y70018D01*
Y75948D01*
X1066750Y76716D01*
Y79605D01*
X1069600Y82455D01*
Y85400D01*
X1069200Y85800D01*
Y88800D01*
X1069600Y89200D01*
Y90800D01*
X1068900Y91500D01*
Y107068D01*
X1059004Y116964D01*
X1057246D01*
X1042056Y132154D01*
Y191624D01*
G01X1071064Y54857D02*
Y59161D01*
X1065982Y64243D01*
Y67149D01*
X1063100Y70031D01*
Y72000D01*
X1062664Y72436D01*
Y82564D01*
X1066300Y86200D01*
Y88400D01*
X1065900Y88800D01*
Y91700D01*
X1066400Y92200D01*
Y106739D01*
X1058175Y114964D01*
X1052765D01*
X1051775Y115954D01*
Y117132D01*
X1052446Y117803D01*
Y118935D01*
X1051315Y120066D01*
X1050183D01*
X1049463Y119346D01*
X1048311D01*
X1047180Y120477D01*
Y121589D01*
X1047920Y122329D01*
Y123461D01*
X1046789Y124592D01*
X1045657D01*
X1045077Y124012D01*
X1043864D01*
X1042733Y125143D01*
Y126194D01*
X1043394Y126855D01*
Y127987D01*
X1040056Y131325D01*
Y191575D01*
G01X1036126Y195037D02*
Y127751D01*
X1052113Y111764D01*
X1057149D01*
X1061800Y107113D01*
Y92300D01*
X1062900Y91200D01*
Y89100D01*
X1060200Y86400D01*
X1060162D01*
X1059100Y85338D01*
Y75300D01*
X1059390Y75010D01*
Y71684D01*
X1059859Y71215D01*
Y68113D01*
X1059413Y67667D01*
Y64487D01*
X1062771Y61129D01*
Y56478D01*
X1062733Y56440D01*
Y46033D01*
X1062100Y45400D01*
Y38418D01*
X1062755Y37763D01*
Y34645D01*
X1066000Y31400D01*
Y27058D01*
X1072736Y20322D01*
Y15502D01*
X1077755Y10483D01*
Y9124D01*
X1077757Y9122D01*
G01X1071064Y17057D02*
Y18597D01*
X1062670Y26991D01*
Y29618D01*
X1062676Y29624D01*
Y31156D01*
X1059416Y34416D01*
Y49371D01*
X1059679Y49634D01*
Y52448D01*
X1059297Y52830D01*
Y56155D01*
X1055957Y59495D01*
Y69757D01*
X1055965Y69765D01*
Y74765D01*
X1056900Y75700D01*
Y85400D01*
X1055800Y86500D01*
Y88334D01*
X1059800Y92334D01*
Y106284D01*
X1056320Y109764D01*
X1051960D01*
X1043383Y118341D01*
X1042521D01*
X1041525Y117345D01*
X1040663D01*
X1039318Y118690D01*
Y119552D01*
X1040314Y120548D01*
Y121410D01*
X1038969Y122755D01*
X1038107D01*
X1037111Y121759D01*
X1036249D01*
X1034904Y123104D01*
Y123966D01*
X1035900Y124962D01*
Y125824D01*
X1034126Y127598D01*
Y194697D01*
G01X991500Y396301D02*
X993962Y398763D01*
Y475598D01*
X980500Y489060D01*
Y503800D01*
X976695Y507605D01*
X976700Y507617D01*
Y512130D01*
X977362Y512792D01*
G01X1032762Y411204D02*
Y483891D01*
X1050983Y502112D01*
Y512792D01*
G01X991961Y401161D02*
Y402186D01*
X991962Y402187D01*
Y475304D01*
X978500Y488766D01*
Y503383D01*
X977395Y504488D01*
X976480D01*
X975567Y503575D01*
X974722D01*
X974021Y504276D01*
Y505155D01*
X974970Y506104D01*
Y506966D01*
X974015Y507921D01*
Y509999D01*
G01X1034762Y411284D02*
Y483062D01*
X1054330Y502630D01*
Y509999D01*
G01X997962Y396007D02*
Y397762D01*
X999500Y399300D01*
Y400600D01*
X997962Y402138D01*
Y476840D01*
X984500Y490302D01*
Y508000D01*
X983200Y509300D01*
Y511937D01*
X984055Y512792D01*
G01X995962Y395968D02*
Y476122D01*
X982500Y489584D01*
Y505800D01*
X978800Y509500D01*
Y511200D01*
X980708Y513108D01*
Y515364D01*
G01X1000800Y402800D02*
X1000700Y402900D01*
Y478450D01*
X999667Y479483D01*
Y481362D01*
X1000700Y482395D01*
Y483951D01*
X999668Y484983D01*
X998419D01*
X995921Y482485D01*
X994671D01*
X993540Y483616D01*
Y484630D01*
X996731Y487821D01*
Y488806D01*
X995600Y489937D01*
X994321D01*
X991486Y487102D01*
X990321D01*
X989190Y488233D01*
Y489332D01*
X992071Y492213D01*
Y493487D01*
X990940Y494618D01*
X989840D01*
X988709Y493487D01*
X987917D01*
X986749Y494655D01*
Y496255D01*
X990049Y499555D01*
Y504751D01*
X985300Y509500D01*
Y511000D01*
X985900Y511600D01*
Y513900D01*
X985400Y514400D01*
Y516812D01*
X984055Y518157D01*
G01X1027562Y410841D02*
Y495262D01*
X1031300Y499000D01*
Y535200D01*
X1037847Y541747D01*
X1039842D01*
X1041027Y542932D01*
Y544597D01*
X1042147Y545717D01*
X1048779D01*
X1050984Y547922D01*
G01X1003162Y407821D02*
Y485738D01*
X992000Y496900D01*
Y505300D01*
X989300Y508000D01*
Y511100D01*
X988900Y511500D01*
Y513900D01*
X989500Y514500D01*
Y516400D01*
X988600Y517300D01*
Y518700D01*
X989129Y519229D01*
Y529871D01*
X986749Y532251D01*
Y534393D01*
X985721Y535421D01*
Y537753D01*
X984174Y539300D01*
X982629D01*
X974015Y547914D01*
G01X1029562Y410706D02*
Y494062D01*
X1040154Y504654D01*
Y505754D01*
X1046400Y512000D01*
Y513600D01*
X1045915Y514085D01*
Y532454D01*
X1049345Y535884D01*
Y542936D01*
X1054331Y547922D01*
G01X984054Y547914D02*
X992459Y539509D01*
Y534641D01*
X994900Y532200D01*
Y531200D01*
X995712Y530388D01*
Y516888D01*
X996098Y516502D01*
Y514398D01*
X995537Y513837D01*
Y511663D01*
X996400Y510800D01*
Y509400D01*
X995800Y508800D01*
Y506803D01*
X996410Y506193D01*
X997829D01*
X998478Y505544D01*
Y504154D01*
X997907Y503583D01*
X996410D01*
X995800Y502973D01*
Y499814D01*
X996626Y498988D01*
X997874D01*
X999076Y500190D01*
X1000111D01*
X1001242Y499059D01*
Y497830D01*
X999972Y496560D01*
Y495428D01*
X1007162Y488238D01*
Y407727D01*
G01X1005162Y407821D02*
Y487138D01*
X994000Y498300D01*
Y507000D01*
X992200Y508800D01*
Y511200D01*
X992700Y511700D01*
Y513900D01*
X992200Y514400D01*
Y516600D01*
X992600Y517000D01*
Y519400D01*
X992400Y519600D01*
Y531808D01*
X990000Y534208D01*
Y534600D01*
X989026Y535574D01*
Y538666D01*
X984356Y543336D01*
X982496D01*
X978991Y546841D01*
Y554140D01*
X980708Y555857D01*
G01X1032385Y380709D02*
X1033500Y381824D01*
Y383100D01*
X1034200Y383800D01*
Y385400D01*
X1033900Y385700D01*
Y387400D01*
X1034400Y387900D01*
Y389200D01*
X1037800Y392600D01*
Y394600D01*
X1039400Y396200D01*
Y403500D01*
X1045162Y409262D01*
Y478651D01*
X1066300Y499789D01*
Y508500D01*
X1065700Y509100D01*
Y511200D01*
X1066300Y511800D01*
Y513900D01*
X1065800Y514400D01*
Y516600D01*
X1067057Y517857D01*
Y520543D01*
X1065984Y521616D01*
Y529884D01*
X1068481Y532381D01*
Y534567D01*
X1069451Y535537D01*
Y538626D01*
X1070443Y539618D01*
X1072536D01*
X1073105Y540187D01*
Y541577D01*
X1072454Y542228D01*
X1070061D01*
X1069451Y542838D01*
Y544029D01*
X1071200Y545778D01*
X1075613D01*
X1077757Y547922D01*
G01X1029005Y378760D02*
Y380004D01*
X1030900Y381899D01*
Y383400D01*
X1030500Y383800D01*
Y385500D01*
X1031034Y386034D01*
Y387166D01*
X1030500Y387700D01*
Y389300D01*
X1031800Y390600D01*
Y391300D01*
X1037600Y397100D01*
Y404300D01*
X1043162Y409862D01*
Y479481D01*
X1062300Y498619D01*
Y508700D01*
X1063000Y509400D01*
Y511200D01*
X1062500Y511700D01*
Y513900D01*
X1062900Y514300D01*
Y516600D01*
X1062500Y517000D01*
Y527100D01*
X1062708Y527308D01*
Y532208D01*
X1065998Y535498D01*
Y543558D01*
X1069437Y546997D01*
Y549263D01*
X1069000Y549700D01*
Y553793D01*
X1071064Y555857D01*
G01X1009162Y407781D02*
Y489438D01*
X1003276Y495324D01*
Y504558D01*
X998669Y509165D01*
Y511169D01*
X999400Y511900D01*
Y513900D01*
X998900Y514400D01*
Y516400D01*
X999300Y516800D01*
Y522284D01*
X999904Y522888D01*
X1001208D01*
X1001775Y523455D01*
Y524845D01*
X1001122Y525498D01*
X999760D01*
X999150Y526108D01*
Y533050D01*
X999062Y533138D01*
Y541718D01*
X995799Y544981D01*
Y552968D01*
X994757Y554010D01*
X992157D01*
X991547Y553400D01*
Y552337D01*
X990916Y551706D01*
X989526D01*
X988937Y552295D01*
Y553400D01*
X988327Y554010D01*
X985902D01*
X984055Y555857D01*
G01X1009000Y401500D02*
X1012362Y404862D01*
Y490809D01*
X1006300Y496871D01*
Y506839D01*
X1002051Y511088D01*
Y513679D01*
X1002885Y514513D01*
Y516681D01*
X1002282Y517284D01*
Y520208D01*
X1006300Y524226D01*
Y527100D01*
X1005760Y527640D01*
Y530360D01*
X1005202Y530918D01*
Y535606D01*
X1005762Y536166D01*
Y541073D01*
X1002499Y544336D01*
Y551069D01*
X999149Y554419D01*
Y557151D01*
X995712Y560588D01*
Y568188D01*
X994600Y569300D01*
X993500D01*
X989041Y573759D01*
Y576086D01*
X988127Y577000D01*
X982800D01*
X981800Y578000D01*
Y581276D01*
X977362Y585714D01*
G01X1016650Y394850D02*
X1022362Y400562D01*
Y498275D01*
X1026900Y502813D01*
Y535600D01*
X1029700Y538400D01*
Y574612D01*
X1035371Y580283D01*
X1045546D01*
X1050985Y585722D01*
G01X1019301Y394600D02*
X1024362Y399661D01*
Y496862D01*
X1029200Y501700D01*
Y535400D01*
X1031400Y537600D01*
Y573600D01*
X1035600Y577800D01*
X1047369D01*
X1054331Y584762D01*
Y585722D01*
G01X980708Y593657D02*
Y589428D01*
X982400Y587736D01*
X991230D01*
X992479Y586487D01*
Y584156D01*
X991262Y582939D01*
X987688D01*
X986863Y582114D01*
Y580750D01*
X987874Y579739D01*
X992234D01*
X995741Y576232D01*
Y573587D01*
X997528Y571800D01*
X998909D01*
X1002426Y568283D01*
Y565959D01*
X1003102Y565283D01*
Y564421D01*
X1002015Y563334D01*
Y562472D01*
X1002999Y561488D01*
X1003861D01*
X1004948Y562575D01*
X1005810D01*
X1009223Y559162D01*
Y536302D01*
X1011004Y534521D01*
X1012304D01*
X1013116Y533709D01*
Y532129D01*
X1012100Y531113D01*
X1010300D01*
X1009500Y530313D01*
Y528000D01*
X1008300Y526800D01*
Y522968D01*
X1006086Y520754D01*
Y509420D01*
X1014362Y501144D01*
Y404012D01*
X1010575Y400225D01*
G01X1032084Y394284D02*
X1035800Y398000D01*
Y405000D01*
X1039962Y409162D01*
Y480807D01*
X1059100Y499945D01*
Y511500D01*
X1059700Y512100D01*
Y513900D01*
X1059100Y514500D01*
Y516300D01*
X1059388Y516588D01*
Y530488D01*
X1059600Y530700D01*
Y535474D01*
X1059387Y535687D01*
Y543387D01*
X1062708Y546708D01*
Y551608D01*
X1065983Y554883D01*
Y569620D01*
X1069113Y572750D01*
X1071478D01*
X1072698Y573970D01*
Y576047D01*
X1070821Y577924D01*
Y579164D01*
X1072427Y580770D01*
X1073784D01*
X1075718Y578836D01*
X1076889D01*
X1078360Y580307D01*
Y581481D01*
X1076566Y583275D01*
Y584531D01*
X1077757Y585722D01*
G01X1029138Y394761D02*
X1034250Y399873D01*
Y406150D01*
X1037962Y409862D01*
Y481636D01*
X1056500Y500174D01*
Y511000D01*
X1055700Y511800D01*
Y513900D01*
X1056300Y514500D01*
Y516300D01*
X1055700Y516900D01*
Y518900D01*
X1055949Y519149D01*
Y538749D01*
X1056700Y539500D01*
Y543440D01*
X1059417Y546157D01*
Y549017D01*
X1059600Y549200D01*
Y551600D01*
X1062766Y554766D01*
Y568034D01*
X1062400Y568400D01*
Y570100D01*
X1065999Y573699D01*
Y588592D01*
X1071064Y593657D01*
G01X1015275Y396325D02*
X1020362Y401412D01*
Y499104D01*
X1022501Y501243D01*
Y525102D01*
X1023400Y526001D01*
Y548900D01*
X1025200Y550700D01*
Y574300D01*
X1016878Y582622D01*
X1007233D01*
X1004133Y585722D01*
G01X997441D02*
Y585116D01*
X1001545Y581012D01*
X1016210D01*
X1021400Y575822D01*
Y559100D01*
X1023300Y557200D01*
Y551200D01*
X1021400Y549300D01*
Y526900D01*
X1020501Y526001D01*
Y502072D01*
X1018362Y499933D01*
Y402262D01*
X1013754Y397654D01*
G01X1011900Y398700D02*
X1016362Y403162D01*
Y506598D01*
X1018469Y508705D01*
Y527168D01*
X1019400Y528099D01*
Y549700D01*
X1021600Y551900D01*
Y556500D01*
X1019400Y558700D01*
Y575267D01*
X1017891Y576776D01*
X1000910D01*
X995757Y581929D01*
Y587043D01*
X994200Y588600D01*
X993200D01*
X989979Y591821D01*
X985891D01*
X984055Y593657D01*
G01X977362Y512792D02*
Y515038D01*
X975300Y517100D01*
Y519100D01*
X975656Y519456D01*
Y532678D01*
X977362Y534384D01*
Y536957D01*
G01X974015Y509999D02*
Y512485D01*
X972200Y514300D01*
Y516600D01*
X972500Y516900D01*
Y519300D01*
X972300Y519500D01*
Y530300D01*
X973000Y531000D01*
Y533249D01*
X974015Y534264D01*
Y536957D01*
G01X984055Y512792D02*
X983100Y513747D01*
Y515900D01*
X982049Y516951D01*
Y519049D01*
X982400Y519400D01*
Y530402D01*
X981538Y531264D01*
X979333D01*
X978723Y531874D01*
Y532864D01*
X979333Y533474D01*
X981350D01*
X982148Y534272D01*
Y535050D01*
X984055Y536957D01*
G01X980708Y515364D02*
X980345Y515727D01*
Y528651D01*
X980708Y529014D01*
G01X984055Y518157D02*
Y529013D01*
X984054Y529014D01*
G01X974015Y547914D02*
Y552524D01*
X975642Y554151D01*
Y557622D01*
X976453Y558433D01*
Y563532D01*
X975642Y564343D01*
Y568058D01*
X974015Y569685D01*
Y574757D01*
G01X984055D02*
X982165Y572867D01*
Y567935D01*
X982400Y567700D01*
Y554913D01*
X981725Y554238D01*
Y550243D01*
X984054Y547914D01*
G01X980708Y555857D02*
Y566814D01*
G01X984055Y555857D02*
Y566813D01*
X984054Y566814D01*
G01X977362Y585714D02*
X975642Y587434D01*
Y595346D01*
X972100Y598888D01*
Y605130D01*
X973269Y606299D01*
X973623D01*
X977362Y610038D01*
Y612457D01*
G01X1004133Y585722D02*
Y588194D01*
X1002411Y589916D01*
Y602711D01*
X1005937Y606237D01*
Y608263D01*
X1004133Y610067D01*
Y612358D01*
G01X997441Y612357D02*
Y610259D01*
X999417Y608283D01*
Y606217D01*
X998200Y605000D01*
Y598424D01*
X995712Y595936D01*
Y592570D01*
X997441Y590841D01*
Y585722D01*
G01X980708Y604614D02*
Y602572D01*
X979882Y601746D01*
X978055D01*
X977270Y600961D01*
Y598901D01*
X977930Y598241D01*
X980160D01*
X980708Y597693D01*
Y593657D01*
G01X984055D02*
Y607292D01*
G01X1071064Y54857D02*
X1068976Y52769D01*
Y49651D01*
X1069434Y49193D01*
Y33966D01*
X1069013Y33545D01*
Y30073D01*
X1071064Y28022D01*
G01X1050985Y9122D02*
Y5113D01*
X1050375Y4503D01*
X1048153D01*
X1047570Y3920D01*
Y2020D01*
X1048207Y1383D01*
X1050375D01*
X1050985Y773D01*
Y-1741D01*
X1050983Y-1743D01*
G01X1087797Y-2402D02*
Y9122D01*
G01D02*
X1087795Y9124D01*
Y11165D01*
X1089400Y12770D01*
Y17865D01*
X1090582Y19047D01*
X1093107D01*
X1093704Y19644D01*
Y21544D01*
X1091903Y23345D01*
Y26270D01*
X1092876Y27243D01*
Y31076D01*
X1096108Y34308D01*
Y37108D01*
X1096300Y37300D01*
Y85600D01*
X1096288Y85612D01*
Y102212D01*
X1094800Y103700D01*
Y105900D01*
X1095483Y106583D01*
G01Y109217D02*
X1063062Y141638D01*
Y195238D01*
X1058900Y199400D01*
Y204801D01*
X1054756Y208945D01*
Y233851D01*
X1057314Y236409D01*
G01X1054331Y9122D02*
Y-4535D01*
X1054330Y-4536D01*
G01X1077757Y9122D02*
Y1943D01*
X1077187Y1373D01*
X1076197D01*
X1075547Y2023D01*
Y6384D01*
X1074937Y6994D01*
X1073947D01*
X1073337Y6384D01*
Y-569D01*
X1074509Y-1741D01*
X1077753D01*
X1077755Y-1743D01*
G01X1071062Y-7108D02*
Y-4538D01*
X1069200Y-2676D01*
Y7600D01*
X1069444Y7844D01*
Y10556D01*
X1069200Y10800D01*
Y14061D01*
X1071064Y15925D01*
Y17057D01*
G01X1084448Y-1743D02*
Y1889D01*
X1083838Y2499D01*
X1081571D01*
X1080961Y3109D01*
Y5009D01*
X1081571Y5619D01*
X1083838D01*
X1084448Y6229D01*
Y9120D01*
X1084450Y9122D01*
G01D02*
X1084448Y9124D01*
Y10942D01*
X1086164Y12658D01*
Y29116D01*
X1088501Y31453D01*
X1089183D01*
X1092860Y35130D01*
Y37140D01*
X1092200Y37800D01*
Y43138D01*
X1092851Y43789D01*
Y55949D01*
X1092300Y56500D01*
Y61156D01*
X1092880Y61736D01*
Y74620D01*
X1092600Y74900D01*
Y86200D01*
X1093000Y86600D01*
Y88600D01*
X1092600Y89000D01*
Y91000D01*
X1093000Y91400D01*
Y93400D01*
X1092800Y93600D01*
Y109536D01*
X1061012Y141324D01*
Y194243D01*
X1056776Y198479D01*
Y203921D01*
X1052279Y208418D01*
Y235365D01*
X1049284Y238360D01*
G01X1050983Y87392D02*
Y73759D01*
X1050985Y73757D01*
G01X1087795Y84714D02*
X1089093Y83416D01*
Y81884D01*
X1088101Y80892D01*
Y79033D01*
X1089700Y77434D01*
Y75660D01*
X1087797Y73757D01*
G01X1057806Y191151D02*
Y140928D01*
X1089623Y109111D01*
Y107902D01*
X1088963Y107242D01*
X1087255D01*
X1086639Y106626D01*
Y104674D01*
X1087332Y103981D01*
X1088931D01*
X1089600Y103312D01*
Y95754D01*
X1088529Y94683D01*
Y91871D01*
X1090058Y90342D01*
Y89458D01*
X1089300Y88700D01*
Y87599D01*
X1088400Y86699D01*
Y85319D01*
X1087795Y84714D01*
G01X1054330Y84599D02*
X1054331Y84598D01*
Y83731D01*
X1053755Y83155D01*
Y79699D01*
X1053999Y79455D01*
Y74089D01*
X1054331Y73757D01*
G01X1077755Y87392D02*
X1077452Y87089D01*
Y82836D01*
X1076842Y82226D01*
X1073992D01*
X1073382Y81616D01*
Y80626D01*
X1073992Y80016D01*
X1077417D01*
X1077992Y79441D01*
Y78451D01*
X1077347Y77806D01*
X1071852D01*
X1071189Y77143D01*
Y76153D01*
X1071746Y75596D01*
X1077162D01*
X1077757Y75001D01*
Y73757D01*
G01X1047256Y190969D02*
Y136768D01*
X1075362Y108662D01*
Y102438D01*
X1076100Y101700D01*
Y93700D01*
X1075677Y93277D01*
Y91823D01*
X1077400Y90100D01*
Y88400D01*
X1077755Y88045D01*
Y87392D01*
G01X1071062Y92757D02*
Y94815D01*
X1071672Y95425D01*
X1072650D01*
X1073242Y96017D01*
Y97007D01*
X1072614Y97635D01*
X1071872D01*
X1071262Y98245D01*
Y99961D01*
X1073362Y102061D01*
Y107833D01*
X1061031Y120164D01*
X1058573D01*
X1057570Y121167D01*
Y123625D01*
X1056505Y124690D01*
X1054047D01*
X1052978Y125759D01*
Y128217D01*
X1051979Y129216D01*
X1049521D01*
X1048452Y130285D01*
Y132743D01*
X1047797Y133398D01*
X1046056D01*
X1045256Y134198D01*
Y191381D01*
G01X1071064Y65822D02*
Y67336D01*
X1069051Y69349D01*
Y71824D01*
X1069449Y72222D01*
Y77778D01*
X1071573Y79902D01*
Y92246D01*
X1071062Y92757D01*
G01X1084448Y87392D02*
X1085500D01*
X1086300Y86592D01*
Y85870D01*
X1085766Y85336D01*
Y75073D01*
X1084450Y73757D01*
G01X1055806Y190981D02*
Y140099D01*
X1084500Y111405D01*
Y103500D01*
X1086100Y101900D01*
Y93900D01*
X1086300Y93700D01*
Y91300D01*
X1085900Y90900D01*
Y89500D01*
X1084448Y88048D01*
Y87392D01*
G01X1050985Y46922D02*
X1048284Y44221D01*
Y38658D01*
X1050985Y35957D01*
G01X1087797Y46922D02*
X1086100Y45225D01*
Y37654D01*
X1087797Y35957D01*
G01Y46922D02*
X1087795Y46924D01*
Y49505D01*
X1085736Y51564D01*
Y53436D01*
X1086165Y53865D01*
Y61154D01*
X1082824Y64495D01*
Y66774D01*
X1081369Y68229D01*
Y70970D01*
X1082824Y72425D01*
Y76226D01*
X1082400Y76650D01*
Y83100D01*
X1083000Y83700D01*
Y85400D01*
X1082200Y86200D01*
Y88500D01*
X1083000Y89300D01*
Y91100D01*
X1082400Y91700D01*
Y93600D01*
X1082900Y94100D01*
Y101200D01*
X1081300Y102800D01*
Y110079D01*
X1052506Y138873D01*
Y191500D01*
G01X1054331Y46922D02*
Y45385D01*
X1056600Y43116D01*
Y38226D01*
X1054331Y35957D01*
G01X1077757Y46922D02*
Y45617D01*
X1077147Y45007D01*
X1073183D01*
X1072573Y44397D01*
Y43366D01*
X1073183Y42756D01*
X1077147D01*
X1077757Y42146D01*
Y40947D01*
X1077147Y40337D01*
X1073183D01*
X1072573Y39727D01*
Y38351D01*
X1073234Y37690D01*
X1077257D01*
X1077757Y37190D01*
Y35957D01*
G01X1084450Y46922D02*
X1083019Y45491D01*
Y37388D01*
X1084450Y35957D01*
G01Y46922D02*
X1081254Y50118D01*
Y52015D01*
X1082714Y53475D01*
Y60527D01*
X1079377Y63864D01*
Y75475D01*
X1079700Y75798D01*
Y83300D01*
X1079300Y83700D01*
Y85800D01*
X1079800Y86300D01*
Y88700D01*
X1079283Y89217D01*
Y91283D01*
X1079650Y91650D01*
Y93500D01*
X1079300Y93850D01*
Y109188D01*
X1050506Y137982D01*
Y191694D01*
G01X1107874Y17157D02*
Y24174D01*
X1109741Y26041D01*
Y28459D01*
X1108591Y29609D01*
Y34191D01*
X1109700Y35300D01*
Y37300D01*
X1109200Y37800D01*
Y45659D01*
X1109600Y46059D01*
Y47905D01*
X1108591Y48914D01*
Y53192D01*
X1109941Y54542D01*
Y66059D01*
X1108591Y67409D01*
Y72091D01*
X1109674Y73174D01*
Y75267D01*
X1109375Y75566D01*
Y83475D01*
X1109600Y83700D01*
Y85648D01*
X1108674Y86574D01*
Y90924D01*
X1109774Y92024D01*
Y102226D01*
X1106500Y105500D01*
Y120613D01*
X1105373Y121740D01*
X1104244D01*
X1102998Y120494D01*
X1102206D01*
X1100735Y121965D01*
Y122757D01*
X1101980Y124002D01*
Y125133D01*
X1100847Y126266D01*
X1099717D01*
X1097514Y124063D01*
X1096385D01*
X1095252Y125196D01*
Y126326D01*
X1097454Y128528D01*
Y129659D01*
X1096321Y130792D01*
X1095191D01*
X1094215Y129816D01*
X1093086D01*
X1091953Y130949D01*
Y132079D01*
X1092928Y133054D01*
Y134185D01*
X1074127Y152992D01*
Y188139D01*
X1074565Y188577D01*
G01X1110520Y12114D02*
X1108447Y14187D01*
Y15248D01*
X1109941Y16742D01*
Y22441D01*
X1112441Y24941D01*
Y37141D01*
X1113008Y37708D01*
Y45687D01*
X1112441Y46254D01*
Y75000D01*
X1113100Y75659D01*
Y83300D01*
X1112441Y83959D01*
Y105050D01*
X1111641Y105850D01*
X1110050D01*
X1109000Y106900D01*
Y115918D01*
X1109800Y116718D01*
X1110600D01*
X1111400Y117518D01*
Y119118D01*
X1110600Y119918D01*
X1109800D01*
X1109000Y120718D01*
Y121649D01*
X1077065Y153584D01*
Y188577D01*
G01X1069565Y189577D02*
X1069392Y189404D01*
Y150508D01*
X1075986Y143914D01*
Y142782D01*
X1073363Y140159D01*
Y139027D01*
X1074830Y137560D01*
X1075962D01*
X1078585Y140183D01*
X1079717D01*
X1081023Y138877D01*
Y137745D01*
X1078446Y135168D01*
Y133555D01*
X1101400Y110601D01*
Y102735D01*
X1103069Y101066D01*
Y91769D01*
X1102374Y91074D01*
Y86474D01*
X1103025Y85823D01*
Y84000D01*
X1102400Y83375D01*
Y75400D01*
X1103025Y74775D01*
Y73059D01*
X1102241Y72275D01*
Y67159D01*
X1103900Y65500D01*
Y54701D01*
X1102377Y53178D01*
Y48322D01*
X1103300Y47399D01*
Y46200D01*
X1102600Y45500D01*
Y37600D01*
X1103300Y36900D01*
Y35500D01*
X1102241Y34441D01*
Y29359D01*
X1103200Y28400D01*
Y26800D01*
X1101181Y24781D01*
Y17157D01*
G01X1072065Y189577D02*
X1071892Y189404D01*
Y151685D01*
X1085249Y138328D01*
Y137466D01*
X1083037Y135254D01*
Y134462D01*
X1084445Y133054D01*
X1085237D01*
X1087449Y135266D01*
X1088311D01*
X1089468Y134109D01*
Y125781D01*
X1104000Y111249D01*
Y104200D01*
X1105792Y102408D01*
Y91856D01*
X1106174Y91474D01*
Y86574D01*
X1105525Y85925D01*
Y84375D01*
X1106300Y83600D01*
Y74800D01*
X1105525Y74025D01*
Y72508D01*
X1106091Y71942D01*
Y66649D01*
X1106000Y66558D01*
Y53705D01*
X1106091Y53614D01*
Y47692D01*
X1105741Y47342D01*
Y46200D01*
X1106400Y45541D01*
Y37600D01*
X1105741Y36941D01*
Y35399D01*
X1106091Y35049D01*
Y28849D01*
X1105841Y28599D01*
Y25841D01*
X1103800Y23800D01*
Y17073D01*
X1102241Y15514D01*
Y14100D01*
X1104227Y12114D01*
G01X1124606Y17157D02*
X1127100Y19651D01*
Y28040D01*
X1125700Y29440D01*
Y34400D01*
X1126841Y35541D01*
Y37060D01*
X1126000Y37901D01*
Y45700D01*
X1126841Y46541D01*
Y47914D01*
X1126041Y48714D01*
Y53414D01*
X1126441Y53814D01*
Y66499D01*
X1125800Y67140D01*
Y72300D01*
X1126841Y73341D01*
Y74459D01*
X1125800Y75500D01*
Y83300D01*
X1126841Y84341D01*
Y85714D01*
X1125700Y86855D01*
Y90873D01*
X1126500Y91673D01*
Y101400D01*
X1125200Y102700D01*
Y103452D01*
X1126000Y104252D01*
X1127100D01*
X1127900Y105052D01*
Y106652D01*
X1127100Y107452D01*
X1126000D01*
X1125200Y108252D01*
Y109852D01*
X1126000Y110652D01*
X1128123D01*
X1128923Y111452D01*
Y113052D01*
X1128123Y113852D01*
X1126000D01*
X1125200Y114652D01*
Y115500D01*
X1126900Y117200D01*
Y118738D01*
X1087379Y158259D01*
Y166300D01*
X1087989Y166910D01*
X1089440D01*
X1090000Y167470D01*
Y169460D01*
X1089440Y170020D01*
X1087989D01*
X1087379Y170630D01*
Y185879D01*
G01X1127952Y12114D02*
X1126141Y13925D01*
Y15550D01*
X1129400Y18809D01*
Y28658D01*
X1130241Y29499D01*
Y34359D01*
X1129341Y35259D01*
Y36740D01*
X1130000Y37399D01*
Y45600D01*
X1129341Y46259D01*
Y47914D01*
X1129874Y48447D01*
Y53481D01*
X1129441Y53914D01*
Y66499D01*
X1130241Y67299D01*
Y72259D01*
X1129341Y73159D01*
Y74741D01*
X1129700Y75100D01*
Y83441D01*
X1129341Y83800D01*
Y85714D01*
X1130141Y86514D01*
Y91014D01*
X1129400Y91755D01*
Y94864D01*
X1131000Y96464D01*
Y118174D01*
X1094928Y154246D01*
Y169265D01*
X1089879Y174314D01*
Y186121D01*
G01X1114340Y14300D02*
X1116066Y16026D01*
Y18100D01*
X1115266Y18900D01*
X1114266D01*
X1113546Y19620D01*
Y20688D01*
X1117421Y24563D01*
Y55580D01*
X1118041Y56200D01*
Y57200D01*
X1117421Y57820D01*
Y58580D01*
X1118041Y59200D01*
Y60200D01*
X1117421Y60820D01*
Y98789D01*
X1118680Y100048D01*
Y108074D01*
X1117559Y109195D01*
X1114052D01*
X1113080Y110167D01*
Y112563D01*
X1113952Y113435D01*
X1117191D01*
X1118680Y114924D01*
Y117240D01*
X1085038Y150882D01*
Y151518D01*
X1084330Y152226D01*
X1083694D01*
X1082956Y152964D01*
Y153600D01*
X1082248Y154308D01*
X1081612D01*
X1080905Y155015D01*
Y157250D01*
X1081355Y157700D01*
Y158700D01*
X1080905Y159150D01*
Y160150D01*
X1081355Y160600D01*
Y161600D01*
X1080905Y162050D01*
Y163050D01*
X1081355Y163500D01*
Y164500D01*
X1080905Y164950D01*
Y166122D01*
X1081355Y166572D01*
Y167572D01*
X1080905Y168022D01*
Y169022D01*
X1081355Y169472D01*
Y170472D01*
X1080905Y170922D01*
Y171922D01*
X1081355Y172372D01*
Y173372D01*
X1080905Y173822D01*
Y174879D01*
X1081355Y175329D01*
Y176329D01*
X1080905Y176779D01*
Y178219D01*
X1081355Y178669D01*
Y179669D01*
X1080905Y180119D01*
Y181119D01*
X1081355Y181569D01*
Y182569D01*
X1080905Y183019D01*
Y186013D01*
G01X1119440Y14514D02*
X1121266Y16340D01*
Y17900D01*
X1119246Y19920D01*
Y20788D01*
X1120220Y21762D01*
X1121096D01*
X1121804Y22470D01*
Y23346D01*
X1122572Y24114D01*
Y24946D01*
X1123192Y25566D01*
Y26566D01*
X1122572Y27186D01*
Y37280D01*
X1123192Y37900D01*
Y38900D01*
X1122572Y39520D01*
Y40280D01*
X1123192Y40900D01*
Y41900D01*
X1122572Y42520D01*
Y118907D01*
X1085276Y156203D01*
Y183955D01*
X1084605Y184626D01*
Y186413D01*
G01X1079845Y186013D02*
Y154575D01*
X1117620Y116800D01*
Y115367D01*
X1116748Y114495D01*
X1113509D01*
X1112020Y113006D01*
Y109727D01*
X1113612Y108135D01*
X1117119D01*
X1117620Y107634D01*
Y100488D01*
X1116361Y99229D01*
Y25006D01*
X1112486Y21131D01*
Y13554D01*
X1114340Y11700D01*
G01X1119440Y11914D02*
X1117716Y13638D01*
Y18217D01*
X1118186Y18687D01*
Y21231D01*
X1121512Y24557D01*
Y118467D01*
X1084216Y155763D01*
Y167925D01*
X1083766Y168375D01*
Y169375D01*
X1084216Y169825D01*
Y171760D01*
X1083766Y172210D01*
Y173210D01*
X1084216Y173660D01*
Y175757D01*
X1083766Y176207D01*
Y177207D01*
X1084216Y177657D01*
Y180047D01*
X1083766Y180497D01*
Y181497D01*
X1084216Y181947D01*
Y183515D01*
X1083545Y184186D01*
Y186413D01*
G01X1131299Y17157D02*
X1133700Y19558D01*
Y22201D01*
X1133000Y22901D01*
Y25600D01*
X1133800Y26400D01*
Y27940D01*
X1132741Y28999D01*
Y34641D01*
X1133241Y35141D01*
Y36859D01*
X1132200Y37900D01*
Y39399D01*
X1132900Y40099D01*
Y41374D01*
X1132300Y41974D01*
Y45301D01*
X1133241Y46242D01*
Y48014D01*
X1132400Y48855D01*
Y53073D01*
X1133174Y53847D01*
Y56200D01*
X1133900Y56926D01*
Y58000D01*
X1133174Y58726D01*
Y60100D01*
X1134000Y60926D01*
Y62000D01*
X1133174Y62826D01*
Y63774D01*
X1134000Y64600D01*
Y65540D01*
X1132741Y66799D01*
Y72541D01*
X1133705Y73505D01*
Y74295D01*
X1132800Y75200D01*
Y83599D01*
X1133562Y84361D01*
Y85493D01*
X1132700Y86355D01*
Y91201D01*
X1133500Y92001D01*
Y119210D01*
X1100388Y152322D01*
Y154295D01*
X1099778Y154905D01*
X1098073D01*
X1097463Y155515D01*
Y157405D01*
X1098073Y158015D01*
X1099778D01*
X1100388Y158625D01*
Y160515D01*
X1099778Y161125D01*
X1098073D01*
X1097463Y161735D01*
Y163625D01*
X1098073Y164235D01*
X1099778D01*
X1100388Y164845D01*
Y167835D01*
X1092379Y175844D01*
Y188577D01*
G01X1134645Y12114D02*
X1132741Y14018D01*
Y15614D01*
X1136091Y18964D01*
Y28699D01*
X1136641Y29249D01*
Y34759D01*
X1135500Y35900D01*
Y47573D01*
X1136474Y48547D01*
Y53481D01*
X1135900Y54055D01*
Y66308D01*
X1136641Y67049D01*
Y72559D01*
X1136041Y73159D01*
Y74641D01*
X1136600Y75200D01*
Y83441D01*
X1136041Y84000D01*
Y85914D01*
X1136741Y86614D01*
Y91274D01*
X1136000Y92015D01*
Y120246D01*
X1106953Y149293D01*
Y153017D01*
X1106393Y153577D01*
X1104460D01*
X1103900Y154137D01*
Y155577D01*
X1104460Y156137D01*
X1106393D01*
X1106953Y156697D01*
Y164714D01*
X1094879Y176788D01*
Y188577D01*
G01X1061000Y401633D02*
Y469928D01*
X1089600Y498528D01*
Y508309D01*
X1087795Y510114D01*
G01X1043200Y393500D02*
Y396200D01*
X1045800Y398800D01*
Y403101D01*
X1050450Y407751D01*
Y476584D01*
X1075547Y501681D01*
Y503363D01*
X1074858Y504052D01*
X1073144D01*
X1072460Y504736D01*
Y506568D01*
X1073144Y507252D01*
X1074862D01*
X1077755Y510145D01*
Y512792D01*
G01X1042200Y393800D02*
Y397642D01*
X1043900Y399342D01*
Y404100D01*
X1048450Y408650D01*
Y477413D01*
X1070274Y499237D01*
Y509374D01*
X1072812Y511912D01*
Y513988D01*
X1071062Y515738D01*
Y518157D01*
G01X1059000Y401553D02*
Y470757D01*
X1061535Y473292D01*
Y475133D01*
X1062878Y476476D01*
X1063588Y476475D01*
X1064718D01*
X1066061Y477818D01*
Y479659D01*
X1067404Y481002D01*
X1068114Y481001D01*
X1069244D01*
X1070587Y482344D01*
Y483763D01*
X1072351Y485527D01*
X1073770D01*
X1075113Y486870D01*
Y488711D01*
X1076456Y490054D01*
X1077166Y490053D01*
X1078296D01*
X1079639Y491396D01*
Y493425D01*
X1081814Y495600D01*
X1083843D01*
X1086696Y498453D01*
Y505156D01*
X1085900Y505952D01*
Y511340D01*
X1084448Y512792D01*
G01X1047700Y391600D02*
Y393900D01*
X1052300Y398500D01*
X1053200D01*
X1054300Y399600D01*
Y403400D01*
X1055700Y404800D01*
Y474369D01*
X1079014Y497683D01*
Y497684D01*
X1083000Y501670D01*
Y510900D01*
X1082572Y511328D01*
Y513872D01*
X1082999Y514299D01*
Y516101D01*
X1082640Y516460D01*
Y519040D01*
X1082822Y519222D01*
Y530278D01*
X1081396Y531704D01*
Y534224D01*
X1082836Y535664D01*
Y541211D01*
X1087797Y546172D01*
Y547922D01*
G01X1045700Y392507D02*
Y394700D01*
X1050700Y399700D01*
Y402600D01*
X1053700Y405600D01*
Y475199D01*
X1080100Y501599D01*
Y508300D01*
X1079385Y509015D01*
Y510885D01*
X1080006Y511506D01*
Y513894D01*
X1079300Y514600D01*
Y516700D01*
X1079600Y517000D01*
Y522629D01*
X1080303Y523332D01*
Y526822D01*
X1079369Y527756D01*
Y542841D01*
X1084450Y547922D01*
G01X1066201Y401566D02*
Y467701D01*
X1096500Y498000D01*
Y510800D01*
X1095500Y511800D01*
Y513800D01*
X1096500Y514800D01*
Y517600D01*
X1096093Y518007D01*
Y531205D01*
X1096200Y531312D01*
Y538300D01*
X1096500Y538600D01*
Y548500D01*
X1095974Y549026D01*
Y551774D01*
X1096279Y552079D01*
Y556979D01*
X1096600Y557300D01*
Y567300D01*
X1096117Y567783D01*
Y577402D01*
X1087797Y585722D01*
G01X1075980Y413233D02*
X1075747Y413466D01*
Y459519D01*
X1090548Y474320D01*
Y478849D01*
X1107162Y495463D01*
Y506662D01*
X1109941Y509441D01*
Y510707D01*
X1108591Y512057D01*
Y516307D01*
X1109941Y517657D01*
Y519100D01*
X1109600Y519441D01*
Y527900D01*
X1109941Y528241D01*
Y529258D01*
X1108591Y530608D01*
Y535290D01*
X1109941Y536640D01*
Y538260D01*
X1109600Y538601D01*
Y546800D01*
X1109941Y547141D01*
Y548507D01*
X1108591Y549857D01*
Y554107D01*
X1109741Y555257D01*
Y557300D01*
X1109500Y557541D01*
Y565800D01*
X1109741Y566041D01*
Y567259D01*
X1108641Y568359D01*
Y573141D01*
X1109791Y574291D01*
Y575600D01*
X1109500Y575891D01*
Y584600D01*
X1109791Y584891D01*
Y586457D01*
X1106441Y589807D01*
Y592324D01*
X1107874Y593757D01*
G01X1078480Y413233D02*
X1078322Y413391D01*
Y458519D01*
X1095214Y475411D01*
Y476273D01*
X1093508Y477980D01*
Y478842D01*
X1094492Y479826D01*
X1095354D01*
X1097060Y478119D01*
X1097922D01*
X1100102Y480299D01*
Y485737D01*
X1110253Y495888D01*
Y496596D01*
X1109898Y496951D01*
Y498931D01*
X1110508Y499541D01*
X1112990D01*
X1113600Y500151D01*
Y502131D01*
X1112990Y502741D01*
X1110508D01*
X1109898Y503351D01*
Y505331D01*
X1110508Y505941D01*
X1112990D01*
X1113600Y506551D01*
Y508200D01*
X1112441Y509359D01*
Y518600D01*
X1112900Y519059D01*
Y528100D01*
X1112441Y528559D01*
Y537700D01*
X1112900Y538159D01*
Y546000D01*
X1112441Y546459D01*
Y556540D01*
X1112900Y556999D01*
Y565300D01*
X1112441Y565759D01*
Y575500D01*
X1112900Y575959D01*
Y584300D01*
X1112441Y584759D01*
Y586443D01*
X1110520Y588364D01*
Y588714D01*
G01X1094489Y406992D02*
X1094400Y407081D01*
Y415600D01*
X1093100Y416900D01*
Y452426D01*
X1131028Y490354D01*
Y507127D01*
X1133145Y509244D01*
Y511253D01*
X1132768Y511630D01*
Y516668D01*
X1133104Y517004D01*
Y529903D01*
X1132200Y530807D01*
Y535101D01*
X1133180Y536081D01*
Y549120D01*
X1132500Y549800D01*
Y554100D01*
X1133348Y554948D01*
Y557193D01*
X1132975Y557566D01*
Y565375D01*
X1133222Y565622D01*
Y567616D01*
X1132300Y568538D01*
Y573285D01*
X1133404Y574389D01*
Y586444D01*
X1130861Y588987D01*
Y593319D01*
X1131299Y593757D01*
G01X1098631Y406491D02*
X1099000Y406860D01*
Y414000D01*
X1095936Y417064D01*
Y451714D01*
X1135498Y491276D01*
Y502086D01*
X1134888Y502696D01*
X1133594D01*
X1132984Y503306D01*
Y504696D01*
X1133594Y505306D01*
X1134888D01*
X1135498Y505916D01*
Y510498D01*
X1137100Y512100D01*
Y516348D01*
X1136091Y517357D01*
Y519500D01*
X1136300Y519709D01*
Y527700D01*
X1136091Y527909D01*
Y529816D01*
X1136741Y530466D01*
Y535458D01*
X1135700Y536499D01*
Y537899D01*
X1136300Y538499D01*
Y546400D01*
X1136041Y546659D01*
Y549641D01*
G01X1136091Y554809D02*
Y567647D01*
X1136941Y568497D01*
Y573058D01*
X1135941Y574058D01*
Y575300D01*
X1136300Y575659D01*
Y584300D01*
X1135941Y584659D01*
Y587470D01*
X1134645Y588766D01*
Y588714D01*
G01X1070980Y411038D02*
X1070747Y411271D01*
Y466138D01*
X1101582Y496973D01*
Y507641D01*
X1103141Y509200D01*
Y510897D01*
X1102241Y511797D01*
Y516457D01*
X1103141Y517357D01*
Y519500D01*
X1102900Y519741D01*
Y527800D01*
X1103141Y528041D01*
Y529358D01*
X1102241Y530258D01*
Y535242D01*
X1103241Y536242D01*
Y537900D01*
X1102900Y538241D01*
Y546500D01*
X1103241Y546841D01*
Y548557D01*
X1102241Y549557D01*
Y554257D01*
X1103141Y555157D01*
Y557300D01*
X1102800Y557641D01*
Y565600D01*
X1103141Y565941D01*
Y567159D01*
X1102093Y568207D01*
Y572944D01*
X1103091Y573942D01*
Y575500D01*
X1102900Y575691D01*
Y584800D01*
X1103091Y584991D01*
Y586457D01*
X1100100Y589448D01*
Y592676D01*
X1101181Y593757D01*
G01X1073480Y410647D02*
X1073247Y410880D01*
Y465354D01*
X1078917Y471024D01*
X1079779D01*
X1081018Y469785D01*
X1081880D01*
X1082864Y470769D01*
Y471631D01*
X1081625Y472870D01*
Y473732D01*
X1082609Y474716D01*
X1083471D01*
X1084710Y473477D01*
X1085572D01*
X1086556Y474461D01*
Y475323D01*
X1085317Y476562D01*
Y477424D01*
X1104280Y496387D01*
Y507598D01*
X1105841Y509159D01*
Y511497D01*
X1106700Y512356D01*
Y516200D01*
X1105400Y517500D01*
Y518999D01*
X1106200Y519799D01*
Y527500D01*
X1105541Y528159D01*
Y529640D01*
X1106400Y530499D01*
Y535499D01*
X1105636Y536263D01*
Y537635D01*
X1106200Y538199D01*
Y546200D01*
X1105500Y546900D01*
Y548900D01*
X1106400Y549800D01*
Y553900D01*
X1105486Y554814D01*
Y556985D01*
X1106200Y557699D01*
Y565500D01*
X1105841Y565859D01*
Y567997D01*
X1106341Y568497D01*
Y572656D01*
X1105741Y573256D01*
Y575400D01*
X1106200Y575859D01*
Y584500D01*
X1105741Y584959D01*
Y587200D01*
X1104227Y588714D01*
G01X1089529Y406641D02*
X1089200Y406970D01*
Y414300D01*
X1088100Y415400D01*
Y454224D01*
X1123654Y489778D01*
Y506698D01*
X1126391Y509435D01*
Y511707D01*
X1126041Y512057D01*
Y516957D01*
X1126441Y517357D01*
Y529842D01*
X1126041Y530242D01*
Y535942D01*
X1126503Y536404D01*
Y549395D01*
X1126041Y549857D01*
Y554757D01*
X1126641Y555357D01*
Y567397D01*
X1125568Y568470D01*
Y572969D01*
X1126448Y573849D01*
Y586750D01*
X1124173Y589025D01*
Y593324D01*
X1124606Y593757D01*
G01X1091989Y406641D02*
X1091700Y406930D01*
Y414800D01*
X1090600Y415900D01*
Y453188D01*
X1128022Y490610D01*
Y492317D01*
X1127512Y492827D01*
X1126694D01*
X1126084Y493437D01*
Y494827D01*
X1126694Y495437D01*
X1128212D01*
X1128822Y496047D01*
Y497437D01*
X1128212Y498047D01*
X1126694D01*
X1126084Y498657D01*
Y500047D01*
X1126694Y500657D01*
X1128212D01*
X1128822Y501267D01*
Y502657D01*
X1128212Y503267D01*
X1126694D01*
X1126084Y503877D01*
Y505944D01*
X1129341Y509201D01*
Y511257D01*
X1130241Y512157D01*
Y516557D01*
X1129441Y517357D01*
Y519300D01*
X1129600Y519459D01*
Y527600D01*
X1129441Y527759D01*
Y529842D01*
X1130141Y530542D01*
Y535658D01*
X1129341Y536458D01*
Y537700D01*
X1129600Y537959D01*
Y546500D01*
X1129341Y546759D01*
Y549057D01*
X1130241Y549957D01*
Y554357D01*
X1129141Y555457D01*
Y557200D01*
X1129600Y557659D01*
Y565700D01*
X1129441Y565859D01*
Y567597D01*
X1130007Y568163D01*
Y573393D01*
X1129341Y574059D01*
Y575500D01*
X1129600Y575759D01*
Y584300D01*
X1129341Y584559D01*
Y587368D01*
X1129298D01*
X1127952Y588714D01*
G01X1106081Y420405D02*
Y448800D01*
X1140485Y483204D01*
X1176657D01*
X1182329Y488876D01*
Y496597D01*
X1183271Y497539D01*
Y510999D01*
X1182348Y511922D01*
Y516442D01*
X1183563Y517657D01*
Y529267D01*
X1182349Y530481D01*
Y535350D01*
X1183214Y536215D01*
Y548856D01*
X1182213Y549857D01*
Y554107D01*
X1183243Y555137D01*
Y567387D01*
X1182263Y568367D01*
Y573163D01*
X1183242Y574142D01*
Y586628D01*
X1180756Y589114D01*
Y593017D01*
X1181496Y593757D01*
G01X1108581Y420405D02*
Y447764D01*
X1141115Y480298D01*
X1152514D01*
X1153124Y479688D01*
Y478478D01*
X1153734Y477868D01*
X1155124D01*
X1155734Y478478D01*
Y479688D01*
X1156344Y480298D01*
X1157734D01*
X1158344Y479688D01*
Y478478D01*
X1158954Y477868D01*
X1160344D01*
X1160954Y478478D01*
Y479688D01*
X1161564Y480298D01*
X1163745D01*
X1164355Y479688D01*
Y478450D01*
X1164965Y477840D01*
X1166355D01*
X1166965Y478450D01*
Y479688D01*
X1167575Y480298D01*
X1168965D01*
X1169575Y479688D01*
Y478450D01*
X1170185Y477840D01*
X1174059D01*
X1186063Y489844D01*
Y499564D01*
X1187811Y501312D01*
Y502790D01*
X1187201Y503400D01*
X1186049D01*
X1185439Y504010D01*
Y504890D01*
X1186049Y505500D01*
X1187201D01*
X1187811Y506110D01*
Y507489D01*
X1186063Y509237D01*
Y518664D01*
X1186500Y519101D01*
Y527800D01*
X1186063Y528237D01*
Y537700D01*
X1186500Y538137D01*
Y546100D01*
X1186063Y546537D01*
Y556664D01*
X1186500Y557101D01*
Y565300D01*
X1186063Y565737D01*
Y586443D01*
X1184142Y588364D01*
Y588714D01*
G01X1101081Y419941D02*
X1099936Y421086D01*
Y449727D01*
X1138509Y488300D01*
X1170201D01*
X1172400Y490499D01*
Y499500D01*
X1175951Y503051D01*
Y508588D01*
X1176763Y509400D01*
Y510897D01*
X1175863Y511797D01*
Y516457D01*
X1176763Y517357D01*
Y529438D01*
X1175863Y530338D01*
Y535242D01*
X1176734Y536113D01*
Y549066D01*
X1175400Y550400D01*
Y553794D01*
X1177336Y555730D01*
Y556863D01*
X1176500Y557699D01*
Y565600D01*
X1176763Y565863D01*
Y567237D01*
X1175400Y568600D01*
Y572629D01*
X1176713Y573942D01*
Y586587D01*
X1175600Y587700D01*
X1174400D01*
X1173563Y588537D01*
Y592517D01*
X1174803Y593757D01*
G01X1103800Y420160D02*
Y421900D01*
X1102436Y423264D01*
Y448691D01*
X1139965Y486220D01*
X1170821D01*
X1172218Y487617D01*
X1173039D01*
X1175144Y485512D01*
X1176049D01*
X1177450Y486913D01*
Y487732D01*
X1179600Y489882D01*
Y494200D01*
X1178264Y495536D01*
Y505540D01*
X1178902Y506178D01*
X1179998D01*
X1180720Y506900D01*
Y508080D01*
X1179463Y509337D01*
Y511497D01*
X1179713Y511747D01*
Y517207D01*
X1179463Y517457D01*
Y518712D01*
X1180873Y520122D01*
Y521297D01*
X1180263Y521907D01*
X1179585D01*
X1178975Y522517D01*
Y524497D01*
X1179585Y525107D01*
X1180263D01*
X1180873Y525717D01*
Y526941D01*
X1179463Y528351D01*
Y529992D01*
X1179713Y530242D01*
Y535192D01*
X1179363Y535542D01*
Y548457D01*
X1179713Y548807D01*
Y555007D01*
X1179463Y555257D01*
Y557100D01*
X1179800Y557437D01*
Y565900D01*
X1179463Y566237D01*
Y567997D01*
X1179963Y568497D01*
Y572656D01*
X1179363Y573256D01*
Y575300D01*
X1180300Y576237D01*
Y583800D01*
X1179363Y584737D01*
Y587200D01*
X1177849Y588714D01*
G01X1082185Y412574D02*
Y457017D01*
X1104009Y478841D01*
Y483590D01*
X1115658Y495239D01*
X1117098Y498717D01*
X1117421Y499497D01*
Y586915D01*
X1116341Y587995D01*
Y589044D01*
X1114485Y590900D01*
X1114341D01*
G01X1084875Y412574D02*
Y455875D01*
X1108509Y479509D01*
Y480371D01*
X1107503Y481377D01*
Y483117D01*
X1109111Y484725D01*
X1110851D01*
X1111857Y483719D01*
X1112719D01*
X1113703Y484703D01*
Y485565D01*
X1112586Y486682D01*
Y488381D01*
X1114194Y489989D01*
X1115975D01*
X1117051Y488913D01*
X1117913D01*
X1119995Y490995D01*
Y508795D01*
X1121461Y510261D01*
Y576231D01*
X1120841Y576851D01*
Y577851D01*
X1121461Y578471D01*
Y579471D01*
X1120841Y580091D01*
Y581091D01*
X1121461Y581711D01*
Y582711D01*
X1120841Y583331D01*
Y584331D01*
X1121461Y584951D01*
Y587594D01*
X1120541Y588514D01*
X1119440D01*
G01X1081125Y412574D02*
Y457457D01*
X1102949Y479281D01*
Y484030D01*
X1114758Y495840D01*
X1115559Y497774D01*
X1115950Y498717D01*
X1116361Y499708D01*
Y563854D01*
X1115909Y564306D01*
Y565306D01*
X1116361Y565758D01*
Y576050D01*
X1115867Y576544D01*
Y577544D01*
X1116361Y578038D01*
Y579164D01*
X1115741Y579784D01*
Y580784D01*
X1116361Y581404D01*
Y582404D01*
X1115741Y583024D01*
Y584024D01*
X1116361Y584644D01*
Y586474D01*
X1114535Y588300D01*
X1114340D01*
G01X1111238Y422000D02*
Y445838D01*
X1141228Y475828D01*
X1175951D01*
X1189983Y489860D01*
Y576310D01*
X1189531Y576762D01*
Y577762D01*
X1189983Y578214D01*
Y579368D01*
X1189363Y579988D01*
Y580988D01*
X1189983Y581608D01*
Y582608D01*
X1189363Y583228D01*
Y584228D01*
X1189983Y584848D01*
Y586986D01*
X1188669Y588300D01*
X1187963D01*
G01X1085935Y412574D02*
Y455435D01*
X1109569Y479069D01*
Y480811D01*
X1108563Y481817D01*
Y482677D01*
X1109551Y483665D01*
X1110411D01*
X1111417Y482659D01*
X1113159D01*
X1114763Y484263D01*
Y486005D01*
X1113646Y487122D01*
Y487941D01*
X1114634Y488929D01*
X1115535D01*
X1116611Y487853D01*
X1118353D01*
X1121055Y490555D01*
Y508355D01*
X1122521Y509821D01*
Y588034D01*
X1119441Y591114D01*
X1119440D01*
G01X1064201Y402640D02*
Y468602D01*
X1092819Y497220D01*
Y508879D01*
X1092500Y509198D01*
Y511400D01*
X1093300Y512200D01*
Y513600D01*
X1092600Y514300D01*
Y516400D01*
X1093300Y517100D01*
Y518900D01*
X1092871Y519329D01*
Y530371D01*
X1093300Y530800D01*
Y532500D01*
X1092600Y533200D01*
Y535600D01*
X1092855Y535855D01*
Y570345D01*
X1089418Y573782D01*
Y580754D01*
X1084450Y585722D01*
G01X1050983Y512792D02*
Y514817D01*
X1047792Y518008D01*
Y521589D01*
X1048405Y522202D01*
X1050224D01*
X1050820Y522798D01*
Y523788D01*
X1050196Y524412D01*
X1048865D01*
X1048255Y525022D01*
Y526905D01*
X1049367Y528017D01*
Y530433D01*
X1049100Y530700D01*
Y532700D01*
X1050984Y534584D01*
Y536956D01*
X1050985Y536957D01*
G01X1087795Y510114D02*
Y512495D01*
X1089600Y514300D01*
Y516400D01*
X1089300Y516700D01*
Y519100D01*
X1089433Y519233D01*
Y530067D01*
X1089200Y530300D01*
Y535554D01*
X1087797Y536957D01*
G01X1054330Y509999D02*
X1053100Y511229D01*
Y513600D01*
X1052606Y514094D01*
Y516706D01*
X1052865Y516965D01*
Y519235D01*
X1052628Y519472D01*
Y530428D01*
X1053100Y530900D01*
Y533034D01*
X1054330Y534264D01*
Y536956D01*
X1054331Y536957D01*
G01X1077755Y512792D02*
X1076300Y514247D01*
Y516610D01*
X1075800Y517110D01*
Y519000D01*
X1076151Y519351D01*
Y535351D01*
X1077757Y536957D01*
G01X1071062Y518157D02*
X1070201D01*
X1069370Y518988D01*
Y520433D01*
X1070362Y521425D01*
X1072949D01*
X1074319Y522795D01*
Y524891D01*
X1073336Y525874D01*
X1072129D01*
X1070880Y524625D01*
X1069730D01*
X1068640Y525715D01*
Y526598D01*
X1071064Y529022D01*
G01X1084448Y512792D02*
Y513548D01*
X1085287Y514387D01*
Y515797D01*
X1087467Y517977D01*
Y519041D01*
X1086859Y519649D01*
X1085748D01*
X1085132Y520265D01*
Y521544D01*
X1085770Y522182D01*
X1086765D01*
X1087348Y522765D01*
Y523755D01*
X1086711Y524392D01*
X1085700D01*
X1085090Y525002D01*
Y526835D01*
X1086083Y527828D01*
Y535324D01*
X1084450Y536957D01*
G01X1050984Y547922D02*
Y550634D01*
X1049264Y552354D01*
Y561246D01*
X1049353Y561335D01*
Y568628D01*
X1050985Y570260D01*
Y574757D01*
G01X1087797Y547922D02*
X1087795Y547924D01*
Y553187D01*
X1086186Y554796D01*
Y560475D01*
X1087029Y561318D01*
Y564830D01*
X1086186Y565673D01*
Y567910D01*
X1087795Y569519D01*
Y574755D01*
X1087797Y574757D01*
G01X1054331Y547922D02*
Y550834D01*
X1052717Y552448D01*
Y567940D01*
X1054331Y569554D01*
Y574757D01*
G01X1077757Y547922D02*
X1079486Y549651D01*
Y557114D01*
X1079369Y557231D01*
Y568069D01*
X1077755Y569683D01*
Y574755D01*
X1077757Y574757D01*
G01X1071064Y555857D02*
Y557122D01*
X1071674Y557732D01*
X1075370D01*
X1076001Y558363D01*
Y559353D01*
X1075412Y559942D01*
X1071674D01*
X1071064Y560552D01*
Y561542D01*
X1071674Y562152D01*
X1075516D01*
X1076126Y562762D01*
Y563752D01*
X1075516Y564362D01*
X1071674D01*
X1071064Y564972D01*
Y566822D01*
G01X1084450Y547922D02*
X1084840Y548312D01*
Y552968D01*
X1082727Y555081D01*
Y560321D01*
X1082844Y560438D01*
Y567556D01*
X1084879Y569591D01*
Y572321D01*
X1084450Y572750D01*
Y574757D01*
G01X1050985Y585722D02*
Y590982D01*
X1049251Y592716D01*
Y595051D01*
X1049581Y595381D01*
Y605547D01*
X1049105Y606023D01*
Y608337D01*
X1050984Y610216D01*
Y612658D01*
G01X1087797Y585722D02*
X1087795Y585724D01*
Y587895D01*
X1089418Y589518D01*
Y594618D01*
X1090300Y595500D01*
Y604900D01*
X1087795Y607405D01*
Y609864D01*
G01X1054331Y585722D02*
X1056000Y587391D01*
Y600240D01*
X1056385Y600625D01*
Y605547D01*
X1054330Y607602D01*
Y609864D01*
G01X1077757Y585722D02*
Y590657D01*
X1079472Y592372D01*
Y595028D01*
X1078300Y596200D01*
Y604800D01*
X1079619Y606119D01*
Y608381D01*
X1077755Y610245D01*
Y612657D01*
G01X1084450Y585722D02*
Y587910D01*
X1084878Y588338D01*
Y590624D01*
X1082734Y592768D01*
Y594934D01*
X1083022Y595222D01*
Y605678D01*
X1082646Y606054D01*
Y608446D01*
X1084448Y610248D01*
Y612657D01*
G01X1071064Y593657D02*
X1071062Y593659D01*
Y596531D01*
X1070028Y597565D01*
X1065285D01*
X1064442Y598408D01*
Y599892D01*
X1065315Y600765D01*
X1071336D01*
X1072394Y601823D01*
Y605960D01*
X1071062Y607292D01*
G01X1147331Y49914D02*
X1148804Y48441D01*
Y35316D01*
X1149420Y34700D01*
Y33356D01*
X1147964Y31900D01*
X1146564D01*
X1144685Y30021D01*
Y27899D01*
G01X1137992D02*
X1139100Y29007D01*
Y30561D01*
X1140239Y31700D01*
X1141463D01*
X1143039Y33276D01*
Y34900D01*
X1142264Y35675D01*
Y48688D01*
X1141038Y49914D01*
G01X1151177Y30750D02*
X1151947Y31520D01*
X1152930D01*
X1154258Y32848D01*
Y48993D01*
X1151151Y52100D01*
G01Y33399D02*
X1151970Y32580D01*
X1152487D01*
X1153198Y33291D01*
Y36580D01*
X1151278Y38500D01*
Y39500D01*
X1151878Y40100D01*
X1152378D01*
X1153198Y40920D01*
Y41880D01*
X1152478Y42600D01*
X1151766D01*
X1151264Y43102D01*
Y44434D01*
X1151880Y45050D01*
X1152228D01*
X1153198Y46020D01*
Y48552D01*
X1152250Y49500D01*
X1151152D01*
G01X1156251Y30540D02*
X1156252D01*
X1159444Y33732D01*
Y49121D01*
X1156251Y52314D01*
G01X1110520Y-4100D02*
X1109653Y-3233D01*
Y-932D01*
X1108020Y701D01*
Y2000D01*
X1109370Y3350D01*
Y4250D01*
X1108120Y5500D01*
Y6699D01*
X1109653Y8232D01*
Y10200D01*
X1106753Y13100D01*
Y16036D01*
X1107874Y17157D01*
G01Y-9901D02*
Y-7779D01*
X1109753Y-5900D01*
X1111153D01*
X1112609Y-4444D01*
Y-3100D01*
X1111993Y-2484D01*
Y10641D01*
X1110520Y12114D01*
G01X1134645Y-3700D02*
X1133078Y-2133D01*
Y-932D01*
X1131720Y426D01*
Y1799D01*
X1132920Y2999D01*
Y4125D01*
X1131720Y5325D01*
Y6900D01*
X1133520Y8700D01*
Y9758D01*
X1130178Y13100D01*
Y16036D01*
X1131299Y17157D01*
G01Y-9901D02*
X1132546Y-8654D01*
Y-7400D01*
X1133846Y-6100D01*
X1134846D01*
X1136646Y-4300D01*
Y-2900D01*
X1136034Y-2288D01*
Y10725D01*
X1134645Y12114D01*
G01X1101181Y17157D02*
X1100253Y16229D01*
Y13101D01*
X1103053Y10301D01*
Y8432D01*
X1101670Y7049D01*
Y5650D01*
X1103120Y4200D01*
Y3000D01*
X1101620Y1500D01*
Y301D01*
X1103053Y-1132D01*
Y-3012D01*
X1104141Y-4100D01*
G01X1104227Y12114D02*
X1105453Y10888D01*
Y-2125D01*
X1106228Y-2900D01*
Y-4524D01*
X1104652Y-6100D01*
X1103428D01*
X1101181Y-8347D01*
Y-9901D01*
G01X1127952Y-3700D02*
X1126478Y-2226D01*
Y-1132D01*
X1125045Y301D01*
Y1524D01*
X1125260Y1740D01*
X1126545Y3024D01*
Y4376D01*
X1125045Y5876D01*
Y6999D01*
X1126720Y8674D01*
Y10059D01*
X1123678Y13101D01*
Y16229D01*
X1124606Y17157D01*
G01Y-9901D02*
X1125853Y-8654D01*
Y-7400D01*
X1127153Y-6100D01*
X1128153D01*
X1129953Y-4300D01*
Y-2900D01*
X1129341Y-2288D01*
Y10725D01*
X1127952Y12114D01*
G01X1144685Y17157D02*
X1143564Y16036D01*
Y13100D01*
X1146464Y10200D01*
Y8232D01*
X1144931Y6699D01*
Y5500D01*
X1146181Y4250D01*
Y3350D01*
X1144831Y2000D01*
Y701D01*
X1146464Y-932D01*
Y-3233D01*
X1147331Y-4100D01*
G01Y12114D02*
X1148804Y10641D01*
Y-2484D01*
X1149420Y-3100D01*
Y-4444D01*
X1147964Y-5900D01*
X1146564D01*
X1144685Y-7779D01*
Y-9901D01*
G01X1137992Y17157D02*
X1137064Y16229D01*
Y13101D01*
X1139864Y10301D01*
Y8432D01*
X1138481Y7049D01*
Y5650D01*
X1139931Y4200D01*
Y3000D01*
X1138431Y1500D01*
Y301D01*
X1139864Y-1132D01*
Y-3012D01*
X1140952Y-4100D01*
G01X1141038Y12114D02*
X1142264Y10888D01*
Y-2125D01*
X1143039Y-2900D01*
Y-4524D01*
X1141463Y-6100D01*
X1140239D01*
X1137992Y-8347D01*
Y-9901D01*
G01X1114366Y-7050D02*
X1115136Y-6280D01*
X1116118D01*
X1117446Y-4952D01*
Y11194D01*
X1114340Y14300D01*
G01X1151152D02*
X1154258Y11194D01*
Y-4952D01*
X1152930Y-6280D01*
X1151948D01*
X1151178Y-7050D01*
G01X1119440Y-7260D02*
X1122632Y-4068D01*
Y11322D01*
X1119440Y14514D01*
G01X1156252D02*
X1159444Y11322D01*
Y-4068D01*
X1156252Y-7260D01*
G01X1114340Y-4401D02*
X1115159Y-5220D01*
X1115675D01*
X1116386Y-4509D01*
Y-1220D01*
X1114466Y700D01*
Y1700D01*
X1115066Y2300D01*
X1115566D01*
X1116386Y3120D01*
Y4080D01*
X1115666Y4800D01*
X1114954D01*
X1114452Y5302D01*
Y6634D01*
X1115068Y7250D01*
X1115416D01*
X1116386Y8220D01*
Y10753D01*
X1115439Y11700D01*
X1114340D01*
G01X1151152D02*
X1152251D01*
X1153198Y10753D01*
Y8220D01*
X1152228Y7250D01*
X1151880D01*
X1151264Y6634D01*
Y5302D01*
X1151766Y4800D01*
X1152478D01*
X1153198Y4080D01*
Y3120D01*
X1152378Y2300D01*
X1151878D01*
X1151278Y1700D01*
Y700D01*
X1153198Y-1220D01*
Y-4509D01*
X1152487Y-5220D01*
X1151971D01*
X1151152Y-4401D01*
G01X1119440Y-4651D02*
X1120549D01*
X1121572Y-3628D01*
Y-1007D01*
X1120865Y-300D01*
X1120067D01*
X1119466Y301D01*
Y1499D01*
X1120067Y2100D01*
X1120765D01*
X1121572Y2907D01*
Y4280D01*
X1120852Y5000D01*
X1120352D01*
X1119652Y5700D01*
Y6700D01*
X1120352Y7400D01*
X1120866D01*
X1121572Y8106D01*
Y10881D01*
X1120538Y11915D01*
X1119440D01*
Y11914D01*
G01X1156252D02*
Y11915D01*
X1157350D01*
X1158384Y10881D01*
Y8106D01*
X1157678Y7400D01*
X1157164D01*
X1156464Y6700D01*
Y5700D01*
X1157164Y5000D01*
X1157664D01*
X1158384Y4280D01*
Y2907D01*
X1157577Y2100D01*
X1156879D01*
X1156278Y1499D01*
Y301D01*
X1156879Y-300D01*
X1157677D01*
X1158384Y-1007D01*
Y-3628D01*
X1157361Y-4651D01*
X1156252D01*
G01X1144685Y54957D02*
Y62670D01*
X1146594Y64579D01*
Y66207D01*
X1145494Y67307D01*
Y72195D01*
X1146494Y73195D01*
Y74906D01*
X1146200Y75200D01*
Y83706D01*
X1146494Y84000D01*
Y85474D01*
X1145094Y86874D01*
Y90694D01*
X1146494Y92094D01*
Y105106D01*
X1144685Y106915D01*
Y112207D01*
X1144535Y112357D01*
G01X1147331Y33700D02*
X1146464Y34567D01*
Y36868D01*
X1144831Y38501D01*
Y39800D01*
X1146181Y41150D01*
Y42050D01*
X1144931Y43300D01*
Y44499D01*
X1146464Y46032D01*
Y48000D01*
X1143564Y50900D01*
Y53836D01*
X1144685Y54957D01*
G01X1147331Y106964D02*
X1149194Y105101D01*
Y83900D01*
X1149800Y83294D01*
Y75200D01*
X1149194Y74594D01*
Y63859D01*
X1146674Y61339D01*
Y54374D01*
X1145600Y53300D01*
Y51645D01*
X1147331Y49914D01*
G01X1138242Y112357D02*
Y107158D01*
X1140100Y105300D01*
Y91980D01*
X1139094Y90974D01*
Y86374D01*
X1139894Y85574D01*
Y84000D01*
X1139300Y83406D01*
Y75300D01*
X1139894Y74706D01*
Y72959D01*
X1139094Y72159D01*
Y67107D01*
X1139894Y66307D01*
Y63359D01*
X1137992Y61457D01*
Y54957D01*
G01D02*
X1138700Y54249D01*
Y49265D01*
X1139864Y48101D01*
Y46364D01*
X1138000Y44500D01*
Y43899D01*
X1139931Y41968D01*
Y41232D01*
X1138000Y39301D01*
Y38500D01*
X1139864Y36636D01*
Y34788D01*
X1140952Y33700D01*
G01X1141038Y49914D02*
Y56962D01*
X1140874Y57126D01*
Y61302D01*
X1142594Y63022D01*
Y67059D01*
X1142894Y67359D01*
Y72659D01*
X1142594Y72959D01*
Y74694D01*
X1143100Y75200D01*
Y83500D01*
X1142594Y84006D01*
Y86074D01*
X1142994Y86474D01*
Y91174D01*
X1142694Y91474D01*
Y105308D01*
X1141038Y106964D01*
G01X1151151Y52100D02*
X1152878Y53827D01*
Y56072D01*
X1152169Y56781D01*
Y60169D01*
X1154169Y62169D01*
Y75032D01*
X1153200Y76001D01*
Y82700D01*
X1154169Y83669D01*
Y107497D01*
X1151152Y110514D01*
G01X1156251Y33149D02*
X1157361D01*
X1158384Y34172D01*
Y36793D01*
X1157677Y37500D01*
X1156879D01*
X1156278Y38101D01*
Y39299D01*
X1156879Y39900D01*
X1157577D01*
X1158384Y40707D01*
Y42080D01*
X1157664Y42800D01*
X1157164D01*
X1156464Y43500D01*
Y44500D01*
X1157164Y45200D01*
X1157678D01*
X1158384Y45906D01*
Y48681D01*
X1157350Y49715D01*
X1156251D01*
G01Y49714D02*
Y49715D01*
G01D02*
X1154528Y51438D01*
Y55739D01*
X1156309Y57520D01*
Y58192D01*
X1158209Y60092D01*
Y105698D01*
X1156252Y107655D01*
G01X1151178Y107865D02*
X1153109Y105934D01*
Y84109D01*
X1152140Y83140D01*
Y75561D01*
X1153109Y74592D01*
Y62609D01*
X1151109Y60609D01*
Y57320D01*
X1149178Y55389D01*
Y51474D01*
X1151152Y49500D01*
G01D02*
X1151151D01*
G01X1156251Y52314D02*
X1158100Y54163D01*
Y55889D01*
X1157369Y56620D01*
Y57749D01*
X1159269Y59649D01*
Y107247D01*
X1156278Y110238D01*
Y110264D01*
G01X1181496Y17157D02*
Y24796D01*
X1183363Y26663D01*
Y28444D01*
X1182213Y29594D01*
Y34213D01*
X1183563Y35563D01*
Y47355D01*
X1182274Y48644D01*
Y53158D01*
X1183374Y54258D01*
Y66227D01*
X1183201Y66400D01*
Y66406D01*
X1182274Y67333D01*
Y72175D01*
X1183574Y73475D01*
Y74826D01*
X1182900Y75500D01*
Y83526D01*
X1183574Y84200D01*
Y85174D01*
X1182274Y86474D01*
Y90974D01*
X1183374Y92074D01*
Y104974D01*
X1182274Y106074D01*
Y110438D01*
X1183392Y111556D01*
Y114734D01*
X1172126Y126000D01*
X1171044D01*
X1170244Y125200D01*
Y123782D01*
X1169444Y122982D01*
X1167844D01*
X1167044Y123782D01*
Y125200D01*
X1166244Y126000D01*
X1164644D01*
X1163844Y125200D01*
Y124560D01*
X1163284Y124000D01*
X1161204D01*
X1160644Y124560D01*
Y127356D01*
X1158900Y129100D01*
X1139875D01*
X1115859Y153116D01*
Y166859D01*
X1103892Y178826D01*
Y185697D01*
G01X1184142Y12114D02*
X1182069Y14187D01*
Y15168D01*
X1183563Y16662D01*
Y23363D01*
X1186063Y25863D01*
Y74863D01*
X1186700Y75500D01*
Y83263D01*
X1186063Y83900D01*
Y115600D01*
X1170563Y131100D01*
X1145178D01*
X1143192Y133086D01*
X1139426D01*
X1118264Y154248D01*
Y168028D01*
X1106100Y180192D01*
Y185400D01*
G01X1204921Y17157D02*
X1207163Y19399D01*
Y28237D01*
X1206400Y29000D01*
Y34900D01*
X1206863Y35363D01*
Y36800D01*
X1206200Y37463D01*
Y45400D01*
X1206863Y46063D01*
Y48014D01*
X1206263Y48614D01*
Y53526D01*
X1207000Y54263D01*
Y66233D01*
X1206174Y67059D01*
Y72375D01*
X1206874Y73075D01*
Y74800D01*
X1206200Y75474D01*
Y83300D01*
X1206874Y83974D01*
Y85674D01*
X1206174Y86374D01*
Y90938D01*
X1206900Y91664D01*
Y103000D01*
X1207608Y103708D01*
Y104840D01*
X1206074Y106374D01*
Y110638D01*
X1207800Y112364D01*
Y115819D01*
X1173319Y150300D01*
X1155348D01*
X1154448Y149400D01*
X1153008D01*
X1152448Y149960D01*
Y151240D01*
X1151888Y151800D01*
X1150448D01*
X1149888Y151240D01*
Y149960D01*
X1149328Y149400D01*
X1147888D01*
X1147328Y149960D01*
Y151240D01*
X1146768Y151800D01*
X1144076D01*
X1136000Y159876D01*
Y171534D01*
X1122056Y185478D01*
Y187055D01*
G01X1208267Y12114D02*
X1206363Y14018D01*
Y15614D01*
X1209713Y18964D01*
Y28699D01*
X1210263Y29249D01*
Y34637D01*
X1209663Y35237D01*
Y37000D01*
X1210400Y37737D01*
Y45300D01*
X1209663Y46037D01*
Y48064D01*
X1210174Y48575D01*
Y53453D01*
X1209713Y53914D01*
Y66598D01*
X1210174Y67059D01*
Y72627D01*
X1209592Y73209D01*
Y74592D01*
X1210200Y75200D01*
Y83492D01*
X1209592Y84100D01*
Y85492D01*
X1210067Y85967D01*
Y91281D01*
X1209800Y91548D01*
Y102600D01*
X1210300Y103100D01*
Y116855D01*
X1173155Y154000D01*
X1145000D01*
X1137988Y161012D01*
Y172548D01*
X1124556Y185980D01*
Y187055D01*
G01X1174803Y17157D02*
Y25103D01*
X1176763Y27063D01*
Y28537D01*
X1175863Y29437D01*
Y34299D01*
X1176863Y35299D01*
Y47885D01*
X1175974Y48774D01*
Y53238D01*
X1176874Y54138D01*
Y66226D01*
X1175774Y67326D01*
Y71959D01*
X1176674Y72859D01*
Y74826D01*
X1176300Y75200D01*
Y83526D01*
X1176674Y83900D01*
Y85874D01*
X1175874Y86674D01*
Y90974D01*
X1176774Y91874D01*
Y105374D01*
X1175974Y106174D01*
Y110838D01*
X1176700Y111564D01*
Y114354D01*
X1175354Y115700D01*
X1153741D01*
X1153181Y116260D01*
Y122800D01*
X1152381Y123600D01*
X1150781D01*
X1149981Y122800D01*
Y118800D01*
X1149181Y118000D01*
X1143903D01*
X1111374Y150529D01*
Y164649D01*
X1099000Y177023D01*
Y185848D01*
G01X1177849Y12114D02*
X1176999Y12964D01*
Y12968D01*
X1175863Y14104D01*
Y15514D01*
X1178000Y17651D01*
Y24800D01*
X1179463Y26263D01*
Y28599D01*
X1179713Y28849D01*
Y35049D01*
X1179363Y35399D01*
Y48027D01*
X1180074Y48738D01*
Y53274D01*
X1179374Y53974D01*
Y66959D01*
X1179974Y67559D01*
Y72175D01*
X1179408Y72741D01*
Y74708D01*
X1180100Y75400D01*
Y83408D01*
X1179408Y84100D01*
Y85772D01*
X1180174Y86538D01*
Y91274D01*
X1179474Y91974D01*
Y105438D01*
X1179792Y105756D01*
Y110956D01*
X1179492Y111256D01*
Y115098D01*
X1175290Y119300D01*
X1165254D01*
X1164154Y118200D01*
X1162554D01*
X1161754Y119000D01*
Y120200D01*
X1155754Y126200D01*
X1139239D01*
X1113389Y152050D01*
Y166274D01*
X1101200Y178463D01*
Y185669D01*
G01X1198228Y17157D02*
X1200263Y19192D01*
Y28499D01*
X1199663Y29099D01*
Y34763D01*
X1200463Y35563D01*
Y37037D01*
X1199700Y37800D01*
Y45637D01*
X1200463Y46400D01*
Y47914D01*
X1199663Y48714D01*
Y53526D01*
X1200063Y53926D01*
Y64448D01*
X1200374Y64759D01*
Y66259D01*
X1199674Y66959D01*
Y72575D01*
X1200274Y73175D01*
Y74350D01*
X1199000Y75624D01*
Y82940D01*
X1200274Y84214D01*
Y85374D01*
X1199474Y86174D01*
Y90938D01*
X1200274Y91738D01*
Y105574D01*
X1199574Y106274D01*
Y110774D01*
X1200028Y111228D01*
Y116347D01*
X1171275Y145100D01*
X1141100D01*
X1138616Y147584D01*
Y148376D01*
X1139474Y149234D01*
Y150026D01*
X1138455Y151045D01*
X1137663D01*
X1136805Y150187D01*
X1136013D01*
X1134994Y151206D01*
Y151998D01*
X1135852Y152856D01*
Y153648D01*
X1134833Y154667D01*
X1134041D01*
X1133183Y153809D01*
X1132391D01*
X1130288Y155912D01*
Y171439D01*
X1117056Y184671D01*
Y187055D01*
G01X1201574Y12114D02*
X1199763Y13925D01*
Y15562D01*
X1203121Y18920D01*
Y28757D01*
X1203500Y29136D01*
Y34900D01*
X1202963Y35437D01*
Y36963D01*
X1203500Y37500D01*
Y45663D01*
X1202963Y46200D01*
Y47914D01*
X1203763Y48714D01*
Y53286D01*
X1203063Y53986D01*
Y66648D01*
X1203630Y67215D01*
Y72371D01*
X1202900Y73101D01*
Y85364D01*
X1203674Y86138D01*
Y90974D01*
X1202974Y91674D01*
Y105438D01*
X1203540Y106004D01*
Y110808D01*
X1202892Y111456D01*
Y117191D01*
X1173083Y147000D01*
X1145100D01*
X1133000Y159100D01*
Y171836D01*
X1119556Y185280D01*
Y187055D01*
G01X1187963Y14300D02*
X1189689Y16026D01*
Y18100D01*
X1188889Y18900D01*
X1187889D01*
X1187169Y19620D01*
Y21436D01*
X1191043Y25310D01*
Y36580D01*
X1191663Y37200D01*
Y38200D01*
X1191043Y38820D01*
Y39580D01*
X1191663Y40200D01*
Y41200D01*
X1191043Y41820D01*
Y42580D01*
X1191663Y43200D01*
Y44200D01*
X1191043Y44820D01*
Y115828D01*
X1168191Y138680D01*
X1164629D01*
X1163508Y137559D01*
Y135280D01*
X1163008Y134780D01*
X1160140D01*
X1159268Y135652D01*
Y137191D01*
X1157779Y138680D01*
X1154397D01*
X1152908Y137191D01*
Y135649D01*
X1152039Y134780D01*
X1149038D01*
X1147912Y135906D01*
Y137424D01*
X1146656Y138680D01*
X1139037D01*
X1122033Y155686D01*
Y157866D01*
X1122483Y158316D01*
Y159316D01*
X1122033Y159766D01*
Y160766D01*
X1122483Y161216D01*
Y162216D01*
X1122033Y162666D01*
Y163666D01*
X1122483Y164116D01*
Y165116D01*
X1122033Y165566D01*
Y166566D01*
X1122483Y167016D01*
Y168016D01*
X1122033Y168466D01*
Y169596D01*
X1120881Y170748D01*
Y171384D01*
X1120173Y172092D01*
X1119537D01*
X1118830Y172799D01*
Y173435D01*
X1118122Y174143D01*
X1117486D01*
X1116779Y174850D01*
Y175486D01*
X1116071Y176194D01*
X1115435D01*
X1114728Y176901D01*
Y177537D01*
X1114020Y178245D01*
X1113384D01*
X1112677Y178952D01*
Y179588D01*
X1111969Y180296D01*
X1111333D01*
X1110626Y181003D01*
Y183900D01*
G01X1193063Y14514D02*
X1194889Y16340D01*
Y18412D01*
X1194301Y19000D01*
X1192870D01*
X1192369Y19501D01*
Y20598D01*
X1194094Y22323D01*
X1194970D01*
X1195677Y23030D01*
Y23906D01*
X1196280Y24509D01*
Y29380D01*
X1196800Y29900D01*
Y31100D01*
X1196280Y31620D01*
Y116391D01*
X1170191Y142480D01*
X1140637D01*
X1127727Y155390D01*
Y170470D01*
X1114427Y183770D01*
Y185913D01*
G01X1187963Y11700D02*
X1186109Y13554D01*
Y21879D01*
X1189983Y25753D01*
Y115388D01*
X1167751Y137620D01*
X1165069D01*
X1164568Y137119D01*
Y134840D01*
X1163448Y133720D01*
X1159697D01*
X1158208Y135209D01*
Y136748D01*
X1157336Y137620D01*
X1154840D01*
X1153968Y136748D01*
Y135209D01*
X1152479Y133720D01*
X1148598D01*
X1146852Y135466D01*
Y136984D01*
X1146216Y137620D01*
X1138597D01*
X1120973Y155246D01*
Y169156D01*
X1109566Y180563D01*
Y183900D01*
G01X1193063Y11914D02*
X1191309Y13668D01*
Y21038D01*
X1195220Y24949D01*
Y115948D01*
X1169748Y141420D01*
X1140197D01*
X1126667Y154950D01*
Y170030D01*
X1123955Y172742D01*
X1123319D01*
X1122611Y173450D01*
Y174086D01*
X1121852Y174845D01*
X1121216D01*
X1120508Y175553D01*
Y176189D01*
X1119520Y177177D01*
X1118883D01*
X1118175Y177885D01*
Y178522D01*
X1117074Y179623D01*
X1116437D01*
X1115729Y180331D01*
Y180968D01*
X1113367Y183330D01*
Y185913D01*
G01X1131200Y193300D02*
X1145600Y178900D01*
X1158500D01*
X1184788Y152612D01*
X1185580D01*
X1186088Y153120D01*
X1186880D01*
X1187899Y152101D01*
Y151309D01*
X1187391Y150801D01*
Y150009D01*
X1188410Y148990D01*
X1189202D01*
X1190110Y149898D01*
X1190902D01*
X1191921Y148879D01*
Y148087D01*
X1191013Y147179D01*
Y146387D01*
X1192032Y145368D01*
X1192824D01*
X1193732Y146276D01*
X1194524D01*
X1195543Y145257D01*
Y144465D01*
X1194635Y143557D01*
Y142765D01*
X1195654Y141746D01*
X1196446D01*
X1197354Y142654D01*
X1198146D01*
X1199165Y141635D01*
Y140843D01*
X1198257Y139935D01*
Y139143D01*
X1199276Y138124D01*
X1200068D01*
X1200976Y139032D01*
X1201768D01*
X1202787Y138013D01*
X1202788D01*
X1219392Y121409D01*
Y102207D01*
X1220107Y101492D01*
Y92107D01*
X1219100Y91100D01*
Y86348D01*
X1220200Y85248D01*
Y84099D01*
X1219400Y83299D01*
Y75500D01*
X1220200Y74700D01*
Y73299D01*
X1219024Y72123D01*
Y67394D01*
X1220200Y66218D01*
Y54273D01*
X1219248Y53321D01*
Y53012D01*
X1219024Y52788D01*
Y48914D01*
X1220200Y47738D01*
Y45834D01*
X1219100Y44734D01*
Y42434D01*
X1219800Y41734D01*
Y39900D01*
X1218900Y39000D01*
Y38200D01*
X1220200Y36900D01*
Y35359D01*
X1219024Y34183D01*
Y29594D01*
X1220200Y28418D01*
Y26799D01*
X1218307Y24906D01*
Y17157D01*
G01X1133100Y194200D02*
X1144400Y182900D01*
X1157099D01*
X1182399Y157600D01*
X1186233D01*
X1221892Y121941D01*
Y103108D01*
X1222874Y102126D01*
Y84027D01*
X1223800Y83101D01*
Y75626D01*
X1222874Y74700D01*
Y46026D01*
X1223600Y45300D01*
Y37926D01*
X1222874Y37200D01*
Y25673D01*
X1220374Y23173D01*
Y16674D01*
X1218880Y15180D01*
Y14187D01*
X1220953Y12114D01*
G01X1143300Y204500D02*
X1149900Y197900D01*
X1161600D01*
X1183374Y176126D01*
X1187374D01*
X1243100Y120400D01*
Y111125D01*
X1243660Y110565D01*
X1245040D01*
X1245600Y110005D01*
Y108565D01*
X1245040Y108005D01*
X1243660D01*
X1243100Y107445D01*
Y106005D01*
X1243660Y105445D01*
X1245040D01*
X1245600Y104885D01*
Y103445D01*
X1245040Y102885D01*
X1243660D01*
X1243100Y102325D01*
Y100885D01*
X1243660Y100325D01*
X1245040D01*
X1245600Y99765D01*
Y98325D01*
X1245040Y97765D01*
X1243660D01*
X1243100Y97205D01*
Y95548D01*
X1244074Y94574D01*
Y92238D01*
X1243074Y91238D01*
Y86414D01*
X1243674Y85814D01*
Y84100D01*
X1243200Y83626D01*
Y75100D01*
X1243674Y74626D01*
Y73175D01*
X1243174Y72675D01*
Y67075D01*
X1244024Y66225D01*
Y54264D01*
X1243074Y53314D01*
Y48374D01*
X1243674Y47774D01*
Y46174D01*
X1243200Y45700D01*
Y37574D01*
X1243674Y37100D01*
Y35175D01*
X1243174Y34675D01*
Y28999D01*
X1243974Y28199D01*
Y19399D01*
X1241732Y17157D01*
G01X1145000Y205500D02*
X1150200Y200300D01*
X1162400D01*
X1184200Y178500D01*
X1188500D01*
X1248400Y118600D01*
Y95500D01*
X1246574Y93674D01*
Y91874D01*
X1247174Y91274D01*
Y86614D01*
X1246474Y85914D01*
Y84100D01*
X1247000Y83574D01*
Y75400D01*
X1246474Y74874D01*
Y73127D01*
X1247074Y72527D01*
Y67049D01*
X1246524Y66499D01*
Y53864D01*
X1247174Y53214D01*
Y48638D01*
X1246474Y47938D01*
Y46226D01*
X1247300Y45400D01*
Y37726D01*
X1246474Y36900D01*
Y35227D01*
X1247074Y34627D01*
Y29249D01*
X1246524Y28699D01*
Y18964D01*
X1243174Y15614D01*
Y14018D01*
X1245078Y12114D01*
G01X1211614Y17157D02*
X1213700Y19243D01*
Y20514D01*
X1212800Y21414D01*
Y22500D01*
X1213584Y23284D01*
Y24416D01*
X1212866Y25134D01*
Y26266D01*
X1213600Y27000D01*
Y28401D01*
X1212674Y29327D01*
Y34299D01*
X1213800Y35425D01*
Y37300D01*
X1213100Y38000D01*
Y45500D01*
X1213800Y46200D01*
Y48000D01*
X1212810Y48990D01*
Y53550D01*
X1213900Y54640D01*
Y66001D01*
X1212674Y67227D01*
Y72239D01*
X1213800Y73365D01*
Y74400D01*
X1213000Y75200D01*
Y83500D01*
X1213800Y84300D01*
Y85648D01*
X1213074Y86374D01*
Y91138D01*
X1213800Y91864D01*
Y103300D01*
X1214392Y103892D01*
Y117209D01*
X1174301Y157300D01*
X1166769D01*
X1166209Y157860D01*
Y163740D01*
X1165649Y164300D01*
X1164209D01*
X1163649Y163740D01*
Y160060D01*
X1163089Y159500D01*
X1161260D01*
X1160700Y160060D01*
Y167201D01*
X1153801Y174100D01*
X1144300D01*
X1129400Y189000D01*
Y189500D01*
G01X1214660Y12114D02*
X1212792Y13982D01*
Y15632D01*
X1216200Y19040D01*
Y28525D01*
X1216524Y28849D01*
Y35049D01*
X1216357Y35216D01*
Y37357D01*
X1216924Y37924D01*
Y45477D01*
X1216357Y46044D01*
Y48497D01*
X1216692Y48832D01*
Y53446D01*
X1216500Y53638D01*
Y67365D01*
X1216692Y67557D01*
Y72357D01*
X1216300Y72749D01*
Y75000D01*
X1216900Y75600D01*
Y83300D01*
X1216300Y83900D01*
Y86000D01*
X1216700Y86400D01*
Y90648D01*
X1216392Y90956D01*
Y102092D01*
X1216892Y102592D01*
Y117309D01*
X1215209Y118992D01*
X1215208Y119784D01*
X1216365Y120941D01*
Y121733D01*
X1215345Y122753D01*
X1214555Y122752D01*
X1213398Y121595D01*
X1212606D01*
X1211587Y122614D01*
X1211586Y123406D01*
X1212743Y124563D01*
Y125355D01*
X1211723Y126375D01*
X1211400D01*
X1210933Y126374D01*
X1209776Y125217D01*
X1208984D01*
X1207965Y126236D01*
X1207963Y127737D01*
X1206861Y128839D01*
X1205362D01*
X1158101Y176100D01*
X1145400D01*
X1130750Y190750D01*
G01X1141450Y200450D02*
X1148700Y193200D01*
X1159900D01*
X1185138Y167962D01*
X1189238D01*
X1235574Y121626D01*
Y118577D01*
X1236134Y118017D01*
X1238040D01*
X1238600Y117457D01*
Y116017D01*
X1238040Y115457D01*
X1236134D01*
X1235574Y114897D01*
Y113457D01*
X1236134Y112897D01*
X1238040D01*
X1238600Y112337D01*
Y110897D01*
X1238040Y110337D01*
X1236134D01*
X1235574Y109777D01*
Y108337D01*
X1236134Y107777D01*
X1238040D01*
X1238600Y107217D01*
Y105777D01*
X1238040Y105217D01*
X1236134D01*
X1235574Y104657D01*
Y102127D01*
X1236874Y100827D01*
Y91614D01*
X1236474Y91214D01*
Y86514D01*
X1237274Y85714D01*
Y84100D01*
X1236700Y83526D01*
Y75500D01*
X1237274Y74926D01*
Y73375D01*
X1236474Y72575D01*
Y66975D01*
X1236874Y66575D01*
Y53814D01*
X1236474Y53414D01*
Y48714D01*
X1237274Y47914D01*
Y46400D01*
X1236500Y45626D01*
Y37600D01*
X1237274Y36826D01*
Y35401D01*
X1236474Y34601D01*
Y29099D01*
X1237074Y28499D01*
Y19192D01*
X1235039Y17157D01*
G01X1142200Y202800D02*
X1149400Y195600D01*
X1160899D01*
X1184900Y171599D01*
X1188700D01*
X1240600Y119699D01*
Y94393D01*
X1239881Y93674D01*
Y91874D01*
X1240481Y91274D01*
Y86614D01*
X1239781Y85914D01*
Y84100D01*
X1240307Y83574D01*
Y75400D01*
X1239781Y74874D01*
Y73127D01*
X1240381Y72527D01*
Y67049D01*
X1239831Y66499D01*
Y53864D01*
X1240481Y53214D01*
Y48638D01*
X1239781Y47938D01*
Y46226D01*
X1240607Y45400D01*
Y37726D01*
X1239781Y36900D01*
Y35227D01*
X1240381Y34627D01*
Y29249D01*
X1239831Y28699D01*
Y18964D01*
X1236481Y15614D01*
Y14018D01*
X1238385Y12114D01*
G01X1136150Y195950D02*
X1136997Y195103D01*
X1137634D01*
X1138342Y194395D01*
Y193758D01*
X1139049Y193051D01*
X1139756D01*
X1140464Y192344D01*
Y191636D01*
X1141171Y190929D01*
X1141878D01*
X1142586Y190222D01*
Y189514D01*
X1143293Y188807D01*
X1144000D01*
X1144708Y188100D01*
Y187392D01*
X1146040Y186060D01*
X1147040D01*
X1147540Y186560D01*
X1148540D01*
X1149040Y186060D01*
X1150100D01*
X1150600Y186560D01*
X1151600D01*
X1152100Y186060D01*
X1153600D01*
X1154100Y186560D01*
X1155100D01*
X1155600Y186060D01*
X1158840D01*
X1159742Y185158D01*
X1160450D01*
X1161158Y184450D01*
Y183742D01*
X1161992Y182908D01*
X1162700D01*
X1163408Y182200D01*
Y181492D01*
X1164115Y180785D01*
Y180783D01*
X1182800Y162100D01*
X1187000D01*
X1225580Y123520D01*
Y117202D01*
X1226449Y116333D01*
X1228068D01*
X1229560Y114841D01*
Y111465D01*
X1228068Y109973D01*
X1226349D01*
X1225480Y109104D01*
Y106605D01*
X1226352Y105733D01*
X1227488D01*
X1229080Y104141D01*
Y102285D01*
X1226969Y100174D01*
Y98427D01*
X1228970Y96426D01*
Y94841D01*
X1227854Y93725D01*
Y48213D01*
X1228304Y47763D01*
Y46763D01*
X1227854Y46313D01*
Y44418D01*
X1228304Y43968D01*
Y42968D01*
X1227854Y42518D01*
Y41126D01*
X1228304Y40676D01*
Y39676D01*
X1227854Y39226D01*
Y24562D01*
X1223980Y20688D01*
Y19620D01*
X1224700Y18900D01*
X1225700D01*
X1226500Y18100D01*
Y16026D01*
X1224774Y14300D01*
G01X1137400Y200400D02*
X1146595Y191205D01*
X1158695D01*
X1184340Y165560D01*
X1187940D01*
X1232954Y120546D01*
Y26134D01*
X1233574Y25514D01*
Y24682D01*
X1232238Y23346D01*
Y22470D01*
X1231530Y21762D01*
X1230654D01*
X1229680Y20788D01*
Y19920D01*
X1231700Y17900D01*
Y16340D01*
X1229874Y14514D01*
G01X1135400Y195200D02*
X1145600Y185000D01*
X1158400D01*
X1163365Y180035D01*
Y180033D01*
X1182360Y161040D01*
X1186560D01*
X1224520Y123080D01*
Y116762D01*
X1226009Y115273D01*
X1227628D01*
X1228500Y114401D01*
Y111905D01*
X1227628Y111033D01*
X1225909D01*
X1224420Y109544D01*
Y106162D01*
X1225909Y104673D01*
X1227048D01*
X1228020Y103701D01*
Y102725D01*
X1225909Y100614D01*
Y97987D01*
X1227910Y95986D01*
Y95281D01*
X1226794Y94165D01*
Y25005D01*
X1222920Y21131D01*
Y13554D01*
X1224774Y11700D01*
G01X1136650Y199650D02*
X1146155Y190145D01*
X1147818D01*
X1148268Y189695D01*
X1149268D01*
X1149718Y190145D01*
X1151555D01*
X1152005Y189695D01*
X1153005D01*
X1153455Y190145D01*
X1158255D01*
X1183900Y164500D01*
X1187500D01*
X1231894Y120106D01*
Y24505D01*
X1228620Y21231D01*
Y18719D01*
X1228150Y18249D01*
Y13638D01*
X1229874Y11914D01*
G01X1123687Y419941D02*
Y440287D01*
X1144673Y461273D01*
X1175784D01*
X1198720Y484209D01*
X1201151D01*
X1206874Y489932D01*
Y491452D01*
X1206500Y491826D01*
Y497478D01*
X1206863Y497841D01*
Y500337D01*
X1206100Y501100D01*
Y508637D01*
X1206863Y509400D01*
Y511157D01*
X1206363Y511657D01*
Y516563D01*
X1207500Y517700D01*
Y519013D01*
X1206600Y519913D01*
Y527800D01*
X1207148Y528348D01*
Y529481D01*
X1206263Y530366D01*
Y535662D01*
X1207100Y536499D01*
Y537663D01*
X1206600Y538163D01*
Y546700D01*
X1206863Y546963D01*
Y548957D01*
X1206363Y549457D01*
Y554857D01*
X1207163Y555657D01*
Y556900D01*
X1206596Y557467D01*
Y565496D01*
X1207163Y566063D01*
Y567297D01*
X1206063Y568397D01*
Y573142D01*
X1206963Y574042D01*
Y586507D01*
X1203563Y589907D01*
Y592399D01*
X1204921Y593757D01*
G01X1126187Y419941D02*
Y439187D01*
X1146094Y459094D01*
X1179752D01*
X1189968Y469310D01*
Y470172D01*
X1189112Y471028D01*
Y471890D01*
X1190096Y472874D01*
X1190958D01*
X1191814Y472018D01*
X1192676D01*
X1193660Y473002D01*
Y473864D01*
X1192804Y474720D01*
Y475582D01*
X1193788Y476566D01*
X1194650D01*
X1195506Y475710D01*
X1196368D01*
X1197352Y476694D01*
Y477556D01*
X1196496Y478412D01*
Y479274D01*
X1197480Y480258D01*
X1198342D01*
X1199198Y479402D01*
X1200060D01*
X1210300Y489642D01*
Y497200D01*
X1209900Y497600D01*
Y509000D01*
X1209663Y509237D01*
Y511657D01*
X1210263Y512257D01*
Y516807D01*
X1209713Y517357D01*
Y519300D01*
X1210000Y519587D01*
Y527600D01*
X1209713Y527887D01*
Y529816D01*
X1210363Y530466D01*
Y535538D01*
X1209663Y536238D01*
Y537600D01*
X1209900Y537837D01*
Y546400D01*
X1209663Y546637D01*
Y549457D01*
X1210263Y550057D01*
Y554607D01*
X1209713Y555157D01*
Y557000D01*
X1210000Y557287D01*
Y565400D01*
X1209713Y565687D01*
Y567647D01*
X1210563Y568497D01*
Y573038D01*
X1209563Y574038D01*
Y587470D01*
X1208267Y588766D01*
Y588714D01*
G01X1121187Y421025D02*
Y441587D01*
X1143360Y463760D01*
X1145360D01*
X1145970Y464370D01*
Y466139D01*
X1146580Y466749D01*
X1147970D01*
X1148580Y466139D01*
Y464370D01*
X1149190Y463760D01*
X1150580D01*
X1151190Y464370D01*
Y466139D01*
X1151800Y466749D01*
X1153190D01*
X1153800Y466139D01*
Y464370D01*
X1154410Y463760D01*
X1155800D01*
X1156410Y464370D01*
Y465748D01*
X1157048Y466386D01*
X1158438D01*
X1159020Y465804D01*
Y464370D01*
X1159630Y463760D01*
X1175590D01*
X1198162Y486332D01*
X1199558D01*
X1202700Y489474D01*
Y499900D01*
X1203529Y500729D01*
Y508934D01*
X1202963Y509500D01*
Y511257D01*
X1203863Y512157D01*
Y516557D01*
X1203063Y517357D01*
Y519400D01*
X1203300Y519637D01*
Y527600D01*
X1203063Y527837D01*
Y529842D01*
X1203763Y530542D01*
Y535738D01*
X1202963Y536538D01*
Y537700D01*
X1203300Y538037D01*
Y546600D01*
X1202963Y546937D01*
Y549057D01*
X1203863Y549957D01*
Y554357D01*
X1202763Y555457D01*
Y557100D01*
X1203300Y557637D01*
Y565700D01*
X1203063Y565937D01*
Y567597D01*
X1203629Y568163D01*
Y573471D01*
X1202963Y574137D01*
Y587368D01*
X1202920D01*
X1201574Y588714D01*
G01X1135756Y412641D02*
Y415380D01*
X1148276Y427900D01*
X1155206D01*
X1162123Y434817D01*
Y444930D01*
X1167096Y449903D01*
X1183691D01*
X1220147Y486359D01*
Y510934D01*
X1219024Y512057D01*
Y516307D01*
X1220035Y517318D01*
Y529606D01*
X1219141Y530500D01*
Y535341D01*
X1220091Y536291D01*
Y548790D01*
X1219024Y549857D01*
Y554107D01*
X1220063Y555146D01*
Y567378D01*
X1219197Y568244D01*
Y573196D01*
X1220091Y574090D01*
Y586590D01*
X1216874Y589807D01*
Y592324D01*
X1218307Y593757D01*
G01X1138256Y414333D02*
X1149938Y426015D01*
X1156915D01*
X1164469Y433569D01*
Y443845D01*
X1165079Y444455D01*
X1166469D01*
X1167079Y443845D01*
Y438919D01*
X1167689Y438309D01*
X1169079D01*
X1169689Y438919D01*
Y446406D01*
X1171118Y447835D01*
X1185419D01*
X1222874Y485290D01*
Y500474D01*
X1223400Y501000D01*
Y508800D01*
X1222874Y509326D01*
Y519100D01*
X1223300Y519526D01*
Y528100D01*
X1222874Y528526D01*
Y537700D01*
X1223400Y538226D01*
Y546200D01*
X1222874Y546726D01*
Y556574D01*
X1223300Y557000D01*
Y565600D01*
X1222874Y566026D01*
Y575500D01*
X1223300Y575926D01*
Y584000D01*
X1222874Y584426D01*
Y586443D01*
X1220953Y588364D01*
Y588714D01*
G01X1152559Y406743D02*
X1152716Y406900D01*
X1156940D01*
X1180722Y430682D01*
X1187822D01*
X1240574Y483434D01*
Y491074D01*
X1243674Y494174D01*
Y511157D01*
X1242900Y511931D01*
Y516399D01*
X1244063Y517562D01*
Y529377D01*
X1242750Y530690D01*
Y535184D01*
X1243895Y536329D01*
Y548736D01*
X1242861Y549770D01*
Y554544D01*
X1243809Y555492D01*
Y567462D01*
X1242748Y568523D01*
Y573016D01*
X1243642Y573910D01*
Y586639D01*
X1241296Y588985D01*
Y593321D01*
X1241732Y593757D01*
G01X1154399Y404903D02*
X1158085D01*
X1165258Y412076D01*
X1166120D01*
X1166958Y411238D01*
X1167820D01*
X1168804Y412222D01*
Y413084D01*
X1167966Y413922D01*
Y414784D01*
X1168950Y415768D01*
X1169812D01*
X1170650Y414930D01*
X1171612D01*
X1172496Y415814D01*
Y416776D01*
X1171658Y417614D01*
Y418476D01*
X1181629Y428447D01*
X1188494D01*
X1245821Y485774D01*
Y487300D01*
X1245421Y487700D01*
X1243200D01*
X1242700Y488200D01*
Y489800D01*
X1243500Y490600D01*
X1245320D01*
X1245821Y491101D01*
Y508673D01*
X1246474Y509326D01*
Y511373D01*
X1247074Y511973D01*
Y516807D01*
X1246524Y517357D01*
Y529816D01*
X1247174Y530466D01*
Y535526D01*
X1246474Y536226D01*
Y549457D01*
X1247074Y550057D01*
Y554607D01*
X1246524Y555157D01*
Y567647D01*
X1247374Y568497D01*
Y573226D01*
X1246374Y574226D01*
Y587470D01*
X1245078Y588766D01*
Y588714D01*
G01X1130756Y414587D02*
X1130800Y414631D01*
Y439000D01*
X1146400Y454600D01*
X1180955D01*
X1213414Y487059D01*
Y511057D01*
X1213023Y511448D01*
Y516806D01*
X1213414Y517197D01*
Y529586D01*
X1212827Y530173D01*
Y535395D01*
X1213330Y535898D01*
Y548901D01*
X1212995Y549236D01*
Y554578D01*
X1213574Y555157D01*
Y567325D01*
X1212526Y568373D01*
Y572944D01*
X1213524Y573942D01*
Y586457D01*
X1210374Y589607D01*
Y592517D01*
X1211614Y593757D01*
G01X1133600Y414931D02*
Y429143D01*
X1134210Y429753D01*
X1135699D01*
X1136309Y430363D01*
Y431753D01*
X1135699Y432363D01*
X1134210D01*
X1133600Y432973D01*
Y438500D01*
X1147300Y452200D01*
X1182020D01*
X1216813Y486993D01*
Y508513D01*
X1216274Y509052D01*
Y511497D01*
X1216600Y511823D01*
Y517131D01*
X1216274Y517457D01*
Y519200D01*
X1216700Y519626D01*
Y527500D01*
X1216274Y527926D01*
Y529992D01*
X1216524Y530242D01*
Y535192D01*
X1216174Y535542D01*
Y537500D01*
X1216700Y538026D01*
Y546100D01*
X1216174Y546626D01*
Y548457D01*
X1216700Y548983D01*
Y554831D01*
X1216274Y555257D01*
Y557000D01*
X1216600Y557326D01*
Y565600D01*
X1216274Y565926D01*
Y567997D01*
X1216774Y568497D01*
Y572656D01*
X1216174Y573256D01*
Y575200D01*
X1216600Y575626D01*
Y583700D01*
X1216174Y584126D01*
Y587200D01*
X1214660Y588714D01*
G01X1148959Y410343D02*
X1149816Y411200D01*
X1154988D01*
X1178884Y435096D01*
X1186036D01*
X1235541Y484601D01*
Y507941D01*
X1237274Y509674D01*
Y511257D01*
X1236474Y512057D01*
Y516957D01*
X1236874Y517357D01*
Y519600D01*
X1236700Y519774D01*
Y527700D01*
X1236874Y527874D01*
Y529842D01*
X1236474Y530242D01*
Y535674D01*
X1237274Y536474D01*
Y538026D01*
X1236700Y538600D01*
Y546300D01*
X1237274Y546874D01*
Y549057D01*
X1236200Y550131D01*
Y554099D01*
X1237421Y555320D01*
Y556453D01*
X1236700Y557174D01*
Y565600D01*
X1237219Y566119D01*
Y567252D01*
X1236001Y568470D01*
Y573201D01*
X1237274Y574474D01*
Y575400D01*
X1236700Y575974D01*
Y583900D01*
X1237649Y584849D01*
Y585982D01*
X1234374Y589257D01*
Y593092D01*
X1235039Y593757D01*
G01X1150734Y408568D02*
X1150934Y408768D01*
X1155682D01*
X1179720Y432806D01*
X1186930D01*
X1238074Y483950D01*
Y492201D01*
X1240766Y494893D01*
Y496184D01*
X1240156Y496794D01*
X1238133D01*
X1237523Y497404D01*
Y499384D01*
X1238133Y499994D01*
X1240743D01*
X1241353Y500604D01*
Y502584D01*
X1240743Y503194D01*
X1238160D01*
X1237606Y503748D01*
Y505728D01*
X1238272Y506394D01*
X1240156D01*
X1240766Y507004D01*
Y508208D01*
X1239774Y509200D01*
Y511257D01*
X1240674Y512157D01*
Y516557D01*
X1239874Y517357D01*
Y519300D01*
X1240100Y519526D01*
Y527700D01*
X1239874Y527926D01*
Y529842D01*
X1240574Y530542D01*
Y535323D01*
X1239461Y536436D01*
Y538361D01*
X1240100Y539000D01*
Y546300D01*
X1239400Y547000D01*
Y548683D01*
X1240674Y549957D01*
Y553925D01*
X1239400Y555199D01*
Y557226D01*
X1240100Y557926D01*
Y565400D01*
X1239874Y565626D01*
Y567597D01*
X1240440Y568163D01*
Y573461D01*
X1239774Y574127D01*
Y575500D01*
X1240100Y575826D01*
Y584000D01*
X1239774Y584326D01*
Y587368D01*
X1239731D01*
X1238385Y588714D01*
G01X1112298Y422000D02*
Y445398D01*
X1141668Y474768D01*
X1176391D01*
X1191043Y489420D01*
Y587429D01*
X1189600Y588872D01*
Y589263D01*
X1187963Y590900D01*
G01X1141956Y411515D02*
Y412556D01*
X1152470Y423070D01*
X1158804D01*
X1173127Y437393D01*
Y443670D01*
X1174277Y444820D01*
X1187548D01*
X1227854Y485126D01*
Y587820D01*
X1224774Y590900D01*
G01X1115001Y422000D02*
Y445125D01*
X1142658Y472782D01*
X1160055D01*
X1162932Y469905D01*
X1164720D01*
X1167067Y472252D01*
X1169799D01*
X1171029Y471022D01*
Y469508D01*
X1171639Y468898D01*
X1173029D01*
X1173639Y469508D01*
Y471022D01*
X1174869Y472252D01*
X1176958D01*
X1195083Y490377D01*
Y507226D01*
X1194658Y507651D01*
Y508651D01*
X1195083Y509076D01*
Y519324D01*
X1194463Y519944D01*
Y520944D01*
X1195083Y521564D01*
Y522564D01*
X1194463Y523184D01*
Y524184D01*
X1195083Y524804D01*
Y525804D01*
X1194463Y526424D01*
Y527424D01*
X1195083Y528044D01*
Y538014D01*
X1194463Y538634D01*
Y539634D01*
X1195083Y540254D01*
Y541254D01*
X1194463Y541874D01*
Y542874D01*
X1195083Y543494D01*
Y544494D01*
X1194463Y545114D01*
Y546114D01*
X1195083Y546734D01*
Y556955D01*
X1194463Y557575D01*
Y558575D01*
X1195083Y559195D01*
Y560195D01*
X1194463Y560815D01*
Y561815D01*
X1195083Y562435D01*
Y563435D01*
X1194463Y564055D01*
Y565055D01*
X1195083Y565675D01*
Y575841D01*
X1194463Y576461D01*
Y577461D01*
X1195083Y578081D01*
Y579081D01*
X1194463Y579701D01*
Y580701D01*
X1195083Y581321D01*
Y582321D01*
X1194463Y582941D01*
Y583941D01*
X1195083Y584561D01*
Y587386D01*
X1193955Y588514D01*
X1193063D01*
G01X1144586Y410383D02*
Y411686D01*
X1149020Y416120D01*
X1150996D01*
X1151799Y415317D01*
X1153178D01*
X1154160Y416299D01*
Y419801D01*
X1155459Y421100D01*
X1160252D01*
X1175779Y436627D01*
Y441604D01*
X1176981Y442806D01*
X1179251D01*
X1180509Y441548D01*
Y439424D01*
X1181207Y438726D01*
X1185205D01*
X1231894Y485415D01*
Y506891D01*
X1231274Y507511D01*
Y508511D01*
X1231894Y509131D01*
Y518933D01*
X1231274Y519553D01*
Y520553D01*
X1231894Y521173D01*
Y522173D01*
X1231274Y522793D01*
Y523793D01*
X1231894Y524413D01*
Y525413D01*
X1231274Y526033D01*
Y527033D01*
X1231894Y527653D01*
Y538405D01*
X1231274Y539025D01*
Y540025D01*
X1231894Y540645D01*
Y541645D01*
X1231274Y542265D01*
Y543265D01*
X1231894Y543885D01*
Y544885D01*
X1231274Y545505D01*
Y546505D01*
X1231894Y547125D01*
Y557095D01*
X1231274Y557715D01*
Y558715D01*
X1231894Y559335D01*
Y560335D01*
X1231274Y560955D01*
Y561955D01*
X1231894Y562575D01*
Y563575D01*
X1231274Y564195D01*
Y565195D01*
X1231894Y565815D01*
Y576259D01*
X1231274Y576879D01*
Y577879D01*
X1231894Y578499D01*
Y579499D01*
X1231274Y580119D01*
Y581119D01*
X1231894Y581739D01*
Y582739D01*
X1231274Y583359D01*
Y584359D01*
X1231894Y584979D01*
Y587593D01*
X1230973Y588514D01*
X1229874D01*
G01X1140896Y411515D02*
Y412996D01*
X1152030Y424130D01*
X1158364D01*
X1172067Y437833D01*
Y444110D01*
X1173837Y445880D01*
X1187108D01*
X1226794Y485566D01*
Y576325D01*
X1226412Y576707D01*
Y577707D01*
X1226794Y578089D01*
Y579285D01*
X1226174Y579905D01*
Y580905D01*
X1226794Y581525D01*
Y582637D01*
X1226286Y583145D01*
Y584145D01*
X1226794Y584653D01*
Y587380D01*
X1225874Y588300D01*
X1224774D01*
G01X1116061Y422000D02*
Y444685D01*
X1143098Y471722D01*
X1159615D01*
X1162492Y468845D01*
X1165160D01*
X1167507Y471192D01*
X1169359D01*
X1169969Y470582D01*
Y469068D01*
X1171199Y467838D01*
X1173469D01*
X1174699Y469068D01*
Y470582D01*
X1175309Y471192D01*
X1177398D01*
X1196143Y489937D01*
Y587829D01*
X1194600Y589372D01*
Y589577D01*
X1193063Y591114D01*
G01X1118687Y421025D02*
Y442487D01*
X1144933Y468733D01*
X1159327D01*
X1162122Y465938D01*
X1174833D01*
X1197182Y488287D01*
X1198100D01*
X1198600Y488787D01*
Y493900D01*
X1199800Y495100D01*
Y497378D01*
X1200061Y497639D01*
Y511659D01*
X1199663Y512057D01*
Y516957D01*
X1200063Y517357D01*
Y529842D01*
X1199663Y530242D01*
Y535762D01*
X1200117Y536216D01*
Y548983D01*
X1199698Y549402D01*
Y554398D01*
X1200263Y554963D01*
Y567397D01*
X1199614Y568046D01*
Y573393D01*
X1200116Y573895D01*
Y586704D01*
X1197909Y588911D01*
Y593438D01*
X1198228Y593757D01*
G01X1145646Y410383D02*
Y411246D01*
X1149460Y415060D01*
X1150556D01*
X1151359Y414257D01*
X1153618D01*
X1155220Y415859D01*
Y419361D01*
X1155899Y420040D01*
X1160692D01*
X1176839Y436187D01*
Y441164D01*
X1177421Y441746D01*
X1178811D01*
X1179449Y441108D01*
Y438984D01*
X1180767Y437666D01*
X1185645D01*
X1232954Y484975D01*
Y588034D01*
X1229874Y591114D01*
G01X1144385Y498487D02*
Y504999D01*
X1146752Y507366D01*
Y510707D01*
X1145402Y512057D01*
Y516307D01*
X1146552Y517457D01*
Y519400D01*
X1146400Y519552D01*
Y527900D01*
X1146552Y528052D01*
Y529447D01*
X1145452Y530547D01*
Y535353D01*
X1146602Y536503D01*
Y537600D01*
X1146400Y537802D01*
Y546300D01*
X1146602Y546502D01*
Y548657D01*
X1143252Y552007D01*
Y554524D01*
X1144685Y555957D01*
G01X1147331Y550914D02*
Y550564D01*
X1149252Y548643D01*
Y546548D01*
X1149700Y546100D01*
Y538148D01*
X1149252Y537700D01*
Y528348D01*
X1149700Y527900D01*
Y519048D01*
X1149252Y518600D01*
Y506330D01*
X1146674Y503752D01*
Y495274D01*
X1145374Y493974D01*
Y492851D01*
X1147331Y490894D01*
G01X1137988Y551100D02*
X1139902Y549186D01*
Y546602D01*
X1139700Y546400D01*
Y538002D01*
X1139902Y537800D01*
Y536142D01*
X1138904Y535144D01*
Y530497D01*
X1139952Y529449D01*
Y528252D01*
X1139700Y528000D01*
Y519852D01*
X1139952Y519600D01*
Y517357D01*
X1139052Y516457D01*
Y511757D01*
X1140052Y510757D01*
Y509051D01*
X1139700Y508699D01*
Y500195D01*
X1137992Y498487D01*
G01X1141038Y550914D02*
X1142552Y549400D01*
Y546548D01*
X1143000Y546100D01*
Y538048D01*
X1142552Y537600D01*
Y535456D01*
X1143152Y534856D01*
Y530697D01*
X1142652Y530197D01*
Y528148D01*
X1143000Y527800D01*
Y519448D01*
X1142652Y519100D01*
Y517457D01*
X1142902Y517207D01*
Y511007D01*
X1142552Y510657D01*
Y499630D01*
X1141985Y499063D01*
Y495215D01*
X1142874Y494326D01*
Y492980D01*
X1141038Y491144D01*
G01X1151152Y553100D02*
X1151296D01*
X1152900Y551496D01*
Y550446D01*
X1154232Y549114D01*
Y504632D01*
X1152500Y502900D01*
Y500400D01*
X1152900Y500000D01*
Y497944D01*
X1151168Y496212D01*
Y496167D01*
G01X1156252Y550714D02*
X1156986D01*
X1158272Y549428D01*
Y505073D01*
X1156040Y502841D01*
Y501040D01*
X1154500Y499500D01*
Y495319D01*
X1156252Y493567D01*
G01X1151152Y550500D02*
X1151346D01*
X1153172Y548674D01*
Y505072D01*
X1151440Y503340D01*
Y501940D01*
X1149444Y499944D01*
Y495191D01*
X1151168Y493467D01*
G01X1156252Y553314D02*
X1158000Y551566D01*
Y551200D01*
X1159332Y549868D01*
Y504633D01*
X1157100Y502401D01*
Y500400D01*
X1158000Y499500D01*
Y497915D01*
X1156252Y496167D01*
G01X1107874Y593757D02*
X1106169Y595462D01*
Y607115D01*
X1109354Y610300D01*
X1110520D01*
G01Y588714D02*
X1110432D01*
X1108746Y590400D01*
Y592092D01*
X1109653Y592999D01*
Y594592D01*
X1108509Y595736D01*
Y597156D01*
X1109353Y598000D01*
Y599700D01*
X1108509Y600544D01*
Y601756D01*
X1109453Y602700D01*
Y603900D01*
X1108854Y604499D01*
X1107874D01*
G01X1131299Y593757D02*
X1129594Y595462D01*
Y605649D01*
X1134645Y610700D01*
G01Y588714D02*
X1134557D01*
X1132871Y590400D01*
Y592092D01*
X1133046Y592267D01*
Y594900D01*
X1131934Y596012D01*
Y597088D01*
X1132946Y598100D01*
Y599300D01*
X1131934Y600312D01*
Y601388D01*
X1133071Y602525D01*
Y603799D01*
X1132371Y604499D01*
X1131299D01*
G01X1101181Y593757D02*
X1099476Y595462D01*
Y605435D01*
X1100098Y606057D01*
Y607245D01*
X1103153Y610300D01*
X1104141D01*
G01X1104227Y588714D02*
X1104139D01*
X1102453Y590400D01*
Y592600D01*
X1102953Y593100D01*
Y594999D01*
X1101816Y596136D01*
Y597464D01*
X1102753Y598401D01*
Y599799D01*
X1101816Y600736D01*
Y601964D01*
X1102853Y603001D01*
Y603899D01*
X1102253Y604499D01*
X1101181D01*
G01X1124606Y593757D02*
X1122901Y595462D01*
Y605649D01*
X1127952Y610700D01*
G01Y588714D02*
X1127864D01*
X1126178Y590400D01*
Y592092D01*
X1126353Y592267D01*
Y594900D01*
X1125241Y596012D01*
Y597088D01*
X1126253Y598100D01*
Y599300D01*
X1125426Y600126D01*
X1125241Y600312D01*
Y601388D01*
X1126378Y602525D01*
Y603799D01*
X1125678Y604499D01*
X1124606D01*
G01X1147700Y611200D02*
X1142980Y606480D01*
Y595462D01*
X1144685Y593757D01*
G01Y604499D02*
X1145665D01*
X1146264Y603900D01*
Y602700D01*
X1145320Y601756D01*
Y600544D01*
X1146164Y599700D01*
Y598000D01*
X1145320Y597156D01*
Y595736D01*
X1146464Y594592D01*
Y592999D01*
X1145557Y592092D01*
Y590400D01*
X1147243Y588714D01*
X1147331D01*
G01X1141332Y611668D02*
X1136909Y607245D01*
Y606057D01*
X1136287Y605435D01*
Y595462D01*
X1137992Y593757D01*
G01Y604499D02*
X1139064D01*
X1139664Y603899D01*
Y603001D01*
X1138627Y601964D01*
Y600736D01*
X1139564Y599799D01*
Y598401D01*
X1138627Y597464D01*
Y596136D01*
X1139764Y594999D01*
Y593100D01*
X1139264Y592600D01*
Y590400D01*
X1140950Y588714D01*
X1141038D01*
G01X1114366Y607350D02*
X1116072Y605644D01*
Y603739D01*
X1115333Y603000D01*
X1114053D01*
X1113413Y602360D01*
Y600940D01*
X1113963Y600390D01*
X1114543D01*
X1115153Y599780D01*
Y598390D01*
X1114543Y597780D01*
X1113933D01*
X1113413Y597260D01*
Y595890D01*
X1114003Y595300D01*
X1114953D01*
X1116053Y594200D01*
Y592612D01*
X1114341Y590900D01*
G01D02*
X1114340D01*
G01X1151152D02*
X1152864Y592612D01*
Y594200D01*
X1151764Y595300D01*
X1150814D01*
X1150224Y595890D01*
Y597260D01*
X1150744Y597780D01*
X1151354D01*
X1151964Y598390D01*
Y599780D01*
X1151354Y600390D01*
X1150774D01*
X1150224Y600940D01*
Y602360D01*
X1150864Y603000D01*
X1152144D01*
X1152883Y603739D01*
Y605645D01*
X1151178Y607350D01*
G01X1119440Y588514D02*
X1119286D01*
X1117735Y590065D01*
Y594901D01*
X1116906Y595730D01*
Y602270D01*
X1117735Y603099D01*
Y608236D01*
X1119248Y609749D01*
X1119440D01*
G01X1156252Y588514D02*
X1155964D01*
X1154546Y589932D01*
Y594901D01*
X1153717Y595730D01*
Y602270D01*
X1154546Y603099D01*
Y608043D01*
X1156252Y609749D01*
G01X1114340Y588300D02*
X1114053D01*
X1113826Y588526D01*
X1112353Y590000D01*
Y608012D01*
X1114340Y609999D01*
G01X1151152Y588300D02*
X1150864D01*
X1149164Y590000D01*
Y608011D01*
X1151152Y609999D01*
G01X1119440Y591114D02*
X1121153Y592827D01*
Y594500D01*
X1120476Y595176D01*
X1120153Y595500D01*
X1118637D01*
X1117966Y596171D01*
Y597448D01*
X1118418Y597900D01*
X1118753D01*
X1119453Y598600D01*
Y599688D01*
X1118743Y600398D01*
X1118506D01*
X1117966Y600938D01*
Y601829D01*
X1118737Y602600D01*
X1120253D01*
X1121253Y603600D01*
Y605328D01*
X1119441Y607140D01*
X1119440D01*
G01X1156252Y591114D02*
X1157964Y592826D01*
Y594500D01*
X1156964Y595500D01*
X1155448D01*
X1154777Y596171D01*
Y597448D01*
X1155229Y597900D01*
X1155564D01*
X1156264Y598600D01*
Y599688D01*
X1155554Y600398D01*
X1155317D01*
X1154777Y600938D01*
Y601829D01*
X1155548Y602600D01*
X1157064D01*
X1158064Y603600D01*
Y605328D01*
X1156252Y607140D01*
G01X1168110Y27899D02*
X1169357Y29146D01*
Y30400D01*
X1170657Y31700D01*
X1171657D01*
X1173457Y33500D01*
Y34900D01*
X1172845Y35512D01*
Y48525D01*
X1171456Y49914D01*
G01X1164763D02*
X1166152Y48525D01*
Y35512D01*
X1166764Y34900D01*
Y33500D01*
X1164964Y31700D01*
X1163964D01*
X1162664Y30400D01*
Y29146D01*
X1161417Y27899D01*
G01X1168110Y17157D02*
X1166989Y16036D01*
Y13100D01*
X1170331Y9758D01*
Y8700D01*
X1168531Y6900D01*
Y5325D01*
X1169731Y4125D01*
Y2999D01*
X1168531Y1799D01*
Y426D01*
X1169889Y-932D01*
Y-2133D01*
X1171456Y-3700D01*
G01Y12114D02*
X1172845Y10725D01*
Y-2288D01*
X1173457Y-2900D01*
Y-4300D01*
X1171657Y-6100D01*
X1170657D01*
X1169357Y-7400D01*
Y-8654D01*
X1168110Y-9901D01*
G01X1161417Y17157D02*
X1160489Y16229D01*
Y13101D01*
X1163531Y10059D01*
Y8674D01*
X1161856Y6999D01*
Y5876D01*
X1163356Y4376D01*
Y3024D01*
X1161856Y1524D01*
Y301D01*
X1163289Y-1132D01*
Y-2226D01*
X1164763Y-3700D01*
G01Y12114D02*
X1166152Y10725D01*
Y-2288D01*
X1166764Y-2900D01*
Y-4300D01*
X1164964Y-6100D01*
X1163964D01*
X1162664Y-7400D01*
Y-8654D01*
X1161417Y-9901D01*
G01X1181496Y17157D02*
X1180375Y16036D01*
Y13100D01*
X1183275Y10200D01*
Y8232D01*
X1181742Y6699D01*
Y5500D01*
X1182992Y4250D01*
Y3350D01*
X1181642Y2000D01*
Y701D01*
X1183275Y-932D01*
Y-3233D01*
X1184142Y-4100D01*
G01X1181496Y-9901D02*
Y-7779D01*
X1183375Y-5900D01*
X1184775D01*
X1186231Y-4444D01*
Y-3100D01*
X1185615Y-2484D01*
Y10641D01*
X1184142Y12114D01*
G01X1208267Y-3700D02*
X1206700Y-2133D01*
Y-932D01*
X1205342Y426D01*
Y1799D01*
X1206542Y2999D01*
Y4125D01*
X1205342Y5325D01*
Y6900D01*
X1207142Y8700D01*
Y9758D01*
X1203800Y13100D01*
Y16036D01*
X1204921Y17157D01*
G01Y-9901D02*
X1206168Y-8654D01*
Y-7400D01*
X1207468Y-6100D01*
X1208468D01*
X1210268Y-4300D01*
Y-2900D01*
X1209656Y-2288D01*
Y10725D01*
X1208267Y12114D01*
G01X1177763Y-4100D02*
X1176675Y-3012D01*
Y-1132D01*
X1175242Y301D01*
Y1500D01*
X1176742Y3000D01*
Y4200D01*
X1175292Y5650D01*
Y7049D01*
X1176675Y8432D01*
Y10301D01*
X1173875Y13101D01*
Y16229D01*
X1174803Y17157D01*
G01Y-9901D02*
Y-8347D01*
X1177050Y-6100D01*
X1178274D01*
X1179850Y-4524D01*
Y-2900D01*
X1179075Y-2125D01*
Y10888D01*
X1177849Y12114D01*
G01X1201574Y-3700D02*
X1200100Y-2226D01*
Y-1132D01*
X1198667Y301D01*
Y1524D01*
X1200167Y3024D01*
Y4376D01*
X1198667Y5876D01*
Y6999D01*
X1200342Y8674D01*
Y10059D01*
X1197300Y13101D01*
Y16229D01*
X1198228Y17157D01*
G01Y-9901D02*
X1199475Y-8654D01*
Y-7400D01*
X1200775Y-6100D01*
X1201775D01*
X1203575Y-4300D01*
Y-2900D01*
X1202963Y-2288D01*
Y10725D01*
X1201574Y12114D01*
G01X1218307Y17157D02*
X1217186Y16036D01*
Y13100D01*
X1220086Y10200D01*
Y8232D01*
X1218553Y6699D01*
Y5500D01*
X1219803Y4250D01*
Y3350D01*
X1218453Y2000D01*
Y701D01*
X1220086Y-932D01*
Y-3233D01*
X1220953Y-4100D01*
G01Y12114D02*
X1222426Y10641D01*
Y-2484D01*
X1223042Y-3100D01*
Y-4444D01*
X1221586Y-5900D01*
X1220186D01*
X1218307Y-7779D01*
Y-9901D01*
G01X1214574Y-4100D02*
X1213486Y-3012D01*
Y-1132D01*
X1212053Y301D01*
Y1500D01*
X1213553Y3000D01*
Y4200D01*
X1212103Y5650D01*
Y7049D01*
X1213486Y8432D01*
Y10301D01*
X1210686Y13101D01*
Y16229D01*
X1211614Y17157D01*
G01Y-9901D02*
Y-8347D01*
X1213861Y-6100D01*
X1215085D01*
X1216661Y-4524D01*
Y-2900D01*
X1215886Y-2125D01*
Y10888D01*
X1214660Y12114D01*
G01X1187989Y-7050D02*
X1188759Y-6280D01*
X1189741D01*
X1191069Y-4952D01*
Y11194D01*
X1187963Y14300D01*
G01X1193063Y-7260D02*
X1196255Y-4068D01*
Y11322D01*
X1193063Y14514D01*
G01X1187963Y-4401D02*
X1188782Y-5220D01*
X1189298D01*
X1190009Y-4509D01*
Y-1220D01*
X1188089Y700D01*
Y1700D01*
X1188689Y2300D01*
X1189189D01*
X1190009Y3120D01*
Y4080D01*
X1189289Y4800D01*
X1188577D01*
X1188075Y5302D01*
Y6634D01*
X1188691Y7250D01*
X1189039D01*
X1190009Y8220D01*
Y10753D01*
X1189062Y11700D01*
X1187963D01*
G01X1193063Y-4651D02*
X1194172D01*
X1195195Y-3628D01*
Y-1007D01*
X1194488Y-300D01*
X1193690D01*
X1193089Y301D01*
Y1499D01*
X1193690Y2100D01*
X1194388D01*
X1195195Y2907D01*
Y4280D01*
X1194475Y5000D01*
X1193975D01*
X1193275Y5700D01*
Y6700D01*
X1193975Y7400D01*
X1194489D01*
X1195195Y8106D01*
Y10881D01*
X1194161Y11915D01*
X1193063D01*
Y11914D01*
G01X1168110Y54957D02*
X1166989Y53836D01*
Y50900D01*
X1170331Y47558D01*
Y46500D01*
X1168531Y44700D01*
Y43125D01*
X1169731Y41925D01*
Y40799D01*
X1168531Y39599D01*
Y38226D01*
X1169889Y36868D01*
Y35667D01*
X1171456Y34100D01*
G01X1167925Y112357D02*
Y107075D01*
X1170094Y104906D01*
Y91874D01*
X1169594Y91374D01*
Y86374D01*
X1170194Y85774D01*
Y84100D01*
X1169400Y83306D01*
Y75500D01*
X1170194Y74706D01*
Y73395D01*
X1169394Y72595D01*
Y67259D01*
X1170074Y66579D01*
Y56921D01*
X1168110Y54957D01*
G01X1171456Y49914D02*
X1169500Y51870D01*
Y53570D01*
X1172728Y56798D01*
Y66313D01*
X1173294Y66879D01*
Y72707D01*
X1172694Y73307D01*
Y74994D01*
X1173300Y75600D01*
Y83594D01*
X1172694Y84200D01*
Y85794D01*
X1173394Y86494D01*
Y91154D01*
X1172694Y91854D01*
Y104991D01*
X1170721Y106964D01*
G01X1161632Y112357D02*
Y106969D01*
X1163694Y104907D01*
Y92174D01*
X1162594Y91074D01*
Y86774D01*
X1163294Y86074D01*
Y83900D01*
X1162600Y83206D01*
Y75600D01*
X1163294Y74906D01*
Y72995D01*
X1162594Y72295D01*
Y67139D01*
X1163394Y66339D01*
Y56934D01*
X1161417Y54957D01*
G01D02*
X1160489Y54029D01*
Y50901D01*
X1163531Y47859D01*
Y46474D01*
X1161856Y44799D01*
Y43676D01*
X1163356Y42176D01*
Y40824D01*
X1161856Y39324D01*
Y38101D01*
X1163289Y36668D01*
Y35574D01*
X1164763Y34100D01*
G01X1164428Y106964D02*
X1165900Y105492D01*
Y92006D01*
X1166894Y91012D01*
Y86674D01*
X1166294Y86074D01*
Y83900D01*
X1166700Y83494D01*
Y75300D01*
X1166294Y74894D01*
Y72659D01*
X1166794Y72159D01*
Y67059D01*
X1165594Y65859D01*
Y56264D01*
X1162924Y53594D01*
Y51753D01*
X1164763Y49914D01*
G01X1167510Y498487D02*
Y506611D01*
X1170052Y509153D01*
Y511157D01*
X1169552Y511657D01*
Y517057D01*
X1170352Y517857D01*
Y519200D01*
X1169800Y519752D01*
Y527800D01*
X1170352Y528352D01*
Y529497D01*
X1169252Y530597D01*
Y535342D01*
X1170152Y536242D01*
Y537700D01*
X1169800Y538052D01*
Y546200D01*
X1170152Y546552D01*
Y548707D01*
X1166752Y552107D01*
Y554599D01*
X1168110Y555957D01*
G01X1170656Y493844D02*
Y501456D01*
X1173200Y504000D01*
Y509000D01*
X1172852Y509348D01*
Y511657D01*
X1173452Y512257D01*
Y516807D01*
X1172902Y517357D01*
Y519300D01*
X1173100Y519498D01*
Y527800D01*
X1172902Y527998D01*
Y529847D01*
X1173752Y530697D01*
Y535348D01*
X1172752Y536348D01*
Y537600D01*
X1173100Y537948D01*
Y545900D01*
X1172752Y546248D01*
Y549670D01*
X1171456Y550966D01*
Y550914D01*
G01X1161417Y555957D02*
X1160752Y555292D01*
Y551457D01*
X1163652Y548557D01*
Y547152D01*
X1163100Y546600D01*
Y538152D01*
X1163652Y537600D01*
Y536442D01*
X1162379Y535169D01*
Y530670D01*
X1163452Y529597D01*
Y528152D01*
X1163100Y527800D01*
Y519852D01*
X1163452Y519500D01*
Y517557D01*
X1162852Y516957D01*
Y512057D01*
X1163652Y511257D01*
Y509552D01*
X1161874Y507774D01*
Y498944D01*
X1161417Y498487D01*
G01X1164763Y550914D02*
X1166109Y549568D01*
X1166152D01*
Y546448D01*
X1166400Y546200D01*
Y538048D01*
X1166152Y537800D01*
Y536247D01*
X1166818Y535581D01*
Y530363D01*
X1166252Y529797D01*
Y527948D01*
X1166500Y527700D01*
Y519748D01*
X1165952Y519200D01*
Y517657D01*
X1167052Y516557D01*
Y512157D01*
X1166152Y511257D01*
Y509248D01*
X1164474Y507570D01*
Y493855D01*
X1164363Y493744D01*
G01X1171456Y610700D02*
X1166405Y605649D01*
Y595462D01*
X1168110Y593757D01*
G01Y604499D02*
X1169182D01*
X1169882Y603799D01*
Y602525D01*
X1168745Y601388D01*
Y600312D01*
X1169757Y599300D01*
Y598100D01*
X1168745Y597088D01*
Y596012D01*
X1169857Y594900D01*
Y592267D01*
X1169682Y592092D01*
Y590400D01*
X1171368Y588714D01*
X1171456D01*
G01X1164763Y610700D02*
X1159712Y605649D01*
Y595462D01*
X1161417Y593757D01*
G01Y604499D02*
X1162489D01*
X1163189Y603799D01*
Y602525D01*
X1162052Y601388D01*
Y600312D01*
X1163064Y599300D01*
Y598100D01*
X1162052Y597088D01*
Y596012D01*
X1163164Y594900D01*
Y592267D01*
X1162989Y592092D01*
Y590400D01*
X1164675Y588714D01*
X1164763D01*
G01X1181496Y593757D02*
X1179791Y595462D01*
Y607115D01*
X1182976Y610300D01*
X1184142D01*
G01Y588714D02*
X1184054D01*
X1182368Y590400D01*
Y592092D01*
X1183275Y592999D01*
Y594592D01*
X1182131Y595736D01*
Y597156D01*
X1182975Y598000D01*
Y599700D01*
X1182131Y600544D01*
Y601756D01*
X1183075Y602700D01*
Y603900D01*
X1182476Y604499D01*
X1181496D01*
G01X1204921Y593757D02*
X1203216Y595462D01*
Y605649D01*
X1208267Y610700D01*
G01Y588714D02*
X1208179D01*
X1206493Y590400D01*
Y592092D01*
X1206668Y592267D01*
Y594900D01*
X1205556Y596012D01*
Y597088D01*
X1206568Y598100D01*
Y599300D01*
X1205556Y600312D01*
Y601388D01*
X1206693Y602525D01*
Y603799D01*
X1205993Y604499D01*
X1204921D01*
G01X1174803Y593757D02*
X1173098Y595462D01*
Y605435D01*
X1173720Y606057D01*
Y607245D01*
X1176775Y610300D01*
X1177763D01*
G01X1177849Y588714D02*
X1177761D01*
X1176075Y590400D01*
Y592600D01*
X1176575Y593100D01*
Y594999D01*
X1175438Y596136D01*
Y597464D01*
X1176375Y598401D01*
Y599799D01*
X1175438Y600736D01*
Y601964D01*
X1176475Y603001D01*
Y603899D01*
X1175875Y604499D01*
X1174803D01*
G01X1198228Y593757D02*
X1196523Y595462D01*
Y605649D01*
X1201574Y610700D01*
G01Y588714D02*
X1201486D01*
X1199800Y590400D01*
Y592092D01*
X1199975Y592267D01*
Y594900D01*
X1198863Y596012D01*
Y597088D01*
X1199875Y598100D01*
Y599300D01*
X1198863Y600312D01*
Y601388D01*
X1200000Y602525D01*
Y603799D01*
X1199300Y604499D01*
X1198228D01*
G01X1218307Y593757D02*
X1216602Y595462D01*
Y607115D01*
X1219787Y610300D01*
X1220953D01*
G01Y588714D02*
X1220865D01*
X1219179Y590400D01*
Y592092D01*
X1220086Y592999D01*
Y594592D01*
X1218942Y595736D01*
Y597156D01*
X1219786Y598000D01*
Y599700D01*
X1218942Y600544D01*
Y601756D01*
X1219886Y602700D01*
Y603900D01*
X1219287Y604499D01*
X1218307D01*
G01X1211614Y593757D02*
X1209909Y595462D01*
Y605435D01*
X1210531Y606057D01*
Y607245D01*
X1213586Y610300D01*
X1214574D01*
G01X1214660Y588714D02*
X1214572D01*
X1212886Y590400D01*
Y592600D01*
X1213386Y593100D01*
Y594999D01*
X1212249Y596136D01*
Y597464D01*
X1213186Y598401D01*
Y599799D01*
X1212249Y600736D01*
Y601964D01*
X1213286Y603001D01*
Y603899D01*
X1212686Y604499D01*
X1211614D01*
G01X1187963Y590900D02*
X1189675Y592612D01*
Y594200D01*
X1188575Y595300D01*
X1187625D01*
X1187035Y595890D01*
Y597260D01*
X1187555Y597780D01*
X1188165D01*
X1188775Y598390D01*
Y599780D01*
X1188165Y600390D01*
X1187585D01*
X1187035Y600940D01*
Y602360D01*
X1187675Y603000D01*
X1188955D01*
X1189694Y603739D01*
Y605645D01*
X1187989Y607350D01*
G01X1193063Y588514D02*
X1192775D01*
X1191358Y589931D01*
Y594900D01*
X1190528Y595730D01*
Y602270D01*
X1191358Y603100D01*
Y608044D01*
X1193063Y609749D01*
G01X1187963Y588300D02*
X1187675D01*
X1185975Y590000D01*
Y608011D01*
X1187963Y609999D01*
G01X1193063Y591114D02*
X1194775Y592826D01*
Y594500D01*
X1193775Y595500D01*
X1192259D01*
X1191588Y596171D01*
Y597448D01*
X1192040Y597900D01*
X1192375D01*
X1193075Y598600D01*
Y599688D01*
X1192365Y600398D01*
X1192128D01*
X1191588Y600938D01*
Y601829D01*
X1192359Y602600D01*
X1193875D01*
X1194875Y603600D01*
Y605328D01*
X1193063Y607140D01*
G01X1241732Y17157D02*
X1240611Y16036D01*
Y13100D01*
X1243953Y9758D01*
Y8700D01*
X1242153Y6900D01*
Y5325D01*
X1243353Y4125D01*
Y2999D01*
X1242153Y1799D01*
Y426D01*
X1243511Y-932D01*
Y-2133D01*
X1245078Y-3700D01*
G01Y12114D02*
X1246467Y10725D01*
Y-2288D01*
X1247079Y-2900D01*
Y-4300D01*
X1245279Y-6100D01*
X1244279D01*
X1242979Y-7400D01*
Y-8654D01*
X1241732Y-9901D01*
G01X1235039Y17157D02*
X1234111Y16229D01*
Y13101D01*
X1237153Y10059D01*
Y8674D01*
X1235478Y6999D01*
Y5876D01*
X1236978Y4376D01*
Y3024D01*
X1235478Y1524D01*
Y301D01*
X1236911Y-1132D01*
Y-2226D01*
X1238385Y-3700D01*
G01Y12114D02*
X1239774Y10725D01*
Y-2288D01*
X1240386Y-2900D01*
Y-4300D01*
X1238586Y-6100D01*
X1237586D01*
X1236286Y-7400D01*
Y-8654D01*
X1235039Y-9901D01*
G01X1224774Y14300D02*
X1227880Y11194D01*
Y-4952D01*
X1226552Y-6280D01*
X1225570D01*
X1224800Y-7050D01*
G01X1229874Y14514D02*
X1233066Y11322D01*
Y-4068D01*
X1229874Y-7260D01*
G01X1224774Y11700D02*
X1225873D01*
X1226820Y10753D01*
Y8220D01*
X1225850Y7250D01*
X1225502D01*
X1224886Y6634D01*
Y5302D01*
X1225388Y4800D01*
X1226100D01*
X1226820Y4080D01*
Y3120D01*
X1226000Y2300D01*
X1225500D01*
X1224900Y1700D01*
Y700D01*
X1226820Y-1220D01*
Y-4509D01*
X1226109Y-5220D01*
X1225593D01*
X1224774Y-4401D01*
G01X1229874Y11914D02*
Y11915D01*
X1230972D01*
X1232006Y10881D01*
Y8106D01*
X1231300Y7400D01*
X1230786D01*
X1230086Y6700D01*
Y5700D01*
X1230786Y5000D01*
X1231286D01*
X1232006Y4280D01*
Y2907D01*
X1231199Y2100D01*
X1230501D01*
X1229900Y1499D01*
Y301D01*
X1230501Y-300D01*
X1231299D01*
X1232006Y-1007D01*
Y-3628D01*
X1230983Y-4651D01*
X1229874D01*
G01X1241732Y593757D02*
X1240027Y595462D01*
Y605649D01*
X1245078Y610700D01*
G01Y588714D02*
X1244990D01*
X1243304Y590400D01*
Y592092D01*
X1243479Y592267D01*
Y594900D01*
X1242367Y596012D01*
Y597088D01*
X1243379Y598100D01*
Y599300D01*
X1242367Y600312D01*
Y601388D01*
X1243504Y602525D01*
Y603799D01*
X1242804Y604499D01*
X1241732D01*
G01X1235039Y593757D02*
X1233334Y595462D01*
Y605649D01*
X1238385Y610700D01*
G01Y588714D02*
X1238297D01*
X1236611Y590400D01*
Y592092D01*
X1236786Y592267D01*
Y594900D01*
X1235674Y596012D01*
Y597088D01*
X1236686Y598100D01*
Y599300D01*
X1235674Y600312D01*
Y601388D01*
X1236811Y602525D01*
Y603799D01*
X1236111Y604499D01*
X1235039D01*
G01X1224774Y590900D02*
X1226486Y592612D01*
Y594200D01*
X1225386Y595300D01*
X1224436D01*
X1223846Y595890D01*
Y597260D01*
X1224366Y597780D01*
X1224976D01*
X1225586Y598390D01*
Y599780D01*
X1224976Y600390D01*
X1224396D01*
X1223846Y600940D01*
Y602360D01*
X1224486Y603000D01*
X1225766D01*
X1226505Y603739D01*
Y605645D01*
X1224800Y607350D01*
G01X1229874Y588514D02*
X1229586D01*
X1228169Y589931D01*
Y594900D01*
X1227339Y595730D01*
Y602270D01*
X1228169Y603100D01*
Y608044D01*
X1229874Y609749D01*
G01X1224774Y588300D02*
X1224486D01*
X1222786Y590000D01*
Y608011D01*
X1224774Y609999D01*
G01X1229874Y591114D02*
X1231586Y592826D01*
Y594500D01*
X1230586Y595500D01*
X1229070D01*
X1228399Y596171D01*
Y597448D01*
X1228851Y597900D01*
X1229186D01*
X1229886Y598600D01*
Y599688D01*
X1229176Y600398D01*
X1228939D01*
X1228399Y600938D01*
Y601829D01*
X1229170Y602600D01*
X1230686D01*
X1231686Y603600D01*
Y605328D01*
X1229874Y607140D01*
G54D29*
G01X272774Y548657D02*
X270860Y550571D01*
Y555953D01*
X270864Y555957D01*
G01X268913Y549200D02*
X269260Y549547D01*
Y555203D01*
X268963Y555500D01*
G01X486433Y549641D02*
X486637Y549845D01*
Y554655D01*
X486483Y554809D01*
G01X488380Y551100D02*
Y555953D01*
X488384Y555957D01*
G01X918521Y549200D02*
X918868Y549547D01*
Y555203D01*
X918571Y555500D01*
G01X922382Y548657D02*
X920468Y550571D01*
Y555953D01*
X920472Y555957D01*
G01X1136041Y549641D02*
X1136245Y549845D01*
Y554655D01*
X1136091Y554809D01*
G01X1137992Y555957D02*
X1137988Y555953D01*
Y551100D01*
G01X1629489Y115491D02*
X1631043Y113937D01*
X1634063D01*
X1634500Y113500D01*
G54D39*
G01X1882999Y7383D02*
Y9010D01*
X1882485Y9524D01*
X1878794D01*
X1877359Y10959D01*
Y16379D01*
X1881417Y20437D01*
X1883606D01*
X1885723Y22554D01*
Y27526D01*
X1880999Y32250D01*
Y48438D01*
X1877214Y52223D01*
Y57114D01*
X1879007Y58907D01*
Y69448D01*
X1887022Y77463D01*
X1892149D01*
X1894442Y79756D01*
Y81794D01*
X1894072Y82164D01*
X1883654D01*
X1882285Y83533D01*
Y86600D01*
X1883251Y87566D01*
X1883324D01*
X1883675Y87917D01*
X1894279D01*
X1894681Y88319D01*
Y89989D01*
X1894251Y90419D01*
X1878226D01*
X1876887Y91758D01*
Y94782D01*
X1878226Y96121D01*
X1893936D01*
X1894338Y96523D01*
Y98106D01*
X1893821Y98623D01*
X1892494D01*
X1891112Y100005D01*
Y103029D01*
X1892408Y104325D01*
X1893900D01*
X1894496Y104921D01*
Y107304D01*
X1893979Y107821D01*
X1885992D01*
X1884610Y109203D01*
Y112227D01*
X1885906Y113523D01*
X1893228D01*
X1893824Y114119D01*
Y115702D01*
X1893307Y116219D01*
X1890093D01*
X1888683Y117629D01*
Y120653D01*
X1889951Y121921D01*
X1893194D01*
X1893766Y122493D01*
Y124072D01*
X1893221Y124617D01*
X1890478D01*
X1889096Y125999D01*
Y129023D01*
X1890392Y130319D01*
X1893651D01*
X1894222Y130890D01*
Y132426D01*
X1893633Y133015D01*
X1886210D01*
X1884844Y134381D01*
Y137450D01*
X1886108Y138714D01*
X1889876D01*
X1890369Y139207D01*
Y145312D01*
X1888639Y147042D01*
G01X1883041Y15814D02*
Y11534D01*
X1882682Y11175D01*
X1879478D01*
X1879010Y11643D01*
Y15695D01*
X1882101Y18786D01*
X1884290D01*
X1887374Y21870D01*
Y28210D01*
X1882650Y32934D01*
Y49122D01*
X1878865Y52907D01*
Y56430D01*
X1880658Y58223D01*
Y68764D01*
X1887706Y75812D01*
X1892833D01*
X1896093Y79072D01*
Y82478D01*
X1894756Y83815D01*
X1884338D01*
X1883936Y84217D01*
Y85915D01*
X1884008D01*
X1884359Y86266D01*
X1894963D01*
X1894992Y86295D01*
Y86339D01*
X1896281Y87628D01*
Y90652D01*
X1894914Y92019D01*
X1878889D01*
X1878487Y92421D01*
Y94119D01*
X1878838Y94470D01*
X1894620D01*
X1895938Y95788D01*
Y98769D01*
X1894484Y100223D01*
X1893157D01*
X1892712Y100668D01*
Y102323D01*
X1893114Y102725D01*
X1894559D01*
X1896096Y104262D01*
Y107967D01*
X1894642Y109421D01*
X1886655D01*
X1886210Y109866D01*
Y111492D01*
X1886590Y111872D01*
X1893912D01*
X1895424Y113384D01*
Y116365D01*
X1893970Y117819D01*
X1890756D01*
X1890283Y118292D01*
Y119919D01*
X1890685Y120321D01*
X1893857D01*
X1895366Y121830D01*
Y124735D01*
X1893884Y126217D01*
X1891141D01*
X1890696Y126662D01*
Y128317D01*
X1891098Y128719D01*
X1894310D01*
X1895819Y130228D01*
Y133088D01*
X1894241Y134666D01*
X1886894D01*
X1886495Y135065D01*
Y136766D01*
X1886792Y137063D01*
X1890560D01*
X1891966Y138469D01*
Y145368D01*
X1893640Y147042D01*
G01X1893094Y-12642D02*
Y-16779D01*
X1893594Y-17279D01*
X1895907D01*
X1896549Y-16637D01*
Y-10444D01*
X1892679Y-6574D01*
X1885980D01*
X1884612Y-5206D01*
Y-2182D01*
X1885922Y-872D01*
X1889905D01*
X1890667Y-110D01*
Y1180D01*
X1890106Y1741D01*
X1886930D01*
X1884911Y3760D01*
Y6221D01*
X1886715Y8025D01*
X1889765D01*
X1890084Y8344D01*
Y10002D01*
X1889685Y10401D01*
X1886893D01*
X1885527Y11767D01*
Y15129D01*
X1887033Y16635D01*
X1889786D01*
X1890138Y16987D01*
Y29530D01*
X1886448Y33220D01*
Y36385D01*
X1887814Y37751D01*
X1890187D01*
X1890586Y38150D01*
Y39251D01*
X1890187Y39650D01*
X1886342D01*
X1884976Y41016D01*
Y54931D01*
X1884577Y55330D01*
X1884200D01*
X1882834Y56696D01*
Y59165D01*
X1884200Y60531D01*
X1884577D01*
X1884976Y60930D01*
Y62031D01*
X1884577Y62430D01*
X1884200D01*
X1882834Y63796D01*
Y66265D01*
X1884200Y67631D01*
X1884577D01*
X1884976Y68030D01*
Y70056D01*
X1888507Y73587D01*
X1891283D01*
X1893222Y71648D01*
Y68050D01*
X1893462Y67810D01*
X1895274D01*
X1895674Y68210D01*
Y69848D01*
X1897144Y71318D01*
X1900990D01*
X1901799Y72127D01*
Y75328D01*
X1901400Y75727D01*
X1899604D01*
X1898237Y77094D01*
Y83563D01*
X1899772Y85098D01*
X1904189D01*
X1904588Y85497D01*
Y87149D01*
X1904188Y87549D01*
X1900119D01*
X1898897Y88771D01*
Y99309D01*
X1900140Y100552D01*
X1903621D01*
X1904025Y100956D01*
Y102656D01*
X1903621Y103060D01*
X1901520D01*
X1900126Y104454D01*
Y107480D01*
X1901911Y109265D01*
X1903673D01*
X1904189Y109781D01*
Y111365D01*
X1903787Y111767D01*
X1901915D01*
X1901650Y112032D01*
X1901575D01*
X1899859Y113748D01*
Y121939D01*
X1900649Y122729D01*
Y126167D01*
X1900249Y126567D01*
X1899375D01*
X1898009Y127933D01*
Y130402D01*
X1899375Y131768D01*
X1900250D01*
X1900649Y132167D01*
Y136188D01*
X1899823Y137014D01*
X1897823D01*
X1896457Y138380D01*
Y141622D01*
X1895957Y142122D01*
X1894855D01*
G01X1893081Y-20735D02*
Y-19376D01*
X1893527Y-18930D01*
X1896591D01*
X1898200Y-17321D01*
Y-9760D01*
X1894330Y-5890D01*
Y-5889D01*
X1893364Y-4923D01*
X1893363D01*
X1893362Y-4922D01*
X1891996D01*
X1891995Y-4923D01*
X1886664D01*
X1886263Y-4522D01*
Y-2866D01*
X1886606Y-2523D01*
X1890589D01*
X1892318Y-794D01*
Y1864D01*
X1890790Y3392D01*
X1887614D01*
X1886562Y4444D01*
Y5537D01*
X1887399Y6374D01*
X1890449D01*
X1891735Y7660D01*
Y10686D01*
X1890369Y12052D01*
X1887577D01*
X1887178Y12451D01*
Y14445D01*
X1887717Y14984D01*
X1890470D01*
X1891789Y16303D01*
Y30214D01*
X1888099Y33904D01*
Y35701D01*
X1888498Y36100D01*
X1890871D01*
X1892237Y37466D01*
Y39935D01*
X1890871Y41301D01*
X1887026D01*
X1886627Y41700D01*
Y55615D01*
X1885261Y56981D01*
X1884884D01*
X1884485Y57380D01*
Y58481D01*
X1884884Y58880D01*
X1885261D01*
X1886627Y60246D01*
Y62715D01*
X1885261Y64081D01*
X1884884D01*
X1884485Y64480D01*
Y65581D01*
X1884884Y65980D01*
X1885261D01*
X1886627Y67346D01*
Y69372D01*
X1889191Y71936D01*
X1890599D01*
X1891571Y70964D01*
Y67366D01*
X1892778Y66159D01*
X1895958D01*
X1897325Y67526D01*
Y69164D01*
X1897828Y69667D01*
X1901674D01*
X1903450Y71443D01*
Y76012D01*
X1902084Y77378D01*
X1900288D01*
X1899888Y77778D01*
Y82879D01*
X1900456Y83447D01*
X1904873D01*
X1906239Y84813D01*
Y87833D01*
X1904872Y89200D01*
X1900803D01*
X1900548Y89455D01*
Y89595D01*
X1900494Y89649D01*
Y98455D01*
X1900994Y98955D01*
X1904283D01*
X1905622Y100294D01*
Y103318D01*
X1904283Y104657D01*
X1902182D01*
X1901723Y105116D01*
Y106814D01*
X1902574Y107665D01*
X1904336D01*
X1905789Y109118D01*
Y112142D01*
X1904248Y113683D01*
X1902259D01*
X1901510Y114432D01*
Y121255D01*
X1902300Y122045D01*
Y126851D01*
X1900933Y128218D01*
X1900059D01*
X1899660Y128617D01*
Y129718D01*
X1900059Y130117D01*
X1900934D01*
X1902300Y131483D01*
Y136872D01*
X1900507Y138665D01*
X1898507D01*
X1898108Y139064D01*
Y141431D01*
X1898799Y142122D01*
X1899855D01*
M02*
